(kicad_pcb
	(version 20260206)
	(generator "pcbnew")
	(generator_version "10.0")
	(general
		(thickness 1.6)
		(legacy_teardrops no)
	)
	(paper "A4")
	(layers
		(0 "F.Cu" signal "TOP")
		(4 "In1.Cu" signal "GND")
		(6 "In2.Cu" signal "IN1")
		(8 "In3.Cu" signal "IN2")
		(10 "In4.Cu" signal "GND1")
		(2 "B.Cu" signal "BOTTOM")
		(9 "F.Adhes" user "F.Adhesive")
		(11 "B.Adhes" user "B.Adhesive")
		(13 "F.Paste" user "Package Geometry/Pastemask Top")
		(15 "B.Paste" user "Package Geometry/Pastemask Bottom")
		(5 "F.SilkS" user "Ref Des/Silkscreen Top")
		(7 "B.SilkS" user "Ref Des/Silkscreen Bottom")
		(1 "F.Mask" user "Board Geometry/Soldermask Top")
		(3 "B.Mask" user "Board Geometry/Soldermask Bottom")
		(17 "Dwgs.User" user "User.Drawings")
		(19 "Cmts.User" user "User.Comments")
		(21 "Eco1.User" user "User.Eco1")
		(23 "Eco2.User" user "User.Eco2")
		(25 "Edge.Cuts" user "Board Geometry/Outline")
		(27 "Margin" user)
		(31 "F.CrtYd" user "Package Geometry/Place Bound Top")
		(29 "B.CrtYd" user "Package Geometry/Place Bound Bottom")
		(35 "F.Fab" user "Ref Des/Assembly Top")
		(33 "B.Fab" user "Ref Des/Assembly Bottom")
	)
	(setup
		(pad_to_mask_clearance 0)
		(allow_soldermask_bridges_in_footprints no)
		(tenting
			(front yes)
			(back yes)
		)
		(covering
			(front no)
			(back no)
		)
		(plugging
			(front no)
			(back no)
		)
		(capping no)
		(filling no)
		(pcbplotparams
			(layerselection 0x00000000_00000000_55555555_5755f5ff)
			(plot_on_all_layers_selection 0x00000000_00000000_00000000_00000000)
			(disableapertmacros no)
			(usegerberextensions no)
			(usegerberattributes yes)
			(usegerberadvancedattributes yes)
			(creategerberjobfile yes)
			(dashed_line_dash_ratio 12)
			(dashed_line_gap_ratio 3)
			(svgprecision 4)
			(plotframeref no)
			(mode 1)
			(useauxorigin no)
			(pdf_front_fp_property_popups yes)
			(pdf_back_fp_property_popups yes)
			(pdf_metadata yes)
			(pdf_single_document no)
			(dxfpolygonmode yes)
			(dxfimperialunits yes)
			(dxfusepcbnewfont yes)
			(psnegative no)
			(psa4output no)
			(plot_black_and_white yes)
			(sketchpadsonfab no)
			(plotpadnumbers no)
			(hidednponfab no)
			(sketchdnponfab yes)
			(crossoutdnponfab yes)
			(subtractmaskfromsilk no)
			(outputformat 1)
			(mirror no)
			(drillshape 1)
			(scaleselection 1)
			(outputdirectory "")
		)
	)
	(footprint ""
		(layer "F.Cu")
		(at 24.638 -187.452 180)
		(property "Reference" "C2084"
			(at 0 0 180)
			(layer "F.SilkS")
			(hide yes)
			(effects
				(font
					(size 1.27 1.27)
				)
			)
		)
		(property "Value" ""
			(at 0 0 180)
			(layer "F.Fab")
			(effects
				(font
					(size 1.27 1.27)
				)
			)
		)
		(duplicate_pad_numbers_are_jumpers no)
		(fp_line
			(start 0.7874 0.4064)
			(end -0.7874 0.4064)
			(stroke
				(width 0.1524)
				(type default)
			)
			(layer "F.SilkS")
		)
		(fp_line
			(start 0.7874 -0.4064)
			(end 0.7874 0.4064)
			(stroke
				(width 0.1524)
				(type default)
			)
			(layer "F.SilkS")
		)
		(fp_line
			(start -0.7874 0.4064)
			(end -0.7874 -0.4064)
			(stroke
				(width 0.1524)
				(type default)
			)
			(layer "F.SilkS")
		)
		(fp_line
			(start -0.7874 -0.4064)
			(end 0.7874 -0.4064)
			(stroke
				(width 0.1524)
				(type default)
			)
			(layer "F.SilkS")
		)
		(fp_line
			(start 0.67945 0.3048)
			(end 0.120396 0.3048)
			(stroke
				(width 0.1)
				(type default)
			)
			(layer "F.Fab")
		)
		(fp_line
			(start 0.67945 -0.3048)
			(end 0.67945 0.3048)
			(stroke
				(width 0.1)
				(type default)
			)
			(layer "F.Fab")
		)
		(fp_line
			(start 0.12065 -0.2794)
			(end 0.12065 -0.3048)
			(stroke
				(width 0.1)
				(type default)
			)
			(layer "F.Fab")
		)
		(fp_line
			(start 0.12065 -0.3048)
			(end 0.67945 -0.3048)
			(stroke
				(width 0.1)
				(type default)
			)
			(layer "F.Fab")
		)
		(fp_line
			(start 0.120396 0.3048)
			(end 0.120396 0.2794)
			(stroke
				(width 0.1)
				(type default)
			)
			(layer "F.Fab")
		)
		(fp_line
			(start 0.120396 0.2794)
			(end -0.12065 0.2794)
			(stroke
				(width 0.1)
				(type default)
			)
			(layer "F.Fab")
		)
		(fp_line
			(start -0.12065 0.3048)
			(end -0.67945 0.3048)
			(stroke
				(width 0.1)
				(type default)
			)
			(layer "F.Fab")
		)
		(fp_line
			(start -0.12065 0.2794)
			(end -0.12065 0.3048)
			(stroke
				(width 0.1)
				(type default)
			)
			(layer "F.Fab")
		)
		(fp_line
			(start -0.12065 -0.2794)
			(end 0.12065 -0.2794)
			(stroke
				(width 0.1)
				(type default)
			)
			(layer "F.Fab")
		)
		(fp_line
			(start -0.12065 -0.305054)
			(end -0.12065 -0.2794)
			(stroke
				(width 0.1)
				(type default)
			)
			(layer "F.Fab")
		)
		(fp_line
			(start -0.67945 0.3048)
			(end -0.67945 -0.305054)
			(stroke
				(width 0.1)
				(type default)
			)
			(layer "F.Fab")
		)
		(fp_line
			(start -0.67945 -0.305054)
			(end -0.12065 -0.305054)
			(stroke
				(width 0.1)
				(type default)
			)
			(layer "F.Fab")
		)
		(pad "1" smd circle
			(at -0.40005 0 180)
			(size 0 0)
			(layers "F.Cu" "F.Mask" "F.Paste")
			(net "P52V_FAN_5_BUFF_EN_R")
		)
		(pad "2" smd circle
			(at 0.40005 0 180)
			(size 0 0)
			(layers "F.Cu" "F.Mask" "F.Paste")
			(net "GND")
		)
	)
	(footprint ""
		(layer "F.Cu")
		(at 23.241 -303.53 -90)
		(property "Reference" "R5511"
			(at 0 0 270)
			(layer "F.SilkS")
			(hide yes)
			(effects
				(font
					(size 1.27 1.27)
				)
			)
		)
		(property "Value" ""
			(at 0 0 270)
			(layer "F.Fab")
			(effects
				(font
					(size 1.27 1.27)
				)
			)
		)
		(duplicate_pad_numbers_are_jumpers no)
		(fp_line
			(start -0.7874 0.4064)
			(end -0.7874 -0.4064)
			(stroke
				(width 0.1524)
				(type default)
			)
			(layer "F.SilkS")
		)
		(fp_line
			(start 0.7874 0.4064)
			(end -0.7874 0.4064)
			(stroke
				(width 0.1524)
				(type default)
			)
			(layer "F.SilkS")
		)
		(fp_line
			(start -0.7874 -0.4064)
			(end 0.7874 -0.4064)
			(stroke
				(width 0.1524)
				(type default)
			)
			(layer "F.SilkS")
		)
		(fp_line
			(start 0.7874 -0.4064)
			(end 0.7874 0.4064)
			(stroke
				(width 0.1524)
				(type default)
			)
			(layer "F.SilkS")
		)
		(fp_line
			(start -0.67945 0.3048)
			(end -0.67945 -0.305054)
			(stroke
				(width 0.1)
				(type default)
			)
			(layer "F.Fab")
		)
		(fp_line
			(start -0.12065 0.3048)
			(end -0.67945 0.3048)
			(stroke
				(width 0.1)
				(type default)
			)
			(layer "F.Fab")
		)
		(fp_line
			(start 0.120396 0.3048)
			(end 0.120396 0.2794)
			(stroke
				(width 0.1)
				(type default)
			)
			(layer "F.Fab")
		)
		(fp_line
			(start 0.67945 0.3048)
			(end 0.120396 0.3048)
			(stroke
				(width 0.1)
				(type default)
			)
			(layer "F.Fab")
		)
		(fp_line
			(start -0.12065 0.2794)
			(end -0.12065 0.3048)
			(stroke
				(width 0.1)
				(type default)
			)
			(layer "F.Fab")
		)
		(fp_line
			(start 0.120396 0.2794)
			(end -0.12065 0.2794)
			(stroke
				(width 0.1)
				(type default)
			)
			(layer "F.Fab")
		)
		(fp_line
			(start -0.12065 -0.2794)
			(end 0.12065 -0.2794)
			(stroke
				(width 0.1)
				(type default)
			)
			(layer "F.Fab")
		)
		(fp_line
			(start 0.12065 -0.2794)
			(end 0.12065 -0.3048)
			(stroke
				(width 0.1)
				(type default)
			)
			(layer "F.Fab")
		)
		(fp_line
			(start 0.12065 -0.3048)
			(end 0.67945 -0.3048)
			(stroke
				(width 0.1)
				(type default)
			)
			(layer "F.Fab")
		)
		(fp_line
			(start 0.67945 -0.3048)
			(end 0.67945 0.3048)
			(stroke
				(width 0.1)
				(type default)
			)
			(layer "F.Fab")
		)
		(fp_line
			(start -0.67945 -0.305054)
			(end -0.12065 -0.305054)
			(stroke
				(width 0.1)
				(type default)
			)
			(layer "F.Fab")
		)
		(fp_line
			(start -0.12065 -0.305054)
			(end -0.12065 -0.2794)
			(stroke
				(width 0.1)
				(type default)
			)
			(layer "F.Fab")
		)
		(pad "1" smd circle
			(at -0.40005 0 270)
			(size 0 0)
			(layers "F.Cu" "F.Mask" "F.Paste")
			(net "P3V3_AUX")
		)
		(pad "2" smd circle
			(at 0.40005 0 270)
			(size 0 0)
			(layers "F.Cu" "F.Mask" "F.Paste")
			(net "FAN_0_PWM_BUF")
		)
	)
	(footprint ""
		(layer "F.Cu")
		(at 4.826 -135.255 -90)
		(property "Reference" "R5568"
			(at 0 0 270)
			(layer "F.SilkS")
			(hide yes)
			(effects
				(font
					(size 1.27 1.27)
				)
			)
		)
		(property "Value" ""
			(at 0 0 270)
			(layer "F.Fab")
			(effects
				(font
					(size 1.27 1.27)
				)
			)
		)
		(duplicate_pad_numbers_are_jumpers no)
		(fp_line
			(start -0.7874 0.4064)
			(end -0.7874 -0.4064)
			(stroke
				(width 0.1524)
				(type default)
			)
			(layer "F.SilkS")
		)
		(fp_line
			(start 0.7874 0.4064)
			(end -0.7874 0.4064)
			(stroke
				(width 0.1524)
				(type default)
			)
			(layer "F.SilkS")
		)
		(fp_line
			(start -0.7874 -0.4064)
			(end 0.7874 -0.4064)
			(stroke
				(width 0.1524)
				(type default)
			)
			(layer "F.SilkS")
		)
		(fp_line
			(start 0.7874 -0.4064)
			(end 0.7874 0.4064)
			(stroke
				(width 0.1524)
				(type default)
			)
			(layer "F.SilkS")
		)
		(fp_line
			(start -0.67945 0.3048)
			(end -0.67945 -0.305054)
			(stroke
				(width 0.1)
				(type default)
			)
			(layer "F.Fab")
		)
		(fp_line
			(start -0.12065 0.3048)
			(end -0.67945 0.3048)
			(stroke
				(width 0.1)
				(type default)
			)
			(layer "F.Fab")
		)
		(fp_line
			(start 0.120396 0.3048)
			(end 0.120396 0.2794)
			(stroke
				(width 0.1)
				(type default)
			)
			(layer "F.Fab")
		)
		(fp_line
			(start 0.67945 0.3048)
			(end 0.120396 0.3048)
			(stroke
				(width 0.1)
				(type default)
			)
			(layer "F.Fab")
		)
		(fp_line
			(start -0.12065 0.2794)
			(end -0.12065 0.3048)
			(stroke
				(width 0.1)
				(type default)
			)
			(layer "F.Fab")
		)
		(fp_line
			(start 0.120396 0.2794)
			(end -0.12065 0.2794)
			(stroke
				(width 0.1)
				(type default)
			)
			(layer "F.Fab")
		)
		(fp_line
			(start -0.12065 -0.2794)
			(end 0.12065 -0.2794)
			(stroke
				(width 0.1)
				(type default)
			)
			(layer "F.Fab")
		)
		(fp_line
			(start 0.12065 -0.2794)
			(end 0.12065 -0.3048)
			(stroke
				(width 0.1)
				(type default)
			)
			(layer "F.Fab")
		)
		(fp_line
			(start 0.12065 -0.3048)
			(end 0.67945 -0.3048)
			(stroke
				(width 0.1)
				(type default)
			)
			(layer "F.Fab")
		)
		(fp_line
			(start 0.67945 -0.3048)
			(end 0.67945 0.3048)
			(stroke
				(width 0.1)
				(type default)
			)
			(layer "F.Fab")
		)
		(fp_line
			(start -0.67945 -0.305054)
			(end -0.12065 -0.305054)
			(stroke
				(width 0.1)
				(type default)
			)
			(layer "F.Fab")
		)
		(fp_line
			(start -0.12065 -0.305054)
			(end -0.12065 -0.2794)
			(stroke
				(width 0.1)
				(type default)
			)
			(layer "F.Fab")
		)
		(pad "1" smd circle
			(at -0.40005 0 270)
			(size 0 0)
			(layers "F.Cu" "F.Mask" "F.Paste")
			(net "SMB_PDBV_FAN_SDA")
		)
		(pad "2" smd circle
			(at 0.40005 0 270)
			(size 0 0)
			(layers "F.Cu" "F.Mask" "F.Paste")
			(net "SMB_PDBV_FAN_R_U404_SDA")
		)
	)
	(footprint ""
		(layer "F.Cu")
		(at 49.492916 -36.304474 -90)
		(property "Reference" "C2049"
			(at 0 0 270)
			(layer "F.SilkS")
			(hide yes)
			(effects
				(font
					(size 1.27 1.27)
				)
			)
		)
		(property "Value" ""
			(at 0 0 270)
			(layer "F.Fab")
			(effects
				(font
					(size 1.27 1.27)
				)
			)
		)
		(duplicate_pad_numbers_are_jumpers no)
		(fp_line
			(start -0.7874 0.4064)
			(end -0.7874 -0.4064)
			(stroke
				(width 0.1524)
				(type default)
			)
			(layer "F.SilkS")
		)
		(fp_line
			(start 0.7874 0.4064)
			(end -0.7874 0.4064)
			(stroke
				(width 0.1524)
				(type default)
			)
			(layer "F.SilkS")
		)
		(fp_line
			(start -0.7874 -0.4064)
			(end 0.7874 -0.4064)
			(stroke
				(width 0.1524)
				(type default)
			)
			(layer "F.SilkS")
		)
		(fp_line
			(start 0.7874 -0.4064)
			(end 0.7874 0.4064)
			(stroke
				(width 0.1524)
				(type default)
			)
			(layer "F.SilkS")
		)
		(fp_line
			(start -0.6858 0.3048)
			(end -0.6858 -0.3048)
			(stroke
				(width 0.1)
				(type default)
			)
			(layer "F.Fab")
		)
		(fp_line
			(start -0.1016 0.3048)
			(end -0.6858 0.3048)
			(stroke
				(width 0.1)
				(type default)
			)
			(layer "F.Fab")
		)
		(fp_line
			(start 0.1016 0.3048)
			(end 0.1016 0.2794)
			(stroke
				(width 0.1)
				(type default)
			)
			(layer "F.Fab")
		)
		(fp_line
			(start 0.6858 0.3048)
			(end 0.1016 0.3048)
			(stroke
				(width 0.1)
				(type default)
			)
			(layer "F.Fab")
		)
		(fp_line
			(start -0.1016 0.2794)
			(end -0.1016 0.3048)
			(stroke
				(width 0.1)
				(type default)
			)
			(layer "F.Fab")
		)
		(fp_line
			(start 0.1016 0.2794)
			(end -0.1016 0.2794)
			(stroke
				(width 0.1)
				(type default)
			)
			(layer "F.Fab")
		)
		(fp_line
			(start -0.1016 -0.2794)
			(end 0.1016 -0.2794)
			(stroke
				(width 0.1)
				(type default)
			)
			(layer "F.Fab")
		)
		(fp_line
			(start 0.1016 -0.2794)
			(end 0.1016 -0.3048)
			(stroke
				(width 0.1)
				(type default)
			)
			(layer "F.Fab")
		)
		(fp_line
			(start -0.6858 -0.3048)
			(end -0.1016 -0.3048)
			(stroke
				(width 0.1)
				(type default)
			)
			(layer "F.Fab")
		)
		(fp_line
			(start -0.1016 -0.3048)
			(end -0.1016 -0.2794)
			(stroke
				(width 0.1)
				(type default)
			)
			(layer "F.Fab")
		)
		(fp_line
			(start 0.1016 -0.3048)
			(end 0.6858 -0.3048)
			(stroke
				(width 0.1)
				(type default)
			)
			(layer "F.Fab")
		)
		(fp_line
			(start 0.6858 -0.3048)
			(end 0.6858 0.3048)
			(stroke
				(width 0.1)
				(type default)
			)
			(layer "F.Fab")
		)
		(pad "1" smd rect
			(at -0.40005 0 90)
			(size 0.4572 0.508)
			(layers "F.Cu" "F.Mask" "F.Paste")
			(net "GND")
		)
		(pad "2" smd rect
			(at 0.40005 0 90)
			(size 0.4572 0.508)
			(layers "F.Cu" "F.Mask" "F.Paste")
			(net "P12V_LED_FAN3")
		)
	)
	(footprint ""
		(layer "F.Cu")
		(at 2.2606 -35.796474 -90)
		(property "Reference" "C2012"
			(at 0 0 270)
			(layer "F.SilkS")
			(hide yes)
			(effects
				(font
					(size 1.27 1.27)
				)
			)
		)
		(property "Value" ""
			(at 0 0 270)
			(layer "F.Fab")
			(effects
				(font
					(size 1.27 1.27)
				)
			)
		)
		(duplicate_pad_numbers_are_jumpers no)
		(fp_line
			(start -0.7874 0.4064)
			(end -0.7874 -0.4064)
			(stroke
				(width 0.1524)
				(type default)
			)
			(layer "F.SilkS")
		)
		(fp_line
			(start 0.7874 0.4064)
			(end -0.7874 0.4064)
			(stroke
				(width 0.1524)
				(type default)
			)
			(layer "F.SilkS")
		)
		(fp_line
			(start -0.7874 -0.4064)
			(end 0.7874 -0.4064)
			(stroke
				(width 0.1524)
				(type default)
			)
			(layer "F.SilkS")
		)
		(fp_line
			(start 0.7874 -0.4064)
			(end 0.7874 0.4064)
			(stroke
				(width 0.1524)
				(type default)
			)
			(layer "F.SilkS")
		)
		(fp_line
			(start -0.6858 0.3048)
			(end -0.6858 -0.3048)
			(stroke
				(width 0.1)
				(type default)
			)
			(layer "F.Fab")
		)
		(fp_line
			(start -0.1016 0.3048)
			(end -0.6858 0.3048)
			(stroke
				(width 0.1)
				(type default)
			)
			(layer "F.Fab")
		)
		(fp_line
			(start 0.1016 0.3048)
			(end 0.1016 0.2794)
			(stroke
				(width 0.1)
				(type default)
			)
			(layer "F.Fab")
		)
		(fp_line
			(start 0.6858 0.3048)
			(end 0.1016 0.3048)
			(stroke
				(width 0.1)
				(type default)
			)
			(layer "F.Fab")
		)
		(fp_line
			(start -0.1016 0.2794)
			(end -0.1016 0.3048)
			(stroke
				(width 0.1)
				(type default)
			)
			(layer "F.Fab")
		)
		(fp_line
			(start 0.1016 0.2794)
			(end -0.1016 0.2794)
			(stroke
				(width 0.1)
				(type default)
			)
			(layer "F.Fab")
		)
		(fp_line
			(start -0.1016 -0.2794)
			(end 0.1016 -0.2794)
			(stroke
				(width 0.1)
				(type default)
			)
			(layer "F.Fab")
		)
		(fp_line
			(start 0.1016 -0.2794)
			(end 0.1016 -0.3048)
			(stroke
				(width 0.1)
				(type default)
			)
			(layer "F.Fab")
		)
		(fp_line
			(start -0.6858 -0.3048)
			(end -0.1016 -0.3048)
			(stroke
				(width 0.1)
				(type default)
			)
			(layer "F.Fab")
		)
		(fp_line
			(start -0.1016 -0.3048)
			(end -0.1016 -0.2794)
			(stroke
				(width 0.1)
				(type default)
			)
			(layer "F.Fab")
		)
		(fp_line
			(start 0.1016 -0.3048)
			(end 0.6858 -0.3048)
			(stroke
				(width 0.1)
				(type default)
			)
			(layer "F.Fab")
		)
		(fp_line
			(start 0.6858 -0.3048)
			(end 0.6858 0.3048)
			(stroke
				(width 0.1)
				(type default)
			)
			(layer "F.Fab")
		)
		(pad "1" smd rect
			(at -0.40005 0 90)
			(size 0.4572 0.508)
			(layers "F.Cu" "F.Mask" "F.Paste")
			(net "GND")
		)
		(pad "2" smd rect
			(at 0.40005 0 90)
			(size 0.4572 0.508)
			(layers "F.Cu" "F.Mask" "F.Paste")
			(net "P12V_LED_FAN4")
		)
	)
	(footprint ""
		(layer "F.Cu")
		(at 22.479 -116.586 90)
		(property "Reference" "U64"
			(at 0.254 -1.87833 90)
			(unlocked yes)
			(layer "F.SilkS")
			(effects
				(font
					(size 0.7874 0.5842)
					(thickness 0.1524)
				)
				(justify left)
			)
		)
		(property "Value" ""
			(at 0 0 90)
			(layer "F.Fab")
			(effects
				(font
					(size 1.27 1.27)
				)
			)
		)
		(duplicate_pad_numbers_are_jumpers no)
		(fp_line
			(start 1.33096 -1.100074)
			(end 1.33096 1.100074)
			(stroke
				(width 0.1524)
				(type default)
			)
			(layer "F.SilkS")
		)
		(fp_line
			(start 0.381 -1.100074)
			(end 1.33096 -1.100074)
			(stroke
				(width 0.1524)
				(type default)
			)
			(layer "F.SilkS")
		)
		(fp_line
			(start -0.381 -1.100074)
			(end 0 -0.649986)
			(stroke
				(width 0.1524)
				(type default)
			)
			(layer "F.SilkS")
		)
		(fp_line
			(start -1.33096 -1.100074)
			(end -0.381 -1.100074)
			(stroke
				(width 0.1524)
				(type default)
			)
			(layer "F.SilkS")
		)
		(fp_line
			(start 0 -0.649986)
			(end 0.381 -1.100074)
			(stroke
				(width 0.1524)
				(type default)
			)
			(layer "F.SilkS")
		)
		(fp_line
			(start 1.33096 1.100074)
			(end -1.33096 1.100074)
			(stroke
				(width 0.1524)
				(type default)
			)
			(layer "F.SilkS")
		)
		(fp_line
			(start -1.33096 1.100074)
			(end -1.33096 -1.100074)
			(stroke
				(width 0.1524)
				(type default)
			)
			(layer "F.SilkS")
		)
		(fp_poly
			(pts
				(xy -1.77546 -1.967738) (xy -2.134616 -1.608582) (xy -1.41605 -1.249172)
			)
			(stroke
				(width 0)
				(type default)
			)
			(fill yes)
			(layer "F.SilkS")
		)
		(fp_line
			(start 0.674878 -1.100074)
			(end 0.674878 1.100074)
			(stroke
				(width 0.1)
				(type default)
			)
			(layer "F.Fab")
		)
		(fp_line
			(start -0.674878 -1.100074)
			(end 0.674878 -1.100074)
			(stroke
				(width 0.1)
				(type default)
			)
			(layer "F.Fab")
		)
		(fp_line
			(start 0.674878 1.100074)
			(end -0.674878 1.100074)
			(stroke
				(width 0.1)
				(type default)
			)
			(layer "F.Fab")
		)
		(fp_line
			(start -0.674878 1.100074)
			(end -0.674878 -1.100074)
			(stroke
				(width 0.1)
				(type default)
			)
			(layer "F.Fab")
		)
		(fp_poly
			(pts
				(xy -2.209292 -0.902462) (xy -2.209292 -0.394462) (xy -1.447292 -0.648462)
			)
			(stroke
				(width 0)
				(type default)
			)
			(fill yes)
			(layer "F.Fab")
		)
		(pad "1" smd rect
			(at -0.94996 -0.649986 180)
			(size 0.4064 0.508)
			(layers "F.Cu" "F.Mask" "F.Paste")
			(net "NC_U64_P1")
		)
		(pad "2" smd rect
			(at -0.94996 0 180)
			(size 0.4064 0.508)
			(layers "F.Cu" "F.Mask" "F.Paste")
			(net "FAN_2_PWM")
		)
		(pad "3" smd rect
			(at -0.94996 0.649986 180)
			(size 0.4064 0.508)
			(layers "F.Cu" "F.Mask" "F.Paste")
			(net "GND")
		)
		(pad "4" smd rect
			(at 0.94996 0.649986 180)
			(size 0.4064 0.508)
			(layers "F.Cu" "F.Mask" "F.Paste")
			(net "FAN_2_PWM_BUF")
		)
		(pad "5" smd rect
			(at 0.94996 -0.649986 180)
			(size 0.4064 0.508)
			(layers "F.Cu" "F.Mask" "F.Paste")
			(net "P3V3_AUX")
		)
	)
	(footprint ""
		(layer "F.Cu")
		(at 18.756122 -30.353 180)
		(property "Reference" "R5309"
			(at 0 0 180)
			(layer "F.SilkS")
			(hide yes)
			(effects
				(font
					(size 1.27 1.27)
				)
			)
		)
		(property "Value" ""
			(at 0 0 180)
			(layer "F.Fab")
			(effects
				(font
					(size 1.27 1.27)
				)
			)
		)
		(duplicate_pad_numbers_are_jumpers no)
		(fp_line
			(start 1.2954 0.5842)
			(end -1.2954 0.5842)
			(stroke
				(width 0.1524)
				(type default)
			)
			(layer "F.SilkS")
		)
		(fp_line
			(start 1.2954 -0.5842)
			(end 1.2954 0.5842)
			(stroke
				(width 0.1524)
				(type default)
			)
			(layer "F.SilkS")
		)
		(fp_line
			(start -1.2954 0.5842)
			(end -1.2954 -0.5842)
			(stroke
				(width 0.1524)
				(type default)
			)
			(layer "F.SilkS")
		)
		(fp_line
			(start -1.2954 -0.5842)
			(end 1.2954 -0.5842)
			(stroke
				(width 0.1524)
				(type default)
			)
			(layer "F.SilkS")
		)
		(fp_line
			(start 1.1938 0.4064)
			(end 0.8636 0.4064)
			(stroke
				(width 0.1)
				(type default)
			)
			(layer "F.Fab")
		)
		(fp_line
			(start 1.1938 -0.406654)
			(end 1.1938 0.4064)
			(stroke
				(width 0.1)
				(type default)
			)
			(layer "F.Fab")
		)
		(fp_line
			(start 0.8636 0.4572)
			(end -0.8636 0.4572)
			(stroke
				(width 0.1)
				(type default)
			)
			(layer "F.Fab")
		)
		(fp_line
			(start 0.8636 0.4064)
			(end 0.8636 0.4572)
			(stroke
				(width 0.1)
				(type default)
			)
			(layer "F.Fab")
		)
		(fp_line
			(start 0.8636 -0.406654)
			(end 1.1938 -0.406654)
			(stroke
				(width 0.1)
				(type default)
			)
			(layer "F.Fab")
		)
		(fp_line
			(start 0.8636 -0.4572)
			(end 0.8636 -0.406654)
			(stroke
				(width 0.1)
				(type default)
			)
			(layer "F.Fab")
		)
		(fp_line
			(start -0.8636 0.4572)
			(end -0.8636 0.4318)
			(stroke
				(width 0.1)
				(type default)
			)
			(layer "F.Fab")
		)
		(fp_line
			(start -0.8636 0.4318)
			(end -0.8636 0.4064)
			(stroke
				(width 0.1)
				(type default)
			)
			(layer "F.Fab")
		)
		(fp_line
			(start -0.8636 0.4064)
			(end -1.1938 0.4064)
			(stroke
				(width 0.1)
				(type default)
			)
			(layer "F.Fab")
		)
		(fp_line
			(start -0.8636 -0.406654)
			(end -0.8636 -0.4572)
			(stroke
				(width 0.1)
				(type default)
			)
			(layer "F.Fab")
		)
		(fp_line
			(start -0.8636 -0.4572)
			(end 0.8636 -0.4572)
			(stroke
				(width 0.1)
				(type default)
			)
			(layer "F.Fab")
		)
		(fp_line
			(start -1.1938 0.4064)
			(end -1.1938 -0.406654)
			(stroke
				(width 0.1)
				(type default)
			)
			(layer "F.Fab")
		)
		(fp_line
			(start -1.1938 -0.406654)
			(end -0.8636 -0.406654)
			(stroke
				(width 0.1)
				(type default)
			)
			(layer "F.Fab")
		)
		(pad "1" smd rect
			(at -0.7366 0 90)
			(size 0.7112 0.8128)
			(layers "F.Cu" "F.Mask" "F.Paste")
			(net "P52V_FAN_4")
		)
		(pad "2" smd rect
			(at 0.7366 0 90)
			(size 0.7112 0.8128)
			(layers "F.Cu" "F.Mask" "F.Paste")
			(net "FAN_4_TACH_OL_R")
		)
	)
	(footprint ""
		(layer "F.Cu")
		(at 21.727668 -264.724388)
		(property "Reference" "ME5"
			(at 0 0 0)
			(layer "F.SilkS")
			(hide yes)
			(effects
				(font
					(size 1.27 1.27)
				)
			)
		)
		(property "Value" ""
			(at 0 0 0)
			(layer "F.Fab")
			(effects
				(font
					(size 1.27 1.27)
				)
			)
		)
		(duplicate_pad_numbers_are_jumpers no)
		(fp_line
			(start -3.1369 2.5527)
			(end -3.1115 2.5019)
			(stroke
				(width 0.1524)
				(type default)
			)
			(layer "F.SilkS")
		)
		(fp_line
			(start -3.1369 3.0861)
			(end -2.8321 3.0861)
			(stroke
				(width 0.1524)
				(type default)
			)
			(layer "F.SilkS")
		)
		(fp_line
			(start -3.1242 2.9972)
			(end -3.1369 3.0861)
			(stroke
				(width 0.1524)
				(type default)
			)
			(layer "F.SilkS")
		)
		(fp_line
			(start -3.1115 2.5019)
			(end -3.0861 2.4765)
			(stroke
				(width 0.1524)
				(type default)
			)
			(layer "F.SilkS")
		)
		(fp_line
			(start -3.0988 2.921)
			(end -3.1242 2.9972)
			(stroke
				(width 0.1524)
				(type default)
			)
			(layer "F.SilkS")
		)
		(fp_line
			(start -3.0861 2.4765)
			(end -3.048 2.4511)
			(stroke
				(width 0.1524)
				(type default)
			)
			(layer "F.SilkS")
		)
		(fp_line
			(start -3.0734 2.8829)
			(end -3.0988 2.921)
			(stroke
				(width 0.1524)
				(type default)
			)
			(layer "F.SilkS")
		)
		(fp_line
			(start -3.048 2.4511)
			(end -2.9972 2.4384)
			(stroke
				(width 0.1524)
				(type default)
			)
			(layer "F.SilkS")
		)
		(fp_line
			(start -3.048 2.8575)
			(end -3.0734 2.8829)
			(stroke
				(width 0.1524)
				(type default)
			)
			(layer "F.SilkS")
		)
		(fp_line
			(start -3.0099 2.8067)
			(end -3.048 2.8575)
			(stroke
				(width 0.1524)
				(type default)
			)
			(layer "F.SilkS")
		)
		(fp_line
			(start -2.9972 2.4384)
			(end -2.9337 2.4511)
			(stroke
				(width 0.1524)
				(type default)
			)
			(layer "F.SilkS")
		)
		(fp_line
			(start -2.9591 2.7686)
			(end -3.0099 2.8067)
			(stroke
				(width 0.1524)
				(type default)
			)
			(layer "F.SilkS")
		)
		(fp_line
			(start -2.9337 2.4511)
			(end -2.8702 2.5146)
			(stroke
				(width 0.1524)
				(type default)
			)
			(layer "F.SilkS")
		)
		(fp_line
			(start -2.921 2.7432)
			(end -2.9591 2.7686)
			(stroke
				(width 0.1524)
				(type default)
			)
			(layer "F.SilkS")
		)
		(fp_line
			(start -2.8956 2.7178)
			(end -2.921 2.7432)
			(stroke
				(width 0.1524)
				(type default)
			)
			(layer "F.SilkS")
		)
		(fp_line
			(start -2.8702 2.5146)
			(end -2.8575 2.5527)
			(stroke
				(width 0.1524)
				(type default)
			)
			(layer "F.SilkS")
		)
		(fp_line
			(start -2.8702 2.6797)
			(end -2.8956 2.7178)
			(stroke
				(width 0.1524)
				(type default)
			)
			(layer "F.SilkS")
		)
		(fp_line
			(start -2.8575 2.5527)
			(end -2.8575 2.6416)
			(stroke
				(width 0.1524)
				(type default)
			)
			(layer "F.SilkS")
		)
		(fp_line
			(start -2.8575 2.6416)
			(end -2.8702 2.6797)
			(stroke
				(width 0.1524)
				(type default)
			)
			(layer "F.SilkS")
		)
		(fp_line
			(start -2.5908 2.6543)
			(end -2.5908 3.0861)
			(stroke
				(width 0.1524)
				(type default)
			)
			(layer "F.SilkS")
		)
		(fp_line
			(start -2.5908 2.7813)
			(end -2.5654 2.7305)
			(stroke
				(width 0.1524)
				(type default)
			)
			(layer "F.SilkS")
		)
		(fp_line
			(start -2.5654 2.7305)
			(end -2.54 2.6924)
			(stroke
				(width 0.1524)
				(type default)
			)
			(layer "F.SilkS")
		)
		(fp_line
			(start -2.54 2.6924)
			(end -2.5146 2.667)
			(stroke
				(width 0.1524)
				(type default)
			)
			(layer "F.SilkS")
		)
		(fp_line
			(start -2.5146 2.667)
			(end -2.4638 2.6543)
			(stroke
				(width 0.1524)
				(type default)
			)
			(layer "F.SilkS")
		)
		(fp_line
			(start -2.4638 2.6543)
			(end -2.4257 2.6543)
			(stroke
				(width 0.1524)
				(type default)
			)
			(layer "F.SilkS")
		)
		(fp_line
			(start -2.4257 2.6543)
			(end -2.3749 2.667)
			(stroke
				(width 0.1524)
				(type default)
			)
			(layer "F.SilkS")
		)
		(fp_line
			(start -2.3749 2.667)
			(end -2.3368 2.7178)
			(stroke
				(width 0.1524)
				(type default)
			)
			(layer "F.SilkS")
		)
		(fp_line
			(start -2.3368 2.7178)
			(end -2.3114 2.7686)
			(stroke
				(width 0.1524)
				(type default)
			)
			(layer "F.SilkS")
		)
		(fp_line
			(start -2.3114 2.7686)
			(end -2.3114 3.0861)
			(stroke
				(width 0.1524)
				(type default)
			)
			(layer "F.SilkS")
		)
		(fp_line
			(start -2.0701 2.8575)
			(end -2.0701 2.9083)
			(stroke
				(width 0.1524)
				(type default)
			)
			(layer "F.SilkS")
		)
		(fp_line
			(start -2.0701 2.9083)
			(end -2.0574 2.9718)
			(stroke
				(width 0.1524)
				(type default)
			)
			(layer "F.SilkS")
		)
		(fp_line
			(start -2.0574 2.8194)
			(end -2.0701 2.8575)
			(stroke
				(width 0.1524)
				(type default)
			)
			(layer "F.SilkS")
		)
		(fp_line
			(start -2.0574 2.9718)
			(end -2.032 3.0099)
			(stroke
				(width 0.1524)
				(type default)
			)
			(layer "F.SilkS")
		)
		(fp_line
			(start -2.0447 2.794)
			(end -2.0574 2.8194)
			(stroke
				(width 0.1524)
				(type default)
			)
			(layer "F.SilkS")
		)
		(fp_line
			(start -2.032 3.0099)
			(end -2.0066 3.0353)
			(stroke
				(width 0.1524)
				(type default)
			)
			(layer "F.SilkS")
		)
		(fp_line
			(start -2.0066 2.7559)
			(end -2.0447 2.794)
			(stroke
				(width 0.1524)
				(type default)
			)
			(layer "F.SilkS")
		)
		(fp_line
			(start -2.0066 3.0353)
			(end -1.9685 3.0607)
			(stroke
				(width 0.1524)
				(type default)
			)
			(layer "F.SilkS")
		)
		(fp_line
			(start -1.9685 2.7305)
			(end -2.0066 2.7559)
			(stroke
				(width 0.1524)
				(type default)
			)
			(layer "F.SilkS")
		)
		(fp_line
			(start -1.9685 3.0607)
			(end -1.9304 3.0734)
			(stroke
				(width 0.1524)
				(type default)
			)
			(layer "F.SilkS")
		)
		(fp_line
			(start -1.9304 3.0734)
			(end -1.8796 3.0734)
			(stroke
				(width 0.1524)
				(type default)
			)
			(layer "F.SilkS")
		)
		(fp_line
			(start -1.9177 2.7178)
			(end -1.9685 2.7305)
			(stroke
				(width 0.1524)
				(type default)
			)
			(layer "F.SilkS")
		)
		(fp_line
			(start -1.8796 3.0734)
			(end -1.8161 3.0607)
			(stroke
				(width 0.1524)
				(type default)
			)
			(layer "F.SilkS")
		)
		(fp_line
			(start -1.8542 2.7178)
			(end -1.9177 2.7178)
			(stroke
				(width 0.1524)
				(type default)
			)
			(layer "F.SilkS")
		)
		(fp_line
			(start -1.8161 2.7305)
			(end -1.8542 2.7178)
			(stroke
				(width 0.1524)
				(type default)
			)
			(layer "F.SilkS")
		)
		(fp_line
			(start -1.8161 3.0607)
			(end -1.778 3.0353)
			(stroke
				(width 0.1524)
				(type default)
			)
			(layer "F.SilkS")
		)
		(fp_line
			(start -1.778 2.7559)
			(end -1.8161 2.7305)
			(stroke
				(width 0.1524)
				(type default)
			)
			(layer "F.SilkS")
		)
		(fp_line
			(start -1.778 3.0353)
			(end -1.7526 3.0099)
			(stroke
				(width 0.1524)
				(type default)
			)
			(layer "F.SilkS")
		)
		(fp_line
			(start -1.7526 2.4384)
			(end -1.7526 3.0861)
			(stroke
				(width 0.1524)
				(type default)
			)
			(layer "F.SilkS")
		)
		(fp_line
			(start -1.7526 2.7813)
			(end -1.778 2.7559)
			(stroke
				(width 0.1524)
				(type default)
			)
			(layer "F.SilkS")
		)
		(fp_line
			(start -1.3208 -1.524)
			(end 1.4732 1.397)
			(stroke
				(width 0.1524)
				(type default)
			)
			(layer "F.SilkS")
		)
		(fp_line
			(start -1.1938 -1.27)
			(end -1.1938 1.2954)
			(stroke
				(width 0.254)
				(type default)
			)
			(layer "F.SilkS")
		)
		(fp_line
			(start -1.1938 -1.27)
			(end -0.5588 -1.27)
			(stroke
				(width 0.254)
				(type default)
			)
			(layer "F.SilkS")
		)
		(fp_line
			(start -1.1557 2.4257)
			(end -1.1557 3.0861)
			(stroke
				(width 0.1524)
				(type default)
			)
			(layer "F.SilkS")
		)
		(fp_line
			(start -1.016 4.7498)
			(end -1.016 4.826)
			(stroke
				(width 0.254)
				(type default)
			)
			(layer "F.SilkS")
		)
		(fp_line
			(start -1.016 4.7752)
			(end 0.3048 4.7752)
			(stroke
				(width 0.254)
				(type default)
			)
			(layer "F.SilkS")
		)
		(fp_line
			(start -1.016 4.826)
			(end -0.9906 4.953)
			(stroke
				(width 0.254)
				(type default)
			)
			(layer "F.SilkS")
		)
		(fp_line
			(start -0.9906 4.5974)
			(end -1.016 4.7498)
			(stroke
				(width 0.254)
				(type default)
			)
			(layer "F.SilkS")
		)
		(fp_line
			(start -0.9906 4.953)
			(end -0.9652 5.0292)
			(stroke
				(width 0.254)
				(type default)
			)
			(layer "F.SilkS")
		)
		(fp_line
			(start -0.9652 4.5212)
			(end -0.9906 4.5974)
			(stroke
				(width 0.254)
				(type default)
			)
			(layer "F.SilkS")
		)
		(fp_line
			(start -0.9652 5.0292)
			(end -0.9144 5.1308)
			(stroke
				(width 0.254)
				(type default)
			)
			(layer "F.SilkS")
		)
		(fp_line
			(start -0.9144 4.4196)
			(end -0.9652 4.5212)
			(stroke
				(width 0.254)
				(type default)
			)
			(layer "F.SilkS")
		)
		(fp_line
			(start -0.9144 5.1308)
			(end -0.8382 5.2324)
			(stroke
				(width 0.254)
				(type default)
			)
			(layer "F.SilkS")
		)
		(fp_line
			(start -0.8382 4.318)
			(end -0.9144 4.4196)
			(stroke
				(width 0.254)
				(type default)
			)
			(layer "F.SilkS")
		)
		(fp_line
			(start -0.8382 5.2324)
			(end -0.7112 5.334)
			(stroke
				(width 0.254)
				(type default)
			)
			(layer "F.SilkS")
		)
		(fp_line
			(start -0.8128 4.2926)
			(end -0.8382 4.318)
			(stroke
				(width 0.254)
				(type default)
			)
			(layer "F.SilkS")
		)
		(fp_line
			(start -0.7747 2.6543)
			(end -0.5969 3.0861)
			(stroke
				(width 0.1524)
				(type default)
			)
			(layer "F.SilkS")
		)
		(fp_line
			(start -0.7112 4.2164)
			(end -0.8128 4.2926)
			(stroke
				(width 0.254)
				(type default)
			)
			(layer "F.SilkS")
		)
		(fp_line
			(start -0.7112 5.334)
			(end -0.6096 5.3848)
			(stroke
				(width 0.254)
				(type default)
			)
			(layer "F.SilkS")
		)
		(fp_line
			(start -0.6096 4.1656)
			(end -0.7112 4.2164)
			(stroke
				(width 0.254)
				(type default)
			)
			(layer "F.SilkS")
		)
		(fp_line
			(start -0.6096 5.3848)
			(end -0.5334 5.4102)
			(stroke
				(width 0.254)
				(type default)
			)
			(layer "F.SilkS")
		)
		(fp_line
			(start -0.5969 3.0861)
			(end -0.4191 2.6543)
			(stroke
				(width 0.1524)
				(type default)
			)
			(layer "F.SilkS")
		)
		(fp_line
			(start -0.5588 0)
			(end -1.1938 0)
			(stroke
				(width 0.254)
				(type default)
			)
			(layer "F.SilkS")
		)
		(fp_line
			(start -0.5334 4.1402)
			(end -0.6096 4.1656)
			(stroke
				(width 0.254)
				(type default)
			)
			(layer "F.SilkS")
		)
		(fp_line
			(start -0.5334 5.4102)
			(end -0.381 5.4356)
			(stroke
				(width 0.254)
				(type default)
			)
			(layer "F.SilkS")
		)
		(fp_line
			(start -0.4064 4.1148)
			(end -0.5334 4.1402)
			(stroke
				(width 0.254)
				(type default)
			)
			(layer "F.SilkS")
		)
		(fp_line
			(start -0.381 5.4356)
			(end -0.3556 5.4356)
			(stroke
				(width 0.254)
				(type default)
			)
			(layer "F.SilkS")
		)
		(fp_line
			(start -0.3556 5.4356)
			(end -0.1778 5.4102)
			(stroke
				(width 0.254)
				(type default)
			)
			(layer "F.SilkS")
		)
		(fp_line
			(start -0.3048 4.1148)
			(end -0.4064 4.1148)
			(stroke
				(width 0.254)
				(type default)
			)
			(layer "F.SilkS")
		)
		(fp_line
			(start -0.1778 4.1402)
			(end -0.3048 4.1148)
			(stroke
				(width 0.254)
				(type default)
			)
			(layer "F.SilkS")
		)
		(fp_line
			(start -0.1778 5.4102)
			(end -0.1016 5.3848)
			(stroke
				(width 0.254)
				(type default)
			)
			(layer "F.SilkS")
		)
		(fp_line
			(start -0.1016 4.1656)
			(end -0.1778 4.1402)
			(stroke
				(width 0.254)
				(type default)
			)
			(layer "F.SilkS")
		)
		(fp_line
			(start -0.1016 5.3848)
			(end -0.0508 5.3594)
			(stroke
				(width 0.254)
				(type default)
			)
			(layer "F.SilkS")
		)
		(fp_line
			(start -0.0508 5.3594)
			(end 0.1016 5.2578)
			(stroke
				(width 0.254)
				(type default)
			)
			(layer "F.SilkS")
		)
		(fp_line
			(start -0.0381 2.4257)
			(end -0.0381 3.0861)
			(stroke
				(width 0.1524)
				(type default)
			)
			(layer "F.SilkS")
		)
		(fp_line
			(start 0 4.2164)
			(end -0.1016 4.1656)
			(stroke
				(width 0.254)
				(type default)
			)
			(layer "F.SilkS")
		)
		(fp_line
			(start 0.1016 5.2578)
			(end 0.2032 5.1308)
			(stroke
				(width 0.254)
				(type default)
			)
			(layer "F.SilkS")
		)
		(fp_line
			(start 0.127 4.318)
			(end 0 4.2164)
			(stroke
				(width 0.254)
				(type default)
			)
			(layer "F.SilkS")
		)
		(fp_line
			(start 0.2032 4.4196)
			(end 0.127 4.318)
			(stroke
				(width 0.254)
				(type default)
			)
			(layer "F.SilkS")
		)
		(fp_line
			(start 0.254 4.5212)
			(end 0.2032 4.4196)
			(stroke
				(width 0.254)
				(type default)
			)
			(layer "F.SilkS")
		)
		(fp_line
			(start 0.2794 4.5974)
			(end 0.254 4.5212)
			(stroke
				(width 0.254)
				(type default)
			)
			(layer "F.SilkS")
		)
		(fp_line
			(start 0.3048 4.7752)
			(end 0.2794 4.5974)
			(stroke
				(width 0.254)
				(type default)
			)
			(layer "F.SilkS")
		)
		(fp_line
			(start 0.3556 -1.27)
			(end 0.3556 1.2954)
			(stroke
				(width 0.254)
				(type default)
			)
			(layer "F.SilkS")
		)
		(fp_line
			(start 0.635 4.3434)
			(end 0.9144 4.191)
			(stroke
				(width 0.254)
				(type default)
			)
			(layer "F.SilkS")
		)
		(fp_line
			(start 0.6731 2.3495)
			(end 0.6731 2.3749)
			(stroke
				(width 0.1524)
				(type default)
			)
			(layer "F.SilkS")
		)
		(fp_line
			(start 0.6731 2.3749)
			(end 0.6985 2.4003)
			(stroke
				(width 0.1524)
				(type default)
			)
			(layer "F.SilkS")
		)
		(fp_line
			(start 0.6985 2.3241)
			(end 0.6731 2.3495)
			(stroke
				(width 0.1524)
				(type default)
			)
			(layer "F.SilkS")
		)
		(fp_line
			(start 0.6985 2.4003)
			(end 0.7239 2.3749)
			(stroke
				(width 0.1524)
				(type default)
			)
			(layer "F.SilkS")
		)
		(fp_line
			(start 0.6985 2.6416)
			(end 0.6985 3.0861)
			(stroke
				(width 0.1524)
				(type default)
			)
			(layer "F.SilkS")
		)
		(fp_line
			(start 0.7239 2.3495)
			(end 0.6985 2.3241)
			(stroke
				(width 0.1524)
				(type default)
			)
			(layer "F.SilkS")
		)
		(fp_line
			(start 0.7239 2.3749)
			(end 0.7239 2.3495)
			(stroke
				(width 0.1524)
				(type default)
			)
			(layer "F.SilkS")
		)
		(fp_line
			(start 0.9144 4.191)
			(end 0.9144 5.461)
			(stroke
				(width 0.254)
				(type default)
			)
			(layer "F.SilkS")
		)
		(fp_line
			(start 1.143 2.6543)
			(end 1.143 3.0861)
			(stroke
				(width 0.1524)
				(type default)
			)
			(layer "F.SilkS")
		)
		(fp_line
			(start 1.143 2.7813)
			(end 1.1684 2.7305)
			(stroke
				(width 0.1524)
				(type default)
			)
			(layer "F.SilkS")
		)
		(fp_line
			(start 1.1684 2.7305)
			(end 1.1938 2.6924)
			(stroke
				(width 0.1524)
				(type default)
			)
			(layer "F.SilkS")
		)
		(fp_line
			(start 1.1938 2.6924)
			(end 1.2192 2.667)
			(stroke
				(width 0.1524)
				(type default)
			)
			(layer "F.SilkS")
		)
		(fp_line
			(start 1.2192 2.667)
			(end 1.27 2.6543)
			(stroke
				(width 0.1524)
				(type default)
			)
			(layer "F.SilkS")
		)
		(fp_line
			(start 1.27 2.6543)
			(end 1.3081 2.6543)
			(stroke
				(width 0.1524)
				(type default)
			)
			(layer "F.SilkS")
		)
		(fp_line
			(start 1.3081 2.6543)
			(end 1.3589 2.667)
			(stroke
				(width 0.1524)
				(type default)
			)
			(layer "F.SilkS")
		)
		(fp_line
			(start 1.3589 2.667)
			(end 1.397 2.7178)
			(stroke
				(width 0.1524)
				(type default)
			)
			(layer "F.SilkS")
		)
		(fp_line
			(start 1.397 2.7178)
			(end 1.4224 2.7686)
			(stroke
				(width 0.1524)
				(type default)
			)
			(layer "F.SilkS")
		)
		(fp_line
			(start 1.4224 2.7686)
			(end 1.4224 3.0861)
			(stroke
				(width 0.1524)
				(type default)
			)
			(layer "F.SilkS")
		)
		(fp_line
			(start 1.7018 2.667)
			(end 1.9304 2.667)
			(stroke
				(width 0.1524)
				(type default)
			)
			(layer "F.SilkS")
		)
		(fp_line
			(start 1.8161 2.4511)
			(end 1.8161 3.0861)
			(stroke
				(width 0.1524)
				(type default)
			)
			(layer "F.SilkS")
		)
		(fp_line
			(start 1.8161 3.0861)
			(end 1.9939 3.0734)
			(stroke
				(width 0.1524)
				(type default)
			)
			(layer "F.SilkS")
		)
		(fp_line
			(start 2.1844 2.8575)
			(end 2.1844 2.8956)
			(stroke
				(width 0.1524)
				(type default)
			)
			(layer "F.SilkS")
		)
		(fp_line
			(start 2.1844 2.8956)
			(end 2.1971 2.9464)
			(stroke
				(width 0.1524)
				(type default)
			)
			(layer "F.SilkS")
		)
		(fp_line
			(start 2.1971 2.794)
			(end 2.1844 2.8575)
			(stroke
				(width 0.1524)
				(type default)
			)
			(layer "F.SilkS")
		)
		(fp_line
			(start 2.1971 2.9464)
			(end 2.2098 2.9718)
			(stroke
				(width 0.1524)
				(type default)
			)
			(layer "F.SilkS")
		)
		(fp_line
			(start 2.2098 2.7686)
			(end 2.1971 2.794)
			(stroke
				(width 0.1524)
				(type default)
			)
			(layer "F.SilkS")
		)
		(fp_line
			(start 2.2098 2.9718)
			(end 2.2352 3.0099)
			(stroke
				(width 0.1524)
				(type default)
			)
			(layer "F.SilkS")
		)
		(fp_line
			(start 2.2352 2.7305)
			(end 2.2098 2.7686)
			(stroke
				(width 0.1524)
				(type default)
			)
			(layer "F.SilkS")
		)
		(fp_line
			(start 2.2352 3.0099)
			(end 2.2606 3.0353)
			(stroke
				(width 0.1524)
				(type default)
			)
			(layer "F.SilkS")
		)
		(fp_line
			(start 2.2606 2.7051)
			(end 2.2352 2.7305)
			(stroke
				(width 0.1524)
				(type default)
			)
			(layer "F.SilkS")
		)
		(fp_line
			(start 2.2606 3.0353)
			(end 2.2987 3.0607)
			(stroke
				(width 0.1524)
				(type default)
			)
			(layer "F.SilkS")
		)
		(fp_line
			(start 2.2987 2.6797)
			(end 2.2606 2.7051)
			(stroke
				(width 0.1524)
				(type default)
			)
			(layer "F.SilkS")
		)
		(fp_line
			(start 2.2987 3.0607)
			(end 2.3241 3.0734)
			(stroke
				(width 0.1524)
				(type default)
			)
			(layer "F.SilkS")
		)
		(fp_line
			(start 2.3241 2.667)
			(end 2.2987 2.6797)
			(stroke
				(width 0.1524)
				(type default)
			)
			(layer "F.SilkS")
		)
		(fp_line
			(start 2.3241 3.0734)
			(end 2.3876 3.0861)
			(stroke
				(width 0.1524)
				(type default)
			)
			(layer "F.SilkS")
		)
		(fp_line
			(start 2.3749 2.6543)
			(end 2.3241 2.667)
			(stroke
				(width 0.1524)
				(type default)
			)
			(layer "F.SilkS")
		)
		(fp_line
			(start 2.3876 3.0861)
			(end 2.4384 3.0861)
			(stroke
				(width 0.1524)
				(type default)
			)
			(layer "F.SilkS")
		)
		(fp_line
			(start 2.413 2.6543)
			(end 2.3749 2.6543)
			(stroke
				(width 0.1524)
				(type default)
			)
			(layer "F.SilkS")
		)
		(fp_line
			(start 2.4384 3.0861)
			(end 2.5019 3.0607)
			(stroke
				(width 0.1524)
				(type default)
			)
			(layer "F.SilkS")
		)
		(fp_line
			(start 2.4638 2.667)
			(end 2.413 2.6543)
			(stroke
				(width 0.1524)
				(type default)
			)
			(layer "F.SilkS")
		)
		(fp_line
			(start 2.5019 2.6797)
			(end 2.4638 2.667)
			(stroke
				(width 0.1524)
				(type default)
			)
			(layer "F.SilkS")
		)
		(fp_line
			(start 2.8194 2.667)
			(end 3.048 2.667)
			(stroke
				(width 0.1524)
				(type default)
			)
			(layer "F.SilkS")
		)
		(fp_line
			(start 2.9337 2.4511)
			(end 2.9337 3.0861)
			(stroke
				(width 0.1524)
				(type default)
			)
			(layer "F.SilkS")
		)
		(fp_line
			(start 2.9337 3.0861)
			(end 3.1115 3.0734)
			(stroke
				(width 0.1524)
				(type default)
			)
			(layer "F.SilkS")
		)
		(fp_arc
			(start -1.5748 4.826)
			(mid -0.985625 3.828401)
			(end 0.127 3.5052)
			(stroke
				(width 0.1524)
				(type default)
			)
			(layer "F.SilkS")
		)
		(fp_arc
			(start -0.5588 -1.27)
			(mid 0.0762 -0.635)
			(end -0.5588 0)
			(stroke
				(width 0.254)
				(type default)
			)
			(layer "F.SilkS")
		)
		(fp_arc
			(start -0.127 3.5052)
			(mid 0.985653 3.828369)
			(end 1.5748 4.826)
			(stroke
				(width 0.1524)
				(type default)
			)
			(layer "F.SilkS")
		)
		(fp_arc
			(start 0.1524 6.096)
			(mid -0.964558 5.805567)
			(end -1.5748 4.826)
			(stroke
				(width 0.1524)
				(type default)
			)
			(layer "F.SilkS")
		)
		(fp_arc
			(start 1.5748 4.826)
			(mid 0.964538 5.805581)
			(end -0.1524 6.096)
			(stroke
				(width 0.1524)
				(type default)
			)
			(layer "F.SilkS")
		)
		(fp_circle
			(center -1.8923 2.8956)
			(end -1.71196 2.8956)
			(stroke
				(width 0.1524)
				(type default)
			)
			(fill no)
			(layer "F.SilkS")
		)
		(fp_circle
			(center 0 0)
			(end 2.03454 0)
			(stroke
				(width 0.1524)
				(type default)
			)
			(fill no)
			(layer "F.SilkS")
		)
		(fp_circle
			(center 0.9652 0.6858)
			(end 1.57734 0.6858)
			(stroke
				(width 0.254)
				(type default)
			)
			(fill no)
			(layer "F.SilkS")
		)
	)
	(footprint ""
		(layer "F.Cu")
		(at 2.794 -188.214)
		(property "Reference" "R316"
			(at 0 0 0)
			(layer "F.SilkS")
			(hide yes)
			(effects
				(font
					(size 1.27 1.27)
				)
			)
		)
		(property "Value" ""
			(at 0 0 0)
			(layer "F.Fab")
			(effects
				(font
					(size 1.27 1.27)
				)
			)
		)
		(duplicate_pad_numbers_are_jumpers no)
		(fp_line
			(start -0.7874 -0.4064)
			(end 0.7874 -0.4064)
			(stroke
				(width 0.1524)
				(type default)
			)
			(layer "F.SilkS")
		)
		(fp_line
			(start -0.7874 0.4064)
			(end -0.7874 -0.4064)
			(stroke
				(width 0.1524)
				(type default)
			)
			(layer "F.SilkS")
		)
		(fp_line
			(start 0.7874 -0.4064)
			(end 0.7874 0.4064)
			(stroke
				(width 0.1524)
				(type default)
			)
			(layer "F.SilkS")
		)
		(fp_line
			(start 0.7874 0.4064)
			(end -0.7874 0.4064)
			(stroke
				(width 0.1524)
				(type default)
			)
			(layer "F.SilkS")
		)
		(fp_line
			(start -0.67945 -0.305054)
			(end -0.12065 -0.305054)
			(stroke
				(width 0.1)
				(type default)
			)
			(layer "F.Fab")
		)
		(fp_line
			(start -0.67945 0.3048)
			(end -0.67945 -0.305054)
			(stroke
				(width 0.1)
				(type default)
			)
			(layer "F.Fab")
		)
		(fp_line
			(start -0.12065 -0.305054)
			(end -0.12065 -0.2794)
			(stroke
				(width 0.1)
				(type default)
			)
			(layer "F.Fab")
		)
		(fp_line
			(start -0.12065 -0.2794)
			(end 0.12065 -0.2794)
			(stroke
				(width 0.1)
				(type default)
			)
			(layer "F.Fab")
		)
		(fp_line
			(start -0.12065 0.2794)
			(end -0.12065 0.3048)
			(stroke
				(width 0.1)
				(type default)
			)
			(layer "F.Fab")
		)
		(fp_line
			(start -0.12065 0.3048)
			(end -0.67945 0.3048)
			(stroke
				(width 0.1)
				(type default)
			)
			(layer "F.Fab")
		)
		(fp_line
			(start 0.120396 0.2794)
			(end -0.12065 0.2794)
			(stroke
				(width 0.1)
				(type default)
			)
			(layer "F.Fab")
		)
		(fp_line
			(start 0.120396 0.3048)
			(end 0.120396 0.2794)
			(stroke
				(width 0.1)
				(type default)
			)
			(layer "F.Fab")
		)
		(fp_line
			(start 0.12065 -0.3048)
			(end 0.67945 -0.3048)
			(stroke
				(width 0.1)
				(type default)
			)
			(layer "F.Fab")
		)
		(fp_line
			(start 0.12065 -0.2794)
			(end 0.12065 -0.3048)
			(stroke
				(width 0.1)
				(type default)
			)
			(layer "F.Fab")
		)
		(fp_line
			(start 0.67945 -0.3048)
			(end 0.67945 0.3048)
			(stroke
				(width 0.1)
				(type default)
			)
			(layer "F.Fab")
		)
		(fp_line
			(start 0.67945 0.3048)
			(end 0.120396 0.3048)
			(stroke
				(width 0.1)
				(type default)
			)
			(layer "F.Fab")
		)
		(pad "1" smd circle
			(at -0.40005 0)
			(size 0 0)
			(layers "F.Cu" "F.Mask" "F.Paste")
			(net "GND")
		)
		(pad "2" smd circle
			(at 0.40005 0)
			(size 0 0)
			(layers "F.Cu" "F.Mask" "F.Paste")
			(net "FRU_ADDR1")
		)
	)
	(footprint ""
		(layer "F.Cu")
		(at 18.542 -209.169 180)
		(property "Reference" "R5536"
			(at 0 0 180)
			(layer "F.SilkS")
			(hide yes)
			(effects
				(font
					(size 1.27 1.27)
				)
			)
		)
		(property "Value" ""
			(at 0 0 180)
			(layer "F.Fab")
			(effects
				(font
					(size 1.27 1.27)
				)
			)
		)
		(duplicate_pad_numbers_are_jumpers no)
		(fp_line
			(start 0.7874 0.4064)
			(end -0.7874 0.4064)
			(stroke
				(width 0.1524)
				(type default)
			)
			(layer "F.SilkS")
		)
		(fp_line
			(start 0.7874 -0.4064)
			(end 0.7874 0.4064)
			(stroke
				(width 0.1524)
				(type default)
			)
			(layer "F.SilkS")
		)
		(fp_line
			(start -0.7874 0.4064)
			(end -0.7874 -0.4064)
			(stroke
				(width 0.1524)
				(type default)
			)
			(layer "F.SilkS")
		)
		(fp_line
			(start -0.7874 -0.4064)
			(end 0.7874 -0.4064)
			(stroke
				(width 0.1524)
				(type default)
			)
			(layer "F.SilkS")
		)
		(fp_line
			(start 0.67945 0.3048)
			(end 0.120396 0.3048)
			(stroke
				(width 0.1)
				(type default)
			)
			(layer "F.Fab")
		)
		(fp_line
			(start 0.67945 -0.3048)
			(end 0.67945 0.3048)
			(stroke
				(width 0.1)
				(type default)
			)
			(layer "F.Fab")
		)
		(fp_line
			(start 0.12065 -0.2794)
			(end 0.12065 -0.3048)
			(stroke
				(width 0.1)
				(type default)
			)
			(layer "F.Fab")
		)
		(fp_line
			(start 0.12065 -0.3048)
			(end 0.67945 -0.3048)
			(stroke
				(width 0.1)
				(type default)
			)
			(layer "F.Fab")
		)
		(fp_line
			(start 0.120396 0.3048)
			(end 0.120396 0.2794)
			(stroke
				(width 0.1)
				(type default)
			)
			(layer "F.Fab")
		)
		(fp_line
			(start 0.120396 0.2794)
			(end -0.12065 0.2794)
			(stroke
				(width 0.1)
				(type default)
			)
			(layer "F.Fab")
		)
		(fp_line
			(start -0.12065 0.3048)
			(end -0.67945 0.3048)
			(stroke
				(width 0.1)
				(type default)
			)
			(layer "F.Fab")
		)
		(fp_line
			(start -0.12065 0.2794)
			(end -0.12065 0.3048)
			(stroke
				(width 0.1)
				(type default)
			)
			(layer "F.Fab")
		)
		(fp_line
			(start -0.12065 -0.2794)
			(end 0.12065 -0.2794)
			(stroke
				(width 0.1)
				(type default)
			)
			(layer "F.Fab")
		)
		(fp_line
			(start -0.12065 -0.305054)
			(end -0.12065 -0.2794)
			(stroke
				(width 0.1)
				(type default)
			)
			(layer "F.Fab")
		)
		(fp_line
			(start -0.67945 0.3048)
			(end -0.67945 -0.305054)
			(stroke
				(width 0.1)
				(type default)
			)
			(layer "F.Fab")
		)
		(fp_line
			(start -0.67945 -0.305054)
			(end -0.12065 -0.305054)
			(stroke
				(width 0.1)
				(type default)
			)
			(layer "F.Fab")
		)
		(pad "1" smd rect
			(at -0.40005 0)
			(size 0.4572 0.508)
			(layers "F.Cu" "F.Mask" "F.Paste")
			(net "P12V_LED_FAN6")
		)
		(pad "2" smd rect
			(at 0.40005 0)
			(size 0.4572 0.508)
			(layers "F.Cu" "F.Mask" "F.Paste")
			(net "FAN_6_OK_LED_R_N")
		)
	)
	(footprint ""
		(layer "F.Cu")
		(at 29.0322 -58.70194 90)
		(property "Reference" "ME6"
			(at 0 0 90)
			(layer "F.SilkS")
			(hide yes)
			(effects
				(font
					(size 1.27 1.27)
				)
			)
		)
		(property "Value" ""
			(at 0 0 90)
			(layer "F.Fab")
			(effects
				(font
					(size 1.27 1.27)
				)
			)
		)
		(duplicate_pad_numbers_are_jumpers no)
	)
	(footprint ""
		(layer "F.Cu")
		(at 43.053 -98.806 180)
		(property "Reference" "C2122"
			(at 0 0 180)
			(layer "F.SilkS")
			(hide yes)
			(effects
				(font
					(size 1.27 1.27)
				)
			)
		)
		(property "Value" ""
			(at 0 0 180)
			(layer "F.Fab")
			(effects
				(font
					(size 1.27 1.27)
				)
			)
		)
		(duplicate_pad_numbers_are_jumpers no)
		(fp_line
			(start 1.2954 0.5842)
			(end -1.2954 0.5842)
			(stroke
				(width 0.1524)
				(type default)
			)
			(layer "F.SilkS")
		)
		(fp_line
			(start 1.2954 -0.5842)
			(end 1.2954 0.5842)
			(stroke
				(width 0.1524)
				(type default)
			)
			(layer "F.SilkS")
		)
		(fp_line
			(start -1.2954 0.5842)
			(end -1.2954 -0.5842)
			(stroke
				(width 0.1524)
				(type default)
			)
			(layer "F.SilkS")
		)
		(fp_line
			(start -1.2954 -0.5842)
			(end 1.2954 -0.5842)
			(stroke
				(width 0.1524)
				(type default)
			)
			(layer "F.SilkS")
		)
		(fp_line
			(start 1.1938 0.4064)
			(end 0.8636 0.4064)
			(stroke
				(width 0.1)
				(type default)
			)
			(layer "F.Fab")
		)
		(fp_line
			(start 1.1938 -0.4064)
			(end 1.1938 0.4064)
			(stroke
				(width 0.1)
				(type default)
			)
			(layer "F.Fab")
		)
		(fp_line
			(start 0.8636 0.4572)
			(end -0.8636 0.4572)
			(stroke
				(width 0.1)
				(type default)
			)
			(layer "F.Fab")
		)
		(fp_line
			(start 0.8636 0.4064)
			(end 0.8636 0.4572)
			(stroke
				(width 0.1)
				(type default)
			)
			(layer "F.Fab")
		)
		(fp_line
			(start 0.8636 -0.4064)
			(end 1.1938 -0.4064)
			(stroke
				(width 0.1)
				(type default)
			)
			(layer "F.Fab")
		)
		(fp_line
			(start 0.8636 -0.4572)
			(end 0.8636 -0.4064)
			(stroke
				(width 0.1)
				(type default)
			)
			(layer "F.Fab")
		)
		(fp_line
			(start -0.8636 0.4572)
			(end -0.8636 0.4064)
			(stroke
				(width 0.1)
				(type default)
			)
			(layer "F.Fab")
		)
		(fp_line
			(start -0.8636 0.4064)
			(end -1.1938 0.4064)
			(stroke
				(width 0.1)
				(type default)
			)
			(layer "F.Fab")
		)
		(fp_line
			(start -0.8636 -0.4064)
			(end -0.8636 -0.4572)
			(stroke
				(width 0.1)
				(type default)
			)
			(layer "F.Fab")
		)
		(fp_line
			(start -0.8636 -0.4572)
			(end 0.8636 -0.4572)
			(stroke
				(width 0.1)
				(type default)
			)
			(layer "F.Fab")
		)
		(fp_line
			(start -1.1938 0.4064)
			(end -1.1938 -0.4064)
			(stroke
				(width 0.1)
				(type default)
			)
			(layer "F.Fab")
		)
		(fp_line
			(start -1.1938 -0.4064)
			(end -0.8636 -0.4064)
			(stroke
				(width 0.1)
				(type default)
			)
			(layer "F.Fab")
		)
		(pad "1" smd rect
			(at -0.7366 0 90)
			(size 0.7112 0.8128)
			(layers "F.Cu" "F.Mask" "F.Paste")
			(net "U407_D1")
		)
		(pad "2" smd rect
			(at 0.7366 0 90)
			(size 0.7112 0.8128)
			(layers "F.Cu" "F.Mask" "F.Paste")
			(net "GND")
		)
	)
	(footprint ""
		(layer "F.Cu")
		(at 13.335 -169.291 180)
		(property "Reference" "R5503"
			(at 0 0 180)
			(layer "F.SilkS")
			(hide yes)
			(effects
				(font
					(size 1.27 1.27)
				)
			)
		)
		(property "Value" ""
			(at 0 0 180)
			(layer "F.Fab")
			(effects
				(font
					(size 1.27 1.27)
				)
			)
		)
		(duplicate_pad_numbers_are_jumpers no)
		(fp_line
			(start 0.7874 0.4064)
			(end -0.7874 0.4064)
			(stroke
				(width 0.1524)
				(type default)
			)
			(layer "F.SilkS")
		)
		(fp_line
			(start 0.7874 -0.4064)
			(end 0.7874 0.4064)
			(stroke
				(width 0.1524)
				(type default)
			)
			(layer "F.SilkS")
		)
		(fp_line
			(start -0.7874 0.4064)
			(end -0.7874 -0.4064)
			(stroke
				(width 0.1524)
				(type default)
			)
			(layer "F.SilkS")
		)
		(fp_line
			(start -0.7874 -0.4064)
			(end 0.7874 -0.4064)
			(stroke
				(width 0.1524)
				(type default)
			)
			(layer "F.SilkS")
		)
		(fp_line
			(start 0.67945 0.3048)
			(end 0.120396 0.3048)
			(stroke
				(width 0.1)
				(type default)
			)
			(layer "F.Fab")
		)
		(fp_line
			(start 0.67945 -0.3048)
			(end 0.67945 0.3048)
			(stroke
				(width 0.1)
				(type default)
			)
			(layer "F.Fab")
		)
		(fp_line
			(start 0.12065 -0.2794)
			(end 0.12065 -0.3048)
			(stroke
				(width 0.1)
				(type default)
			)
			(layer "F.Fab")
		)
		(fp_line
			(start 0.12065 -0.3048)
			(end 0.67945 -0.3048)
			(stroke
				(width 0.1)
				(type default)
			)
			(layer "F.Fab")
		)
		(fp_line
			(start 0.120396 0.3048)
			(end 0.120396 0.2794)
			(stroke
				(width 0.1)
				(type default)
			)
			(layer "F.Fab")
		)
		(fp_line
			(start 0.120396 0.2794)
			(end -0.12065 0.2794)
			(stroke
				(width 0.1)
				(type default)
			)
			(layer "F.Fab")
		)
		(fp_line
			(start -0.12065 0.3048)
			(end -0.67945 0.3048)
			(stroke
				(width 0.1)
				(type default)
			)
			(layer "F.Fab")
		)
		(fp_line
			(start -0.12065 0.2794)
			(end -0.12065 0.3048)
			(stroke
				(width 0.1)
				(type default)
			)
			(layer "F.Fab")
		)
		(fp_line
			(start -0.12065 -0.2794)
			(end 0.12065 -0.2794)
			(stroke
				(width 0.1)
				(type default)
			)
			(layer "F.Fab")
		)
		(fp_line
			(start -0.12065 -0.305054)
			(end -0.12065 -0.2794)
			(stroke
				(width 0.1)
				(type default)
			)
			(layer "F.Fab")
		)
		(fp_line
			(start -0.67945 0.3048)
			(end -0.67945 -0.305054)
			(stroke
				(width 0.1)
				(type default)
			)
			(layer "F.Fab")
		)
		(fp_line
			(start -0.67945 -0.305054)
			(end -0.12065 -0.305054)
			(stroke
				(width 0.1)
				(type default)
			)
			(layer "F.Fab")
		)
		(pad "1" smd circle
			(at -0.40005 0 180)
			(size 0 0)
			(layers "F.Cu" "F.Mask" "F.Paste")
			(net "P3V3_AUX")
		)
		(pad "2" smd circle
			(at 0.40005 0 180)
			(size 0 0)
			(layers "F.Cu" "F.Mask" "F.Paste")
			(net "FAN_4_PRESENT_N")
		)
	)
	(footprint ""
		(layer "F.Cu")
		(at 46.355 -167.513)
		(property "Reference" "R5116"
			(at 0 0 0)
			(layer "F.SilkS")
			(hide yes)
			(effects
				(font
					(size 1.27 1.27)
				)
			)
		)
		(property "Value" ""
			(at 0 0 0)
			(layer "F.Fab")
			(effects
				(font
					(size 1.27 1.27)
				)
			)
		)
		(duplicate_pad_numbers_are_jumpers no)
		(fp_line
			(start -0.7874 -0.4064)
			(end 0.7874 -0.4064)
			(stroke
				(width 0.1524)
				(type default)
			)
			(layer "F.SilkS")
		)
		(fp_line
			(start -0.7874 0.4064)
			(end -0.7874 -0.4064)
			(stroke
				(width 0.1524)
				(type default)
			)
			(layer "F.SilkS")
		)
		(fp_line
			(start 0.7874 -0.4064)
			(end 0.7874 0.4064)
			(stroke
				(width 0.1524)
				(type default)
			)
			(layer "F.SilkS")
		)
		(fp_line
			(start 0.7874 0.4064)
			(end -0.7874 0.4064)
			(stroke
				(width 0.1524)
				(type default)
			)
			(layer "F.SilkS")
		)
		(fp_line
			(start -0.67945 -0.305054)
			(end -0.12065 -0.305054)
			(stroke
				(width 0.1)
				(type default)
			)
			(layer "F.Fab")
		)
		(fp_line
			(start -0.67945 0.3048)
			(end -0.67945 -0.305054)
			(stroke
				(width 0.1)
				(type default)
			)
			(layer "F.Fab")
		)
		(fp_line
			(start -0.12065 -0.305054)
			(end -0.12065 -0.2794)
			(stroke
				(width 0.1)
				(type default)
			)
			(layer "F.Fab")
		)
		(fp_line
			(start -0.12065 -0.2794)
			(end 0.12065 -0.2794)
			(stroke
				(width 0.1)
				(type default)
			)
			(layer "F.Fab")
		)
		(fp_line
			(start -0.12065 0.2794)
			(end -0.12065 0.3048)
			(stroke
				(width 0.1)
				(type default)
			)
			(layer "F.Fab")
		)
		(fp_line
			(start -0.12065 0.3048)
			(end -0.67945 0.3048)
			(stroke
				(width 0.1)
				(type default)
			)
			(layer "F.Fab")
		)
		(fp_line
			(start 0.120396 0.2794)
			(end -0.12065 0.2794)
			(stroke
				(width 0.1)
				(type default)
			)
			(layer "F.Fab")
		)
		(fp_line
			(start 0.120396 0.3048)
			(end 0.120396 0.2794)
			(stroke
				(width 0.1)
				(type default)
			)
			(layer "F.Fab")
		)
		(fp_line
			(start 0.12065 -0.3048)
			(end 0.67945 -0.3048)
			(stroke
				(width 0.1)
				(type default)
			)
			(layer "F.Fab")
		)
		(fp_line
			(start 0.12065 -0.2794)
			(end 0.12065 -0.3048)
			(stroke
				(width 0.1)
				(type default)
			)
			(layer "F.Fab")
		)
		(fp_line
			(start 0.67945 -0.3048)
			(end 0.67945 0.3048)
			(stroke
				(width 0.1)
				(type default)
			)
			(layer "F.Fab")
		)
		(fp_line
			(start 0.67945 0.3048)
			(end 0.120396 0.3048)
			(stroke
				(width 0.1)
				(type default)
			)
			(layer "F.Fab")
		)
		(pad "1" smd circle
			(at -0.40005 0)
			(size 0 0)
			(layers "F.Cu" "F.Mask" "F.Paste")
			(net "PCA9552_MB1_A1")
		)
		(pad "2" smd circle
			(at 0.40005 0)
			(size 0 0)
			(layers "F.Cu" "F.Mask" "F.Paste")
			(net "GND")
		)
	)
	(footprint ""
		(layer "F.Cu")
		(at 19.431 -136.017 -90)
		(property "Reference" "R4850"
			(at 0 0 270)
			(layer "F.SilkS")
			(hide yes)
			(effects
				(font
					(size 1.27 1.27)
				)
			)
		)
		(property "Value" ""
			(at 0 0 270)
			(layer "F.Fab")
			(effects
				(font
					(size 1.27 1.27)
				)
			)
		)
		(duplicate_pad_numbers_are_jumpers no)
		(fp_line
			(start -0.7874 0.4064)
			(end -0.7874 -0.4064)
			(stroke
				(width 0.1524)
				(type default)
			)
			(layer "F.SilkS")
		)
		(fp_line
			(start 0.7874 0.4064)
			(end -0.7874 0.4064)
			(stroke
				(width 0.1524)
				(type default)
			)
			(layer "F.SilkS")
		)
		(fp_line
			(start -0.7874 -0.4064)
			(end 0.7874 -0.4064)
			(stroke
				(width 0.1524)
				(type default)
			)
			(layer "F.SilkS")
		)
		(fp_line
			(start 0.7874 -0.4064)
			(end 0.7874 0.4064)
			(stroke
				(width 0.1524)
				(type default)
			)
			(layer "F.SilkS")
		)
		(fp_line
			(start -0.67945 0.3048)
			(end -0.67945 -0.305054)
			(stroke
				(width 0.1)
				(type default)
			)
			(layer "F.Fab")
		)
		(fp_line
			(start -0.12065 0.3048)
			(end -0.67945 0.3048)
			(stroke
				(width 0.1)
				(type default)
			)
			(layer "F.Fab")
		)
		(fp_line
			(start 0.120396 0.3048)
			(end 0.120396 0.2794)
			(stroke
				(width 0.1)
				(type default)
			)
			(layer "F.Fab")
		)
		(fp_line
			(start 0.67945 0.3048)
			(end 0.120396 0.3048)
			(stroke
				(width 0.1)
				(type default)
			)
			(layer "F.Fab")
		)
		(fp_line
			(start -0.12065 0.2794)
			(end -0.12065 0.3048)
			(stroke
				(width 0.1)
				(type default)
			)
			(layer "F.Fab")
		)
		(fp_line
			(start 0.120396 0.2794)
			(end -0.12065 0.2794)
			(stroke
				(width 0.1)
				(type default)
			)
			(layer "F.Fab")
		)
		(fp_line
			(start -0.12065 -0.2794)
			(end 0.12065 -0.2794)
			(stroke
				(width 0.1)
				(type default)
			)
			(layer "F.Fab")
		)
		(fp_line
			(start 0.12065 -0.2794)
			(end 0.12065 -0.3048)
			(stroke
				(width 0.1)
				(type default)
			)
			(layer "F.Fab")
		)
		(fp_line
			(start 0.12065 -0.3048)
			(end 0.67945 -0.3048)
			(stroke
				(width 0.1)
				(type default)
			)
			(layer "F.Fab")
		)
		(fp_line
			(start 0.67945 -0.3048)
			(end 0.67945 0.3048)
			(stroke
				(width 0.1)
				(type default)
			)
			(layer "F.Fab")
		)
		(fp_line
			(start -0.67945 -0.305054)
			(end -0.12065 -0.305054)
			(stroke
				(width 0.1)
				(type default)
			)
			(layer "F.Fab")
		)
		(fp_line
			(start -0.12065 -0.305054)
			(end -0.12065 -0.2794)
			(stroke
				(width 0.1)
				(type default)
			)
			(layer "F.Fab")
		)
		(pad "1" smd circle
			(at -0.40005 0 270)
			(size 0 0)
			(layers "F.Cu" "F.Mask" "F.Paste")
			(net "GND")
		)
		(pad "2" smd circle
			(at 0.40005 0 270)
			(size 0 0)
			(layers "F.Cu" "F.Mask" "F.Paste")
			(net "MAX31790_U330_ADD0")
		)
	)
	(footprint ""
		(layer "F.Cu")
		(at 18.669 -289.179)
		(property "Reference" "R5322"
			(at 0 0 0)
			(layer "F.SilkS")
			(hide yes)
			(effects
				(font
					(size 1.27 1.27)
				)
			)
		)
		(property "Value" ""
			(at 0 0 0)
			(layer "F.Fab")
			(effects
				(font
					(size 1.27 1.27)
				)
			)
		)
		(duplicate_pad_numbers_are_jumpers no)
		(fp_line
			(start -0.7874 -0.4064)
			(end 0.7874 -0.4064)
			(stroke
				(width 0.1524)
				(type default)
			)
			(layer "F.SilkS")
		)
		(fp_line
			(start -0.7874 0.4064)
			(end -0.7874 -0.4064)
			(stroke
				(width 0.1524)
				(type default)
			)
			(layer "F.SilkS")
		)
		(fp_line
			(start 0.7874 -0.4064)
			(end 0.7874 0.4064)
			(stroke
				(width 0.1524)
				(type default)
			)
			(layer "F.SilkS")
		)
		(fp_line
			(start 0.7874 0.4064)
			(end -0.7874 0.4064)
			(stroke
				(width 0.1524)
				(type default)
			)
			(layer "F.SilkS")
		)
		(fp_line
			(start -0.67945 -0.305054)
			(end -0.12065 -0.305054)
			(stroke
				(width 0.1)
				(type default)
			)
			(layer "F.Fab")
		)
		(fp_line
			(start -0.67945 0.3048)
			(end -0.67945 -0.305054)
			(stroke
				(width 0.1)
				(type default)
			)
			(layer "F.Fab")
		)
		(fp_line
			(start -0.12065 -0.305054)
			(end -0.12065 -0.2794)
			(stroke
				(width 0.1)
				(type default)
			)
			(layer "F.Fab")
		)
		(fp_line
			(start -0.12065 -0.2794)
			(end 0.12065 -0.2794)
			(stroke
				(width 0.1)
				(type default)
			)
			(layer "F.Fab")
		)
		(fp_line
			(start -0.12065 0.2794)
			(end -0.12065 0.3048)
			(stroke
				(width 0.1)
				(type default)
			)
			(layer "F.Fab")
		)
		(fp_line
			(start -0.12065 0.3048)
			(end -0.67945 0.3048)
			(stroke
				(width 0.1)
				(type default)
			)
			(layer "F.Fab")
		)
		(fp_line
			(start 0.120396 0.2794)
			(end -0.12065 0.2794)
			(stroke
				(width 0.1)
				(type default)
			)
			(layer "F.Fab")
		)
		(fp_line
			(start 0.120396 0.3048)
			(end 0.120396 0.2794)
			(stroke
				(width 0.1)
				(type default)
			)
			(layer "F.Fab")
		)
		(fp_line
			(start 0.12065 -0.3048)
			(end 0.67945 -0.3048)
			(stroke
				(width 0.1)
				(type default)
			)
			(layer "F.Fab")
		)
		(fp_line
			(start 0.12065 -0.2794)
			(end 0.12065 -0.3048)
			(stroke
				(width 0.1)
				(type default)
			)
			(layer "F.Fab")
		)
		(fp_line
			(start 0.67945 -0.3048)
			(end 0.67945 0.3048)
			(stroke
				(width 0.1)
				(type default)
			)
			(layer "F.Fab")
		)
		(fp_line
			(start 0.67945 0.3048)
			(end 0.120396 0.3048)
			(stroke
				(width 0.1)
				(type default)
			)
			(layer "F.Fab")
		)
		(pad "1" smd rect
			(at -0.40005 0 180)
			(size 0.4572 0.508)
			(layers "F.Cu" "F.Mask" "F.Paste")
			(net "FAN_7_TACH_IL_R")
		)
		(pad "2" smd rect
			(at 0.40005 0 180)
			(size 0.4572 0.508)
			(layers "F.Cu" "F.Mask" "F.Paste")
			(net "FAN_7_TACH_IL")
		)
	)
	(footprint ""
		(layer "F.Cu")
		(at 16.520922 -19.136868)
		(property "Reference" "C2015"
			(at 0 0 0)
			(layer "F.SilkS")
			(hide yes)
			(effects
				(font
					(size 1.27 1.27)
				)
			)
		)
		(property "Value" ""
			(at 0 0 0)
			(layer "F.Fab")
			(effects
				(font
					(size 1.27 1.27)
				)
			)
		)
		(duplicate_pad_numbers_are_jumpers no)
		(fp_line
			(start -0.7874 -0.4064)
			(end 0.7874 -0.4064)
			(stroke
				(width 0.1524)
				(type default)
			)
			(layer "F.SilkS")
		)
		(fp_line
			(start -0.7874 0.4064)
			(end -0.7874 -0.4064)
			(stroke
				(width 0.1524)
				(type default)
			)
			(layer "F.SilkS")
		)
		(fp_line
			(start 0.7874 -0.4064)
			(end 0.7874 0.4064)
			(stroke
				(width 0.1524)
				(type default)
			)
			(layer "F.SilkS")
		)
		(fp_line
			(start 0.7874 0.4064)
			(end -0.7874 0.4064)
			(stroke
				(width 0.1524)
				(type default)
			)
			(layer "F.SilkS")
		)
		(fp_line
			(start -0.67945 -0.305054)
			(end -0.12065 -0.305054)
			(stroke
				(width 0.1)
				(type default)
			)
			(layer "F.Fab")
		)
		(fp_line
			(start -0.67945 0.3048)
			(end -0.67945 -0.305054)
			(stroke
				(width 0.1)
				(type default)
			)
			(layer "F.Fab")
		)
		(fp_line
			(start -0.12065 -0.305054)
			(end -0.12065 -0.2794)
			(stroke
				(width 0.1)
				(type default)
			)
			(layer "F.Fab")
		)
		(fp_line
			(start -0.12065 -0.2794)
			(end 0.12065 -0.2794)
			(stroke
				(width 0.1)
				(type default)
			)
			(layer "F.Fab")
		)
		(fp_line
			(start -0.12065 0.2794)
			(end -0.12065 0.3048)
			(stroke
				(width 0.1)
				(type default)
			)
			(layer "F.Fab")
		)
		(fp_line
			(start -0.12065 0.3048)
			(end -0.67945 0.3048)
			(stroke
				(width 0.1)
				(type default)
			)
			(layer "F.Fab")
		)
		(fp_line
			(start 0.120396 0.2794)
			(end -0.12065 0.2794)
			(stroke
				(width 0.1)
				(type default)
			)
			(layer "F.Fab")
		)
		(fp_line
			(start 0.120396 0.3048)
			(end 0.120396 0.2794)
			(stroke
				(width 0.1)
				(type default)
			)
			(layer "F.Fab")
		)
		(fp_line
			(start 0.12065 -0.3048)
			(end 0.67945 -0.3048)
			(stroke
				(width 0.1)
				(type default)
			)
			(layer "F.Fab")
		)
		(fp_line
			(start 0.12065 -0.2794)
			(end 0.12065 -0.3048)
			(stroke
				(width 0.1)
				(type default)
			)
			(layer "F.Fab")
		)
		(fp_line
			(start 0.67945 -0.3048)
			(end 0.67945 0.3048)
			(stroke
				(width 0.1)
				(type default)
			)
			(layer "F.Fab")
		)
		(fp_line
			(start 0.67945 0.3048)
			(end 0.120396 0.3048)
			(stroke
				(width 0.1)
				(type default)
			)
			(layer "F.Fab")
		)
		(pad "1" smd circle
			(at -0.40005 0)
			(size 0 0)
			(layers "F.Cu" "F.Mask" "F.Paste")
			(net "FAN_4_PWM_IL_R")
		)
		(pad "2" smd circle
			(at 0.40005 0)
			(size 0 0)
			(layers "F.Cu" "F.Mask" "F.Paste")
			(net "GND")
		)
	)
	(footprint ""
		(layer "F.Cu")
		(at 35.306 -119.564912 180)
		(property "Reference" "C2040"
			(at 0 0 180)
			(layer "F.SilkS")
			(hide yes)
			(effects
				(font
					(size 1.27 1.27)
				)
			)
		)
		(property "Value" ""
			(at 0 0 180)
			(layer "F.Fab")
			(effects
				(font
					(size 1.27 1.27)
				)
			)
		)
		(duplicate_pad_numbers_are_jumpers no)
		(fp_line
			(start 0.7874 0.4064)
			(end -0.7874 0.4064)
			(stroke
				(width 0.1524)
				(type default)
			)
			(layer "F.SilkS")
		)
		(fp_line
			(start 0.7874 -0.4064)
			(end 0.7874 0.4064)
			(stroke
				(width 0.1524)
				(type default)
			)
			(layer "F.SilkS")
		)
		(fp_line
			(start -0.7874 0.4064)
			(end -0.7874 -0.4064)
			(stroke
				(width 0.1524)
				(type default)
			)
			(layer "F.SilkS")
		)
		(fp_line
			(start -0.7874 -0.4064)
			(end 0.7874 -0.4064)
			(stroke
				(width 0.1524)
				(type default)
			)
			(layer "F.SilkS")
		)
		(fp_line
			(start 0.67945 0.3048)
			(end 0.120396 0.3048)
			(stroke
				(width 0.1)
				(type default)
			)
			(layer "F.Fab")
		)
		(fp_line
			(start 0.67945 -0.3048)
			(end 0.67945 0.3048)
			(stroke
				(width 0.1)
				(type default)
			)
			(layer "F.Fab")
		)
		(fp_line
			(start 0.12065 -0.2794)
			(end 0.12065 -0.3048)
			(stroke
				(width 0.1)
				(type default)
			)
			(layer "F.Fab")
		)
		(fp_line
			(start 0.12065 -0.3048)
			(end 0.67945 -0.3048)
			(stroke
				(width 0.1)
				(type default)
			)
			(layer "F.Fab")
		)
		(fp_line
			(start 0.120396 0.3048)
			(end 0.120396 0.2794)
			(stroke
				(width 0.1)
				(type default)
			)
			(layer "F.Fab")
		)
		(fp_line
			(start 0.120396 0.2794)
			(end -0.12065 0.2794)
			(stroke
				(width 0.1)
				(type default)
			)
			(layer "F.Fab")
		)
		(fp_line
			(start -0.12065 0.3048)
			(end -0.67945 0.3048)
			(stroke
				(width 0.1)
				(type default)
			)
			(layer "F.Fab")
		)
		(fp_line
			(start -0.12065 0.2794)
			(end -0.12065 0.3048)
			(stroke
				(width 0.1)
				(type default)
			)
			(layer "F.Fab")
		)
		(fp_line
			(start -0.12065 -0.2794)
			(end 0.12065 -0.2794)
			(stroke
				(width 0.1)
				(type default)
			)
			(layer "F.Fab")
		)
		(fp_line
			(start -0.12065 -0.305054)
			(end -0.12065 -0.2794)
			(stroke
				(width 0.1)
				(type default)
			)
			(layer "F.Fab")
		)
		(fp_line
			(start -0.67945 0.3048)
			(end -0.67945 -0.305054)
			(stroke
				(width 0.1)
				(type default)
			)
			(layer "F.Fab")
		)
		(fp_line
			(start -0.67945 -0.305054)
			(end -0.12065 -0.305054)
			(stroke
				(width 0.1)
				(type default)
			)
			(layer "F.Fab")
		)
		(pad "1" smd circle
			(at -0.40005 0 180)
			(size 0 0)
			(layers "F.Cu" "F.Mask" "F.Paste")
			(net "FAN_2_PWM_OL_R")
		)
		(pad "2" smd circle
			(at 0.40005 0 180)
			(size 0 0)
			(layers "F.Cu" "F.Mask" "F.Paste")
			(net "GND")
		)
	)
	(footprint ""
		(layer "F.Cu")
		(at 28.956 -176.022 180)
		(property "Reference" "R5104"
			(at 0 0 180)
			(layer "F.SilkS")
			(hide yes)
			(effects
				(font
					(size 1.27 1.27)
				)
			)
		)
		(property "Value" ""
			(at 0 0 180)
			(layer "F.Fab")
			(effects
				(font
					(size 1.27 1.27)
				)
			)
		)
		(duplicate_pad_numbers_are_jumpers no)
		(fp_line
			(start 0.7874 0.4064)
			(end -0.7874 0.4064)
			(stroke
				(width 0.1524)
				(type default)
			)
			(layer "F.SilkS")
		)
		(fp_line
			(start 0.7874 -0.4064)
			(end 0.7874 0.4064)
			(stroke
				(width 0.1524)
				(type default)
			)
			(layer "F.SilkS")
		)
		(fp_line
			(start -0.7874 0.4064)
			(end -0.7874 -0.4064)
			(stroke
				(width 0.1524)
				(type default)
			)
			(layer "F.SilkS")
		)
		(fp_line
			(start -0.7874 -0.4064)
			(end 0.7874 -0.4064)
			(stroke
				(width 0.1524)
				(type default)
			)
			(layer "F.SilkS")
		)
		(fp_line
			(start 0.67945 0.3048)
			(end 0.120396 0.3048)
			(stroke
				(width 0.1)
				(type default)
			)
			(layer "F.Fab")
		)
		(fp_line
			(start 0.67945 -0.3048)
			(end 0.67945 0.3048)
			(stroke
				(width 0.1)
				(type default)
			)
			(layer "F.Fab")
		)
		(fp_line
			(start 0.12065 -0.2794)
			(end 0.12065 -0.3048)
			(stroke
				(width 0.1)
				(type default)
			)
			(layer "F.Fab")
		)
		(fp_line
			(start 0.12065 -0.3048)
			(end 0.67945 -0.3048)
			(stroke
				(width 0.1)
				(type default)
			)
			(layer "F.Fab")
		)
		(fp_line
			(start 0.120396 0.3048)
			(end 0.120396 0.2794)
			(stroke
				(width 0.1)
				(type default)
			)
			(layer "F.Fab")
		)
		(fp_line
			(start 0.120396 0.2794)
			(end -0.12065 0.2794)
			(stroke
				(width 0.1)
				(type default)
			)
			(layer "F.Fab")
		)
		(fp_line
			(start -0.12065 0.3048)
			(end -0.67945 0.3048)
			(stroke
				(width 0.1)
				(type default)
			)
			(layer "F.Fab")
		)
		(fp_line
			(start -0.12065 0.2794)
			(end -0.12065 0.3048)
			(stroke
				(width 0.1)
				(type default)
			)
			(layer "F.Fab")
		)
		(fp_line
			(start -0.12065 -0.2794)
			(end 0.12065 -0.2794)
			(stroke
				(width 0.1)
				(type default)
			)
			(layer "F.Fab")
		)
		(fp_line
			(start -0.12065 -0.305054)
			(end -0.12065 -0.2794)
			(stroke
				(width 0.1)
				(type default)
			)
			(layer "F.Fab")
		)
		(fp_line
			(start -0.67945 0.3048)
			(end -0.67945 -0.305054)
			(stroke
				(width 0.1)
				(type default)
			)
			(layer "F.Fab")
		)
		(fp_line
			(start -0.67945 -0.305054)
			(end -0.12065 -0.305054)
			(stroke
				(width 0.1)
				(type default)
			)
			(layer "F.Fab")
		)
		(pad "1" smd circle
			(at -0.40005 0 180)
			(size 0 0)
			(layers "F.Cu" "F.Mask" "F.Paste")
			(net "FAN_5_OK_LED")
		)
		(pad "2" smd circle
			(at 0.40005 0 180)
			(size 0 0)
			(layers "F.Cu" "F.Mask" "F.Paste")
			(net "FAN_5_OK_R_LED")
		)
	)
	(footprint ""
		(layer "F.Cu")
		(at 14.351 -207.264 180)
		(property "Reference" "R5372"
			(at 0 0 180)
			(layer "F.SilkS")
			(hide yes)
			(effects
				(font
					(size 1.27 1.27)
				)
			)
		)
		(property "Value" ""
			(at 0 0 180)
			(layer "F.Fab")
			(effects
				(font
					(size 1.27 1.27)
				)
			)
		)
		(duplicate_pad_numbers_are_jumpers no)
		(fp_line
			(start 0.7874 0.4064)
			(end -0.7874 0.4064)
			(stroke
				(width 0.1524)
				(type default)
			)
			(layer "F.SilkS")
		)
		(fp_line
			(start 0.7874 -0.4064)
			(end 0.7874 0.4064)
			(stroke
				(width 0.1524)
				(type default)
			)
			(layer "F.SilkS")
		)
		(fp_line
			(start -0.7874 0.4064)
			(end -0.7874 -0.4064)
			(stroke
				(width 0.1524)
				(type default)
			)
			(layer "F.SilkS")
		)
		(fp_line
			(start -0.7874 -0.4064)
			(end 0.7874 -0.4064)
			(stroke
				(width 0.1524)
				(type default)
			)
			(layer "F.SilkS")
		)
		(fp_line
			(start 0.67945 0.3048)
			(end 0.120396 0.3048)
			(stroke
				(width 0.1)
				(type default)
			)
			(layer "F.Fab")
		)
		(fp_line
			(start 0.67945 -0.3048)
			(end 0.67945 0.3048)
			(stroke
				(width 0.1)
				(type default)
			)
			(layer "F.Fab")
		)
		(fp_line
			(start 0.12065 -0.2794)
			(end 0.12065 -0.3048)
			(stroke
				(width 0.1)
				(type default)
			)
			(layer "F.Fab")
		)
		(fp_line
			(start 0.12065 -0.3048)
			(end 0.67945 -0.3048)
			(stroke
				(width 0.1)
				(type default)
			)
			(layer "F.Fab")
		)
		(fp_line
			(start 0.120396 0.3048)
			(end 0.120396 0.2794)
			(stroke
				(width 0.1)
				(type default)
			)
			(layer "F.Fab")
		)
		(fp_line
			(start 0.120396 0.2794)
			(end -0.12065 0.2794)
			(stroke
				(width 0.1)
				(type default)
			)
			(layer "F.Fab")
		)
		(fp_line
			(start -0.12065 0.3048)
			(end -0.67945 0.3048)
			(stroke
				(width 0.1)
				(type default)
			)
			(layer "F.Fab")
		)
		(fp_line
			(start -0.12065 0.2794)
			(end -0.12065 0.3048)
			(stroke
				(width 0.1)
				(type default)
			)
			(layer "F.Fab")
		)
		(fp_line
			(start -0.12065 -0.2794)
			(end 0.12065 -0.2794)
			(stroke
				(width 0.1)
				(type default)
			)
			(layer "F.Fab")
		)
		(fp_line
			(start -0.12065 -0.305054)
			(end -0.12065 -0.2794)
			(stroke
				(width 0.1)
				(type default)
			)
			(layer "F.Fab")
		)
		(fp_line
			(start -0.67945 0.3048)
			(end -0.67945 -0.305054)
			(stroke
				(width 0.1)
				(type default)
			)
			(layer "F.Fab")
		)
		(fp_line
			(start -0.67945 -0.305054)
			(end -0.12065 -0.305054)
			(stroke
				(width 0.1)
				(type default)
			)
			(layer "F.Fab")
		)
		(pad "1" smd rect
			(at -0.40005 0)
			(size 0.4572 0.508)
			(layers "F.Cu" "F.Mask" "F.Paste")
			(net "FAN_6_OK_LED_R_N")
		)
		(pad "2" smd rect
			(at 0.40005 0)
			(size 0.4572 0.508)
			(layers "F.Cu" "F.Mask" "F.Paste")
			(net "FAN_6_OK_R_LED_N")
		)
	)
	(footprint ""
		(layer "F.Cu")
		(at 8.509 -131.191 90)
		(property "Reference" "U404"
			(at -4.21513 -1.81356 0)
			(unlocked yes)
			(layer "F.SilkS")
			(effects
				(font
					(size 0.7874 0.5842)
					(thickness 0.1524)
				)
				(justify left)
			)
		)
		(property "Value" ""
			(at 0 0 90)
			(layer "F.Fab")
			(effects
				(font
					(size 1.27 1.27)
				)
			)
		)
		(duplicate_pad_numbers_are_jumpers no)
		(fp_line
			(start 0.762 -3.6576)
			(end 0.762 -2.6416)
			(stroke
				(width 0.1524)
				(type default)
			)
			(layer "F.SilkS")
		)
		(fp_line
			(start 1.999996 -1.999996)
			(end 1.999996 -1.524)
			(stroke
				(width 0.1524)
				(type default)
			)
			(layer "F.SilkS")
		)
		(fp_line
			(start 1.524 -1.999996)
			(end 1.999996 -1.999996)
			(stroke
				(width 0.1524)
				(type default)
			)
			(layer "F.SilkS")
		)
		(fp_line
			(start -1.999996 -1.999996)
			(end -1.524 -1.999996)
			(stroke
				(width 0.1524)
				(type default)
			)
			(layer "F.SilkS")
		)
		(fp_line
			(start -1.999996 -1.524)
			(end -1.999996 -1.999996)
			(stroke
				(width 0.1524)
				(type default)
			)
			(layer "F.SilkS")
		)
		(fp_line
			(start 3.1496 0.254)
			(end 2.6416 0.254)
			(stroke
				(width 0.1524)
				(type default)
			)
			(layer "F.SilkS")
		)
		(fp_line
			(start -2.6416 0.762)
			(end -3.1496 0.762)
			(stroke
				(width 0.1524)
				(type default)
			)
			(layer "F.SilkS")
		)
		(fp_line
			(start 1.999996 1.524)
			(end 1.999996 1.999996)
			(stroke
				(width 0.1524)
				(type default)
			)
			(layer "F.SilkS")
		)
		(fp_line
			(start 1.999996 1.999996)
			(end 1.524 1.999996)
			(stroke
				(width 0.1524)
				(type default)
			)
			(layer "F.SilkS")
		)
		(fp_line
			(start -1.524 1.999996)
			(end -1.999996 1.999996)
			(stroke
				(width 0.1524)
				(type default)
			)
			(layer "F.SilkS")
		)
		(fp_line
			(start -1.999996 1.999996)
			(end -1.999996 1.524)
			(stroke
				(width 0.1524)
				(type default)
			)
			(layer "F.SilkS")
		)
		(fp_line
			(start 0.254 2.6416)
			(end 0.254 3.6576)
			(stroke
				(width 0.1524)
				(type default)
			)
			(layer "F.SilkS")
		)
		(fp_poly
			(pts
				(xy -2.63779 -1.249934) (xy -3.40741 -0.865378) (xy -3.40741 -1.634744)
			)
			(stroke
				(width 0)
				(type default)
			)
			(fill yes)
			(layer "F.SilkS")
		)
		(fp_line
			(start 0.762 -3.6576)
			(end 0.762 -2.6416)
			(stroke
				(width 0.1)
				(type default)
			)
			(layer "F.Fab")
		)
		(fp_line
			(start 1.999996 -1.999996)
			(end 1.999996 1.999996)
			(stroke
				(width 0.1)
				(type default)
			)
			(layer "F.Fab")
		)
		(fp_line
			(start -1.999996 -1.999996)
			(end 1.999996 -1.999996)
			(stroke
				(width 0.1)
				(type default)
			)
			(layer "F.Fab")
		)
		(fp_line
			(start 3.1496 0.254)
			(end 2.6416 0.254)
			(stroke
				(width 0.1)
				(type default)
			)
			(layer "F.Fab")
		)
		(fp_line
			(start -2.6416 0.762)
			(end -3.1496 0.762)
			(stroke
				(width 0.1)
				(type default)
			)
			(layer "F.Fab")
		)
		(fp_line
			(start 1.999996 1.999996)
			(end -1.999996 1.999996)
			(stroke
				(width 0.1)
				(type default)
			)
			(layer "F.Fab")
		)
		(fp_line
			(start -1.999996 1.999996)
			(end -1.999996 -1.999996)
			(stroke
				(width 0.1)
				(type default)
			)
			(layer "F.Fab")
		)
		(fp_line
			(start 0.254 2.6416)
			(end 0.254 3.6576)
			(stroke
				(width 0.1)
				(type default)
			)
			(layer "F.Fab")
		)
		(fp_poly
			(pts
				(xy -2.63779 -1.249934) (xy -3.40741 -0.865378) (xy -3.40741 -1.634744)
			)
			(stroke
				(width 0)
				(type default)
			)
			(fill yes)
			(layer "F.Fab")
		)
		(fp_text user "19"
			(at 1.41732 -3.19913 90)
			(unlocked yes)
			(layer "F.SilkS")
			(effects
				(font
					(size 0.635 0.4064)
					(thickness 0.1524)
				)
			)
		)
		(fp_text user "24"
			(at -1.52908 -3.06959 90)
			(unlocked yes)
			(layer "F.SilkS")
			(effects
				(font
					(size 0.635 0.4064)
					(thickness 0.1524)
				)
			)
		)
		(fp_text user "18"
			(at 2.55651 -1.99644 0)
			(unlocked yes)
			(layer "F.SilkS")
			(effects
				(font
					(size 0.635 0.4064)
					(thickness 0.1524)
				)
			)
		)
		(fp_text user "13"
			(at 3.01625 1.524 0)
			(unlocked yes)
			(layer "F.SilkS")
			(effects
				(font
					(size 0.635 0.4064)
					(thickness 0.1524)
				)
			)
		)
		(fp_text user "6"
			(at -3.00355 1.5494 0)
			(unlocked yes)
			(layer "F.SilkS")
			(effects
				(font
					(size 0.635 0.4064)
					(thickness 0.1524)
				)
			)
		)
		(fp_text user "12"
			(at 1.5748 3.02895 90)
			(unlocked yes)
			(layer "F.SilkS")
			(effects
				(font
					(size 0.635 0.4064)
					(thickness 0.1524)
				)
			)
		)
		(fp_text user "7"
			(at -1.67132 3.11785 90)
			(unlocked yes)
			(layer "F.SilkS")
			(effects
				(font
					(size 0.635 0.4064)
					(thickness 0.1524)
				)
			)
		)
		(fp_text user "19"
			(at 1.7018 -3.09245 90)
			(unlocked yes)
			(layer "F.Fab")
			(effects
				(font
					(size 0.635 0.4064)
					(thickness 0.1524)
				)
			)
		)
		(fp_text user "24"
			(at -1.6256 -3.01625 90)
			(unlocked yes)
			(layer "F.Fab")
			(effects
				(font
					(size 0.635 0.4064)
					(thickness 0.1524)
				)
			)
		)
		(fp_text user "18"
			(at 3.04165 -1.6256 0)
			(unlocked yes)
			(layer "F.Fab")
			(effects
				(font
					(size 0.635 0.4064)
					(thickness 0.1524)
				)
			)
		)
		(fp_text user "13"
			(at 3.01625 1.524 0)
			(unlocked yes)
			(layer "F.Fab")
			(effects
				(font
					(size 0.635 0.4064)
					(thickness 0.1524)
				)
			)
		)
		(fp_text user "6"
			(at -3.00355 1.5494 0)
			(unlocked yes)
			(layer "F.Fab")
			(effects
				(font
					(size 0.635 0.4064)
					(thickness 0.1524)
				)
			)
		)
		(fp_text user "12"
			(at 1.5748 3.02895 90)
			(unlocked yes)
			(layer "F.Fab")
			(effects
				(font
					(size 0.635 0.4064)
					(thickness 0.1524)
				)
			)
		)
		(fp_text user "7"
			(at -1.27 3.10515 90)
			(unlocked yes)
			(layer "F.Fab")
			(effects
				(font
					(size 0.635 0.4064)
					(thickness 0.1524)
				)
			)
		)
		(pad "1" smd rect
			(at -2.050034 -1.249934)
			(size 0.2794 0.9144)
			(layers "F.Cu" "F.Mask" "F.Paste")
			(net "FAN_4_PWM_R2")
		)
		(pad "2" smd rect
			(at -2.050034 -0.750062)
			(size 0.2794 0.9144)
			(layers "F.Cu" "F.Mask" "F.Paste")
			(net "FAN_4_TACH_IL_R2")
		)
		(pad "3" smd rect
			(at -2.050034 -0.249936)
			(size 0.2794 0.9144)
			(layers "F.Cu" "F.Mask" "F.Paste")
			(net "FAN_5_TACH_IL_R2")
		)
		(pad "4" smd rect
			(at -2.050034 0.249936)
			(size 0.2794 0.9144)
			(layers "F.Cu" "F.Mask" "F.Paste")
			(net "FAN_4_TACH_OL_R2")
		)
		(pad "5" smd rect
			(at -2.050034 0.750062)
			(size 0.2794 0.9144)
			(layers "F.Cu" "F.Mask" "F.Paste")
			(net "FAN_5_PWM_R2")
		)
		(pad "6" smd rect
			(at -2.050034 1.249934)
			(size 0.2794 0.9144)
			(layers "F.Cu" "F.Mask" "F.Paste")
			(net "FAN_5_TACH_OL_R2")
		)
		(pad "7" smd rect
			(at -1.249934 2.050034 90)
			(size 0.2794 0.9144)
			(layers "F.Cu" "F.Mask" "F.Paste")
			(net "FAN_6_PWM_R2")
		)
		(pad "8" smd rect
			(at -0.750062 2.050034 90)
			(size 0.2794 0.9144)
			(layers "F.Cu" "F.Mask" "F.Paste")
			(net "FAN_6_TACH_IL_R2")
		)
		(pad "9" smd rect
			(at -0.249936 2.050034 90)
			(size 0.2794 0.9144)
			(layers "F.Cu" "F.Mask" "F.Paste")
			(net "GND")
		)
		(pad "10" smd rect
			(at 0.249936 2.050034 90)
			(size 0.2794 0.9144)
			(layers "F.Cu" "F.Mask" "F.Paste")
			(net "FAN_7_TACH_IL_R2")
		)
		(pad "11" smd rect
			(at 0.750062 2.050034 90)
			(size 0.2794 0.9144)
			(layers "F.Cu" "F.Mask" "F.Paste")
			(net "FAN_6_TACH_OL_R2")
		)
		(pad "12" smd rect
			(at 1.249934 2.050034 90)
			(size 0.2794 0.9144)
			(layers "F.Cu" "F.Mask" "F.Paste")
			(net "FAN_7_PWM_R2")
		)
		(pad "13" smd rect
			(at 2.050034 1.249934)
			(size 0.2794 0.9144)
			(layers "F.Cu" "F.Mask" "F.Paste")
			(net "FAN_7_TACH_OL_R2")
		)
		(pad "14" smd rect
			(at 2.050034 0.750062)
			(size 0.2794 0.9144)
			(layers "F.Cu" "F.Mask" "F.Paste")
			(net "NC_U404_P14")
		)
		(pad "15" smd rect
			(at 2.050034 0.249936)
			(size 0.2794 0.9144)
			(layers "F.Cu" "F.Mask" "F.Paste")
			(net "NC_U404_P15")
		)
		(pad "16" smd rect
			(at 2.050034 -0.249936)
			(size 0.2794 0.9144)
			(layers "F.Cu" "F.Mask" "F.Paste")
			(net "NC_U404_P16")
		)
		(pad "17" smd rect
			(at 2.050034 -0.750062)
			(size 0.2794 0.9144)
			(layers "F.Cu" "F.Mask" "F.Paste")
			(net "NC_U404_P17")
		)
		(pad "18" smd rect
			(at 2.050034 -1.249934)
			(size 0.2794 0.9144)
			(layers "F.Cu" "F.Mask" "F.Paste")
			(net "U404_ADD0")
		)
		(pad "19" smd rect
			(at 1.249934 -2.050034 90)
			(size 0.2794 0.9144)
			(layers "F.Cu" "F.Mask" "F.Paste")
			(net "SMB_PDBV_FAN_R_U404_SCL")
		)
		(pad "20" smd rect
			(at 0.750062 -2.050034 90)
			(size 0.2794 0.9144)
			(layers "F.Cu" "F.Mask" "F.Paste")
			(net "SMB_PDBV_FAN_R_U404_SDA")
		)
		(pad "21" smd rect
			(at 0.249936 -2.050034 90)
			(size 0.2794 0.9144)
			(layers "F.Cu" "F.Mask" "F.Paste")
			(net "P3V3_AUX")
		)
		(pad "22" smd rect
			(at -0.249936 -2.050034 90)
			(size 0.2794 0.9144)
			(layers "F.Cu" "F.Mask" "F.Paste")
			(net "NC_U404_P22")
		)
		(pad "23" smd rect
			(at -0.750062 -2.050034 90)
			(size 0.2794 0.9144)
			(layers "F.Cu" "F.Mask" "F.Paste")
			(net "U404_ADD1")
		)
		(pad "24" smd rect
			(at -1.249934 -2.050034 90)
			(size 0.2794 0.9144)
			(layers "F.Cu" "F.Mask" "F.Paste")
			(net "U404_ADD2")
		)
		(pad "TH" smd rect
			(at 0 0 90)
			(size 2.7686 2.7686)
			(layers "F.Cu" "F.Mask" "F.Paste")
			(net "GND")
		)
		(zone
			(layer "F.Cu")
			(hatch none 0.5)
			(connect_pads
				(clearance 0)
			)
			(min_thickness 0.25)
			(keepout
				(tracks not_allowed)
				(vias allowed)
				(pads allowed)
				(copperpour not_allowed)
				(footprints allowed)
			)
			(placement
				(enabled no)
				(sheetname "")
			)
			(fill
				(thermal_gap 0.5)
				(thermal_bridge_width 0.5)
				(island_removal_mode 0)
			)
			(polygon
				(pts
					(xy 10.033 -129.667) (xy 6.985 -129.667) (xy 6.985 -132.715) (xy 7.0612 -132.715) (xy 7.0612 -129.7432)
					(xy 9.9568 -129.7432) (xy 9.9568 -132.6388) (xy 7.0866 -132.6388) (xy 7.0866 -132.715) (xy 10.033 -132.715)
				)
			)
		)
	)
	(footprint ""
		(layer "F.Cu")
		(at 17.399 -207.137 180)
		(property "Reference" "U364"
			(at -0.508 -1.80467 0)
			(unlocked yes)
			(layer "F.SilkS")
			(effects
				(font
					(size 0.7874 0.5842)
					(thickness 0.1524)
				)
				(justify left)
			)
		)
		(property "Value" ""
			(at 0 0 180)
			(layer "F.Fab")
			(effects
				(font
					(size 1.27 1.27)
				)
			)
		)
		(duplicate_pad_numbers_are_jumpers no)
		(fp_line
			(start 1.335278 1.100074)
			(end 1.335278 -1.100074)
			(stroke
				(width 0.1524)
				(type default)
			)
			(layer "F.SilkS")
		)
		(fp_line
			(start 1.335278 -1.100074)
			(end -1.335278 -1.100074)
			(stroke
				(width 0.1524)
				(type default)
			)
			(layer "F.SilkS")
		)
		(fp_line
			(start -1.335278 1.100074)
			(end 1.335278 1.100074)
			(stroke
				(width 0.1524)
				(type default)
			)
			(layer "F.SilkS")
		)
		(fp_line
			(start -1.335278 -1.100074)
			(end -1.335278 1.100074)
			(stroke
				(width 0.1524)
				(type default)
			)
			(layer "F.SilkS")
		)
		(fp_line
			(start 0.674878 1.100074)
			(end 0.674878 -1.100074)
			(stroke
				(width 0.1)
				(type default)
			)
			(layer "F.Fab")
		)
		(fp_line
			(start 0.674878 -1.100074)
			(end -0.674878 -1.100074)
			(stroke
				(width 0.1)
				(type default)
			)
			(layer "F.Fab")
		)
		(fp_line
			(start -0.674878 1.100074)
			(end 0.674878 1.100074)
			(stroke
				(width 0.1)
				(type default)
			)
			(layer "F.Fab")
		)
		(fp_line
			(start -0.674878 -1.100074)
			(end -0.674878 1.100074)
			(stroke
				(width 0.1)
				(type default)
			)
			(layer "F.Fab")
		)
		(pad "D" smd rect
			(at 0.8001 0 90)
			(size 0.6096 0.8128)
			(layers "F.Cu" "F.Mask" "F.Paste")
			(net "FAN_6_OK_LED_R_N")
		)
		(pad "G" smd rect
			(at -0.8001 -0.649986 90)
			(size 0.6096 0.8128)
			(layers "F.Cu" "F.Mask" "F.Paste")
			(net "FAN_6_OK_R_LED")
		)
		(pad "S" smd rect
			(at -0.8001 0.649986 90)
			(size 0.6096 0.8128)
			(layers "F.Cu" "F.Mask" "F.Paste")
			(net "GND")
		)
	)
	(footprint ""
		(layer "F.Cu")
		(at 37.465 -304.165)
		(property "Reference" "R5184"
			(at 0 0 0)
			(layer "F.SilkS")
			(hide yes)
			(effects
				(font
					(size 1.27 1.27)
				)
			)
		)
		(property "Value" ""
			(at 0 0 0)
			(layer "F.Fab")
			(effects
				(font
					(size 1.27 1.27)
				)
			)
		)
		(duplicate_pad_numbers_are_jumpers no)
		(fp_line
			(start -0.7874 -0.4064)
			(end 0.7874 -0.4064)
			(stroke
				(width 0.1524)
				(type default)
			)
			(layer "F.SilkS")
		)
		(fp_line
			(start -0.7874 0.4064)
			(end -0.7874 -0.4064)
			(stroke
				(width 0.1524)
				(type default)
			)
			(layer "F.SilkS")
		)
		(fp_line
			(start 0.7874 -0.4064)
			(end 0.7874 0.4064)
			(stroke
				(width 0.1524)
				(type default)
			)
			(layer "F.SilkS")
		)
		(fp_line
			(start 0.7874 0.4064)
			(end -0.7874 0.4064)
			(stroke
				(width 0.1524)
				(type default)
			)
			(layer "F.SilkS")
		)
		(fp_line
			(start -0.67945 -0.305054)
			(end -0.12065 -0.305054)
			(stroke
				(width 0.1)
				(type default)
			)
			(layer "F.Fab")
		)
		(fp_line
			(start -0.67945 0.3048)
			(end -0.67945 -0.305054)
			(stroke
				(width 0.1)
				(type default)
			)
			(layer "F.Fab")
		)
		(fp_line
			(start -0.12065 -0.305054)
			(end -0.12065 -0.2794)
			(stroke
				(width 0.1)
				(type default)
			)
			(layer "F.Fab")
		)
		(fp_line
			(start -0.12065 -0.2794)
			(end 0.12065 -0.2794)
			(stroke
				(width 0.1)
				(type default)
			)
			(layer "F.Fab")
		)
		(fp_line
			(start -0.12065 0.2794)
			(end -0.12065 0.3048)
			(stroke
				(width 0.1)
				(type default)
			)
			(layer "F.Fab")
		)
		(fp_line
			(start -0.12065 0.3048)
			(end -0.67945 0.3048)
			(stroke
				(width 0.1)
				(type default)
			)
			(layer "F.Fab")
		)
		(fp_line
			(start 0.120396 0.2794)
			(end -0.12065 0.2794)
			(stroke
				(width 0.1)
				(type default)
			)
			(layer "F.Fab")
		)
		(fp_line
			(start 0.120396 0.3048)
			(end 0.120396 0.2794)
			(stroke
				(width 0.1)
				(type default)
			)
			(layer "F.Fab")
		)
		(fp_line
			(start 0.12065 -0.3048)
			(end 0.67945 -0.3048)
			(stroke
				(width 0.1)
				(type default)
			)
			(layer "F.Fab")
		)
		(fp_line
			(start 0.12065 -0.2794)
			(end 0.12065 -0.3048)
			(stroke
				(width 0.1)
				(type default)
			)
			(layer "F.Fab")
		)
		(fp_line
			(start 0.67945 -0.3048)
			(end 0.67945 0.3048)
			(stroke
				(width 0.1)
				(type default)
			)
			(layer "F.Fab")
		)
		(fp_line
			(start 0.67945 0.3048)
			(end 0.120396 0.3048)
			(stroke
				(width 0.1)
				(type default)
			)
			(layer "F.Fab")
		)
		(pad "1" smd circle
			(at -0.40005 0)
			(size 0 0)
			(layers "F.Cu" "F.Mask" "F.Paste")
			(net "FAN_0_PWM_OL")
		)
		(pad "2" smd circle
			(at 0.40005 0)
			(size 0 0)
			(layers "F.Cu" "F.Mask" "F.Paste")
			(net "FAN_0_PWM_OL_R")
		)
	)
	(footprint ""
		(layer "F.Cu")
		(at 40.132 -4.445)
		(property "Reference" ""
			(at 0 0 0)
			(layer "F.SilkS")
			(hide yes)
			(effects
				(font
					(size 1.27 1.27)
				)
			)
		)
		(property "Value" ""
			(at 0 0 0)
			(layer "F.Fab")
			(effects
				(font
					(size 1.27 1.27)
				)
			)
		)
		(duplicate_pad_numbers_are_jumpers no)
		(pad "1" smd circle
			(at 0 0)
			(size 0.9906 0.9906)
			(layers "F.Cu" "F.Mask" "F.Paste")
			(net "Net_126")
		)
		(zone
			(layer "F.Cu")
			(hatch none 0.5)
			(connect_pads
				(clearance 0)
			)
			(min_thickness 0.25)
			(keepout
				(tracks not_allowed)
				(vias allowed)
				(pads allowed)
				(copperpour not_allowed)
				(footprints allowed)
			)
			(placement
				(enabled no)
				(sheetname "")
			)
			(fill
				(thermal_gap 0.5)
				(thermal_bridge_width 0.5)
				(island_removal_mode 0)
			)
			(polygon
				(pts
					(arc
						(start 41.7576 -4.445)
						(mid 38.5064 -4.445)
						(end 41.7576 -4.445)
					)
				)
			)
		)
	)
	(footprint ""
		(layer "F.Cu")
		(at 16.891 -205.105 180)
		(property "Reference" "R5535"
			(at 0 0 180)
			(layer "F.SilkS")
			(hide yes)
			(effects
				(font
					(size 1.27 1.27)
				)
			)
		)
		(property "Value" ""
			(at 0 0 180)
			(layer "F.Fab")
			(effects
				(font
					(size 1.27 1.27)
				)
			)
		)
		(duplicate_pad_numbers_are_jumpers no)
		(fp_line
			(start 0.7874 0.4064)
			(end -0.7874 0.4064)
			(stroke
				(width 0.1524)
				(type default)
			)
			(layer "F.SilkS")
		)
		(fp_line
			(start 0.7874 -0.4064)
			(end 0.7874 0.4064)
			(stroke
				(width 0.1524)
				(type default)
			)
			(layer "F.SilkS")
		)
		(fp_line
			(start -0.7874 0.4064)
			(end -0.7874 -0.4064)
			(stroke
				(width 0.1524)
				(type default)
			)
			(layer "F.SilkS")
		)
		(fp_line
			(start -0.7874 -0.4064)
			(end 0.7874 -0.4064)
			(stroke
				(width 0.1524)
				(type default)
			)
			(layer "F.SilkS")
		)
		(fp_line
			(start 0.67945 0.3048)
			(end 0.120396 0.3048)
			(stroke
				(width 0.1)
				(type default)
			)
			(layer "F.Fab")
		)
		(fp_line
			(start 0.67945 -0.3048)
			(end 0.67945 0.3048)
			(stroke
				(width 0.1)
				(type default)
			)
			(layer "F.Fab")
		)
		(fp_line
			(start 0.12065 -0.2794)
			(end 0.12065 -0.3048)
			(stroke
				(width 0.1)
				(type default)
			)
			(layer "F.Fab")
		)
		(fp_line
			(start 0.12065 -0.3048)
			(end 0.67945 -0.3048)
			(stroke
				(width 0.1)
				(type default)
			)
			(layer "F.Fab")
		)
		(fp_line
			(start 0.120396 0.3048)
			(end 0.120396 0.2794)
			(stroke
				(width 0.1)
				(type default)
			)
			(layer "F.Fab")
		)
		(fp_line
			(start 0.120396 0.2794)
			(end -0.12065 0.2794)
			(stroke
				(width 0.1)
				(type default)
			)
			(layer "F.Fab")
		)
		(fp_line
			(start -0.12065 0.3048)
			(end -0.67945 0.3048)
			(stroke
				(width 0.1)
				(type default)
			)
			(layer "F.Fab")
		)
		(fp_line
			(start -0.12065 0.2794)
			(end -0.12065 0.3048)
			(stroke
				(width 0.1)
				(type default)
			)
			(layer "F.Fab")
		)
		(fp_line
			(start -0.12065 -0.2794)
			(end 0.12065 -0.2794)
			(stroke
				(width 0.1)
				(type default)
			)
			(layer "F.Fab")
		)
		(fp_line
			(start -0.12065 -0.305054)
			(end -0.12065 -0.2794)
			(stroke
				(width 0.1)
				(type default)
			)
			(layer "F.Fab")
		)
		(fp_line
			(start -0.67945 0.3048)
			(end -0.67945 -0.305054)
			(stroke
				(width 0.1)
				(type default)
			)
			(layer "F.Fab")
		)
		(fp_line
			(start -0.67945 -0.305054)
			(end -0.12065 -0.305054)
			(stroke
				(width 0.1)
				(type default)
			)
			(layer "F.Fab")
		)
		(pad "1" smd rect
			(at -0.40005 0)
			(size 0.4572 0.508)
			(layers "F.Cu" "F.Mask" "F.Paste")
			(net "P12V_LED_FAN6")
		)
		(pad "2" smd rect
			(at 0.40005 0)
			(size 0.4572 0.508)
			(layers "F.Cu" "F.Mask" "F.Paste")
			(net "FAN_6_FAIL_LED_R_N")
		)
	)
	(footprint ""
		(layer "F.Cu")
		(at 21.717 -28.194 90)
		(property "Reference" "C2089"
			(at 0 0 90)
			(layer "F.SilkS")
			(hide yes)
			(effects
				(font
					(size 1.27 1.27)
				)
			)
		)
		(property "Value" ""
			(at 0 0 90)
			(layer "F.Fab")
			(effects
				(font
					(size 1.27 1.27)
				)
			)
		)
		(duplicate_pad_numbers_are_jumpers no)
		(fp_line
			(start 0.7874 -0.4064)
			(end 0.7874 0.4064)
			(stroke
				(width 0.1524)
				(type default)
			)
			(layer "F.SilkS")
		)
		(fp_line
			(start -0.7874 -0.4064)
			(end 0.7874 -0.4064)
			(stroke
				(width 0.1524)
				(type default)
			)
			(layer "F.SilkS")
		)
		(fp_line
			(start 0.7874 0.4064)
			(end -0.7874 0.4064)
			(stroke
				(width 0.1524)
				(type default)
			)
			(layer "F.SilkS")
		)
		(fp_line
			(start -0.7874 0.4064)
			(end -0.7874 -0.4064)
			(stroke
				(width 0.1524)
				(type default)
			)
			(layer "F.SilkS")
		)
		(fp_line
			(start -0.12065 -0.305054)
			(end -0.12065 -0.2794)
			(stroke
				(width 0.1)
				(type default)
			)
			(layer "F.Fab")
		)
		(fp_line
			(start -0.67945 -0.305054)
			(end -0.12065 -0.305054)
			(stroke
				(width 0.1)
				(type default)
			)
			(layer "F.Fab")
		)
		(fp_line
			(start 0.67945 -0.3048)
			(end 0.67945 0.3048)
			(stroke
				(width 0.1)
				(type default)
			)
			(layer "F.Fab")
		)
		(fp_line
			(start 0.12065 -0.3048)
			(end 0.67945 -0.3048)
			(stroke
				(width 0.1)
				(type default)
			)
			(layer "F.Fab")
		)
		(fp_line
			(start 0.12065 -0.2794)
			(end 0.12065 -0.3048)
			(stroke
				(width 0.1)
				(type default)
			)
			(layer "F.Fab")
		)
		(fp_line
			(start -0.12065 -0.2794)
			(end 0.12065 -0.2794)
			(stroke
				(width 0.1)
				(type default)
			)
			(layer "F.Fab")
		)
		(fp_line
			(start 0.120396 0.2794)
			(end -0.12065 0.2794)
			(stroke
				(width 0.1)
				(type default)
			)
			(layer "F.Fab")
		)
		(fp_line
			(start -0.12065 0.2794)
			(end -0.12065 0.3048)
			(stroke
				(width 0.1)
				(type default)
			)
			(layer "F.Fab")
		)
		(fp_line
			(start 0.67945 0.3048)
			(end 0.120396 0.3048)
			(stroke
				(width 0.1)
				(type default)
			)
			(layer "F.Fab")
		)
		(fp_line
			(start 0.120396 0.3048)
			(end 0.120396 0.2794)
			(stroke
				(width 0.1)
				(type default)
			)
			(layer "F.Fab")
		)
		(fp_line
			(start -0.12065 0.3048)
			(end -0.67945 0.3048)
			(stroke
				(width 0.1)
				(type default)
			)
			(layer "F.Fab")
		)
		(fp_line
			(start -0.67945 0.3048)
			(end -0.67945 -0.305054)
			(stroke
				(width 0.1)
				(type default)
			)
			(layer "F.Fab")
		)
		(pad "1" smd circle
			(at -0.40005 0 90)
			(size 0 0)
			(layers "F.Cu" "F.Mask" "F.Paste")
			(net "P3V3_AUX")
		)
		(pad "2" smd circle
			(at 0.40005 0 90)
			(size 0 0)
			(layers "F.Cu" "F.Mask" "F.Paste")
			(net "GND")
		)
	)
	(footprint ""
		(layer "F.Cu")
		(at 48.768 -31.623 180)
		(property "Reference" "R5695"
			(at 0 0 180)
			(layer "F.SilkS")
			(hide yes)
			(effects
				(font
					(size 1.27 1.27)
				)
			)
		)
		(property "Value" ""
			(at 0 0 180)
			(layer "F.Fab")
			(effects
				(font
					(size 1.27 1.27)
				)
			)
		)
		(duplicate_pad_numbers_are_jumpers no)
		(fp_line
			(start 0.7874 0.4064)
			(end -0.7874 0.4064)
			(stroke
				(width 0.1524)
				(type default)
			)
			(layer "F.SilkS")
		)
		(fp_line
			(start 0.7874 -0.4064)
			(end 0.7874 0.4064)
			(stroke
				(width 0.1524)
				(type default)
			)
			(layer "F.SilkS")
		)
		(fp_line
			(start -0.7874 0.4064)
			(end -0.7874 -0.4064)
			(stroke
				(width 0.1524)
				(type default)
			)
			(layer "F.SilkS")
		)
		(fp_line
			(start -0.7874 -0.4064)
			(end 0.7874 -0.4064)
			(stroke
				(width 0.1524)
				(type default)
			)
			(layer "F.SilkS")
		)
		(fp_line
			(start 0.67945 0.3048)
			(end 0.120396 0.3048)
			(stroke
				(width 0.1)
				(type default)
			)
			(layer "F.Fab")
		)
		(fp_line
			(start 0.67945 -0.3048)
			(end 0.67945 0.3048)
			(stroke
				(width 0.1)
				(type default)
			)
			(layer "F.Fab")
		)
		(fp_line
			(start 0.12065 -0.2794)
			(end 0.12065 -0.3048)
			(stroke
				(width 0.1)
				(type default)
			)
			(layer "F.Fab")
		)
		(fp_line
			(start 0.12065 -0.3048)
			(end 0.67945 -0.3048)
			(stroke
				(width 0.1)
				(type default)
			)
			(layer "F.Fab")
		)
		(fp_line
			(start 0.120396 0.3048)
			(end 0.120396 0.2794)
			(stroke
				(width 0.1)
				(type default)
			)
			(layer "F.Fab")
		)
		(fp_line
			(start 0.120396 0.2794)
			(end -0.12065 0.2794)
			(stroke
				(width 0.1)
				(type default)
			)
			(layer "F.Fab")
		)
		(fp_line
			(start -0.12065 0.3048)
			(end -0.67945 0.3048)
			(stroke
				(width 0.1)
				(type default)
			)
			(layer "F.Fab")
		)
		(fp_line
			(start -0.12065 0.2794)
			(end -0.12065 0.3048)
			(stroke
				(width 0.1)
				(type default)
			)
			(layer "F.Fab")
		)
		(fp_line
			(start -0.12065 -0.2794)
			(end 0.12065 -0.2794)
			(stroke
				(width 0.1)
				(type default)
			)
			(layer "F.Fab")
		)
		(fp_line
			(start -0.12065 -0.305054)
			(end -0.12065 -0.2794)
			(stroke
				(width 0.1)
				(type default)
			)
			(layer "F.Fab")
		)
		(fp_line
			(start -0.67945 0.3048)
			(end -0.67945 -0.305054)
			(stroke
				(width 0.1)
				(type default)
			)
			(layer "F.Fab")
		)
		(fp_line
			(start -0.67945 -0.305054)
			(end -0.12065 -0.305054)
			(stroke
				(width 0.1)
				(type default)
			)
			(layer "F.Fab")
		)
		(pad "1" smd rect
			(at -0.40005 0)
			(size 0.4572 0.508)
			(layers "F.Cu" "F.Mask" "F.Paste")
			(net "P12V_LED_FAN3")
		)
		(pad "2" smd rect
			(at 0.40005 0)
			(size 0.4572 0.508)
			(layers "F.Cu" "F.Mask" "F.Paste")
			(net "P12V_LED_R_FAN3")
		)
	)
	(footprint ""
		(layer "F.Cu")
		(at 29.083 -199.898 -90)
		(property "Reference" "R5521"
			(at 0 0 270)
			(layer "F.SilkS")
			(hide yes)
			(effects
				(font
					(size 1.27 1.27)
				)
			)
		)
		(property "Value" ""
			(at 0 0 270)
			(layer "F.Fab")
			(effects
				(font
					(size 1.27 1.27)
				)
			)
		)
		(duplicate_pad_numbers_are_jumpers no)
		(fp_line
			(start -0.7874 0.4064)
			(end -0.7874 -0.4064)
			(stroke
				(width 0.1524)
				(type default)
			)
			(layer "F.SilkS")
		)
		(fp_line
			(start 0.7874 0.4064)
			(end -0.7874 0.4064)
			(stroke
				(width 0.1524)
				(type default)
			)
			(layer "F.SilkS")
		)
		(fp_line
			(start -0.7874 -0.4064)
			(end 0.7874 -0.4064)
			(stroke
				(width 0.1524)
				(type default)
			)
			(layer "F.SilkS")
		)
		(fp_line
			(start 0.7874 -0.4064)
			(end 0.7874 0.4064)
			(stroke
				(width 0.1524)
				(type default)
			)
			(layer "F.SilkS")
		)
		(fp_line
			(start -0.67945 0.3048)
			(end -0.67945 -0.305054)
			(stroke
				(width 0.1)
				(type default)
			)
			(layer "F.Fab")
		)
		(fp_line
			(start -0.12065 0.3048)
			(end -0.67945 0.3048)
			(stroke
				(width 0.1)
				(type default)
			)
			(layer "F.Fab")
		)
		(fp_line
			(start 0.120396 0.3048)
			(end 0.120396 0.2794)
			(stroke
				(width 0.1)
				(type default)
			)
			(layer "F.Fab")
		)
		(fp_line
			(start 0.67945 0.3048)
			(end 0.120396 0.3048)
			(stroke
				(width 0.1)
				(type default)
			)
			(layer "F.Fab")
		)
		(fp_line
			(start -0.12065 0.2794)
			(end -0.12065 0.3048)
			(stroke
				(width 0.1)
				(type default)
			)
			(layer "F.Fab")
		)
		(fp_line
			(start 0.120396 0.2794)
			(end -0.12065 0.2794)
			(stroke
				(width 0.1)
				(type default)
			)
			(layer "F.Fab")
		)
		(fp_line
			(start -0.12065 -0.2794)
			(end 0.12065 -0.2794)
			(stroke
				(width 0.1)
				(type default)
			)
			(layer "F.Fab")
		)
		(fp_line
			(start 0.12065 -0.2794)
			(end 0.12065 -0.3048)
			(stroke
				(width 0.1)
				(type default)
			)
			(layer "F.Fab")
		)
		(fp_line
			(start 0.12065 -0.3048)
			(end 0.67945 -0.3048)
			(stroke
				(width 0.1)
				(type default)
			)
			(layer "F.Fab")
		)
		(fp_line
			(start 0.67945 -0.3048)
			(end 0.67945 0.3048)
			(stroke
				(width 0.1)
				(type default)
			)
			(layer "F.Fab")
		)
		(fp_line
			(start -0.67945 -0.305054)
			(end -0.12065 -0.305054)
			(stroke
				(width 0.1)
				(type default)
			)
			(layer "F.Fab")
		)
		(fp_line
			(start -0.12065 -0.305054)
			(end -0.12065 -0.2794)
			(stroke
				(width 0.1)
				(type default)
			)
			(layer "F.Fab")
		)
		(pad "1" smd circle
			(at -0.40005 0 270)
			(size 0 0)
			(layers "F.Cu" "F.Mask" "F.Paste")
			(net "P3V3_AUX")
		)
		(pad "2" smd circle
			(at 0.40005 0 270)
			(size 0 0)
			(layers "F.Cu" "F.Mask" "F.Paste")
			(net "FAN_6_PWM")
		)
	)
	(footprint ""
		(layer "F.Cu")
		(at 27.305 -30.734 180)
		(property "Reference" "C2123"
			(at 0 0 180)
			(layer "F.SilkS")
			(hide yes)
			(effects
				(font
					(size 1.27 1.27)
				)
			)
		)
		(property "Value" ""
			(at 0 0 180)
			(layer "F.Fab")
			(effects
				(font
					(size 1.27 1.27)
				)
			)
		)
		(duplicate_pad_numbers_are_jumpers no)
		(fp_line
			(start 1.2954 0.5842)
			(end -1.2954 0.5842)
			(stroke
				(width 0.1524)
				(type default)
			)
			(layer "F.SilkS")
		)
		(fp_line
			(start 1.2954 -0.5842)
			(end 1.2954 0.5842)
			(stroke
				(width 0.1524)
				(type default)
			)
			(layer "F.SilkS")
		)
		(fp_line
			(start -1.2954 0.5842)
			(end -1.2954 -0.5842)
			(stroke
				(width 0.1524)
				(type default)
			)
			(layer "F.SilkS")
		)
		(fp_line
			(start -1.2954 -0.5842)
			(end 1.2954 -0.5842)
			(stroke
				(width 0.1524)
				(type default)
			)
			(layer "F.SilkS")
		)
		(fp_line
			(start 1.1938 0.4064)
			(end 0.8636 0.4064)
			(stroke
				(width 0.1)
				(type default)
			)
			(layer "F.Fab")
		)
		(fp_line
			(start 1.1938 -0.4064)
			(end 1.1938 0.4064)
			(stroke
				(width 0.1)
				(type default)
			)
			(layer "F.Fab")
		)
		(fp_line
			(start 0.8636 0.4572)
			(end -0.8636 0.4572)
			(stroke
				(width 0.1)
				(type default)
			)
			(layer "F.Fab")
		)
		(fp_line
			(start 0.8636 0.4064)
			(end 0.8636 0.4572)
			(stroke
				(width 0.1)
				(type default)
			)
			(layer "F.Fab")
		)
		(fp_line
			(start 0.8636 -0.4064)
			(end 1.1938 -0.4064)
			(stroke
				(width 0.1)
				(type default)
			)
			(layer "F.Fab")
		)
		(fp_line
			(start 0.8636 -0.4572)
			(end 0.8636 -0.4064)
			(stroke
				(width 0.1)
				(type default)
			)
			(layer "F.Fab")
		)
		(fp_line
			(start -0.8636 0.4572)
			(end -0.8636 0.4064)
			(stroke
				(width 0.1)
				(type default)
			)
			(layer "F.Fab")
		)
		(fp_line
			(start -0.8636 0.4064)
			(end -1.1938 0.4064)
			(stroke
				(width 0.1)
				(type default)
			)
			(layer "F.Fab")
		)
		(fp_line
			(start -0.8636 -0.4064)
			(end -0.8636 -0.4572)
			(stroke
				(width 0.1)
				(type default)
			)
			(layer "F.Fab")
		)
		(fp_line
			(start -0.8636 -0.4572)
			(end 0.8636 -0.4572)
			(stroke
				(width 0.1)
				(type default)
			)
			(layer "F.Fab")
		)
		(fp_line
			(start -1.1938 0.4064)
			(end -1.1938 -0.4064)
			(stroke
				(width 0.1)
				(type default)
			)
			(layer "F.Fab")
		)
		(fp_line
			(start -1.1938 -0.4064)
			(end -0.8636 -0.4064)
			(stroke
				(width 0.1)
				(type default)
			)
			(layer "F.Fab")
		)
		(pad "1" smd rect
			(at -0.7366 0 90)
			(size 0.7112 0.8128)
			(layers "F.Cu" "F.Mask" "F.Paste")
			(net "U408_D1")
		)
		(pad "2" smd rect
			(at 0.7366 0 90)
			(size 0.7112 0.8128)
			(layers "F.Cu" "F.Mask" "F.Paste")
			(net "GND")
		)
	)
	(footprint ""
		(layer "F.Cu")
		(at 3.429 -123.698)
		(property "Reference" "R5701"
			(at 0 0 0)
			(layer "F.SilkS")
			(hide yes)
			(effects
				(font
					(size 1.27 1.27)
				)
			)
		)
		(property "Value" ""
			(at 0 0 0)
			(layer "F.Fab")
			(effects
				(font
					(size 1.27 1.27)
				)
			)
		)
		(duplicate_pad_numbers_are_jumpers no)
		(fp_line
			(start -0.7874 -0.4064)
			(end 0.7874 -0.4064)
			(stroke
				(width 0.1524)
				(type default)
			)
			(layer "F.SilkS")
		)
		(fp_line
			(start -0.7874 0.4064)
			(end -0.7874 -0.4064)
			(stroke
				(width 0.1524)
				(type default)
			)
			(layer "F.SilkS")
		)
		(fp_line
			(start 0.7874 -0.4064)
			(end 0.7874 0.4064)
			(stroke
				(width 0.1524)
				(type default)
			)
			(layer "F.SilkS")
		)
		(fp_line
			(start 0.7874 0.4064)
			(end -0.7874 0.4064)
			(stroke
				(width 0.1524)
				(type default)
			)
			(layer "F.SilkS")
		)
		(fp_line
			(start -0.67945 -0.305054)
			(end -0.12065 -0.305054)
			(stroke
				(width 0.1)
				(type default)
			)
			(layer "F.Fab")
		)
		(fp_line
			(start -0.67945 0.3048)
			(end -0.67945 -0.305054)
			(stroke
				(width 0.1)
				(type default)
			)
			(layer "F.Fab")
		)
		(fp_line
			(start -0.12065 -0.305054)
			(end -0.12065 -0.2794)
			(stroke
				(width 0.1)
				(type default)
			)
			(layer "F.Fab")
		)
		(fp_line
			(start -0.12065 -0.2794)
			(end 0.12065 -0.2794)
			(stroke
				(width 0.1)
				(type default)
			)
			(layer "F.Fab")
		)
		(fp_line
			(start -0.12065 0.2794)
			(end -0.12065 0.3048)
			(stroke
				(width 0.1)
				(type default)
			)
			(layer "F.Fab")
		)
		(fp_line
			(start -0.12065 0.3048)
			(end -0.67945 0.3048)
			(stroke
				(width 0.1)
				(type default)
			)
			(layer "F.Fab")
		)
		(fp_line
			(start 0.120396 0.2794)
			(end -0.12065 0.2794)
			(stroke
				(width 0.1)
				(type default)
			)
			(layer "F.Fab")
		)
		(fp_line
			(start 0.120396 0.3048)
			(end 0.120396 0.2794)
			(stroke
				(width 0.1)
				(type default)
			)
			(layer "F.Fab")
		)
		(fp_line
			(start 0.12065 -0.3048)
			(end 0.67945 -0.3048)
			(stroke
				(width 0.1)
				(type default)
			)
			(layer "F.Fab")
		)
		(fp_line
			(start 0.12065 -0.2794)
			(end 0.12065 -0.3048)
			(stroke
				(width 0.1)
				(type default)
			)
			(layer "F.Fab")
		)
		(fp_line
			(start 0.67945 -0.3048)
			(end 0.67945 0.3048)
			(stroke
				(width 0.1)
				(type default)
			)
			(layer "F.Fab")
		)
		(fp_line
			(start 0.67945 0.3048)
			(end 0.120396 0.3048)
			(stroke
				(width 0.1)
				(type default)
			)
			(layer "F.Fab")
		)
		(pad "1" smd rect
			(at -0.40005 0 180)
			(size 0.4572 0.508)
			(layers "F.Cu" "F.Mask" "F.Paste")
			(net "P12V_LED_FAN5")
		)
		(pad "2" smd rect
			(at 0.40005 0 180)
			(size 0.4572 0.508)
			(layers "F.Cu" "F.Mask" "F.Paste")
			(net "P12V_LED_R_FAN5")
		)
	)
	(footprint ""
		(layer "F.Cu")
		(at 22.225 -136.017 -90)
		(property "Reference" "R4951"
			(at 0 0 270)
			(layer "F.SilkS")
			(hide yes)
			(effects
				(font
					(size 1.27 1.27)
				)
			)
		)
		(property "Value" ""
			(at 0 0 270)
			(layer "F.Fab")
			(effects
				(font
					(size 1.27 1.27)
				)
			)
		)
		(duplicate_pad_numbers_are_jumpers no)
		(fp_line
			(start -0.7874 0.4064)
			(end -0.7874 -0.4064)
			(stroke
				(width 0.1524)
				(type default)
			)
			(layer "F.SilkS")
		)
		(fp_line
			(start 0.7874 0.4064)
			(end -0.7874 0.4064)
			(stroke
				(width 0.1524)
				(type default)
			)
			(layer "F.SilkS")
		)
		(fp_line
			(start -0.7874 -0.4064)
			(end 0.7874 -0.4064)
			(stroke
				(width 0.1524)
				(type default)
			)
			(layer "F.SilkS")
		)
		(fp_line
			(start 0.7874 -0.4064)
			(end 0.7874 0.4064)
			(stroke
				(width 0.1524)
				(type default)
			)
			(layer "F.SilkS")
		)
		(fp_line
			(start -0.67945 0.3048)
			(end -0.67945 -0.305054)
			(stroke
				(width 0.1)
				(type default)
			)
			(layer "F.Fab")
		)
		(fp_line
			(start -0.12065 0.3048)
			(end -0.67945 0.3048)
			(stroke
				(width 0.1)
				(type default)
			)
			(layer "F.Fab")
		)
		(fp_line
			(start 0.120396 0.3048)
			(end 0.120396 0.2794)
			(stroke
				(width 0.1)
				(type default)
			)
			(layer "F.Fab")
		)
		(fp_line
			(start 0.67945 0.3048)
			(end 0.120396 0.3048)
			(stroke
				(width 0.1)
				(type default)
			)
			(layer "F.Fab")
		)
		(fp_line
			(start -0.12065 0.2794)
			(end -0.12065 0.3048)
			(stroke
				(width 0.1)
				(type default)
			)
			(layer "F.Fab")
		)
		(fp_line
			(start 0.120396 0.2794)
			(end -0.12065 0.2794)
			(stroke
				(width 0.1)
				(type default)
			)
			(layer "F.Fab")
		)
		(fp_line
			(start -0.12065 -0.2794)
			(end 0.12065 -0.2794)
			(stroke
				(width 0.1)
				(type default)
			)
			(layer "F.Fab")
		)
		(fp_line
			(start 0.12065 -0.2794)
			(end 0.12065 -0.3048)
			(stroke
				(width 0.1)
				(type default)
			)
			(layer "F.Fab")
		)
		(fp_line
			(start 0.12065 -0.3048)
			(end 0.67945 -0.3048)
			(stroke
				(width 0.1)
				(type default)
			)
			(layer "F.Fab")
		)
		(fp_line
			(start 0.67945 -0.3048)
			(end 0.67945 0.3048)
			(stroke
				(width 0.1)
				(type default)
			)
			(layer "F.Fab")
		)
		(fp_line
			(start -0.67945 -0.305054)
			(end -0.12065 -0.305054)
			(stroke
				(width 0.1)
				(type default)
			)
			(layer "F.Fab")
		)
		(fp_line
			(start -0.12065 -0.305054)
			(end -0.12065 -0.2794)
			(stroke
				(width 0.1)
				(type default)
			)
			(layer "F.Fab")
		)
		(pad "1" smd circle
			(at -0.40005 0 270)
			(size 0 0)
			(layers "F.Cu" "F.Mask" "F.Paste")
			(net "GND")
		)
		(pad "2" smd circle
			(at 0.40005 0 270)
			(size 0 0)
			(layers "F.Cu" "F.Mask" "F.Paste")
			(net "MAX31790_U330_SPIN_START")
		)
	)
	(footprint ""
		(layer "F.Cu")
		(at 39.206932 -70.542912 180)
		(property "Reference" "R5421"
			(at 0 0 180)
			(layer "F.SilkS")
			(hide yes)
			(effects
				(font
					(size 1.27 1.27)
				)
			)
		)
		(property "Value" ""
			(at 0 0 180)
			(layer "F.Fab")
			(effects
				(font
					(size 1.27 1.27)
				)
			)
		)
		(duplicate_pad_numbers_are_jumpers no)
		(fp_line
			(start 0.7874 0.4064)
			(end -0.7874 0.4064)
			(stroke
				(width 0.1524)
				(type default)
			)
			(layer "F.SilkS")
		)
		(fp_line
			(start 0.7874 -0.4064)
			(end 0.7874 0.4064)
			(stroke
				(width 0.1524)
				(type default)
			)
			(layer "F.SilkS")
		)
		(fp_line
			(start -0.7874 0.4064)
			(end -0.7874 -0.4064)
			(stroke
				(width 0.1524)
				(type default)
			)
			(layer "F.SilkS")
		)
		(fp_line
			(start -0.7874 -0.4064)
			(end 0.7874 -0.4064)
			(stroke
				(width 0.1524)
				(type default)
			)
			(layer "F.SilkS")
		)
		(fp_line
			(start 0.67945 0.3048)
			(end 0.120396 0.3048)
			(stroke
				(width 0.1)
				(type default)
			)
			(layer "F.Fab")
		)
		(fp_line
			(start 0.67945 -0.3048)
			(end 0.67945 0.3048)
			(stroke
				(width 0.1)
				(type default)
			)
			(layer "F.Fab")
		)
		(fp_line
			(start 0.12065 -0.2794)
			(end 0.12065 -0.3048)
			(stroke
				(width 0.1)
				(type default)
			)
			(layer "F.Fab")
		)
		(fp_line
			(start 0.12065 -0.3048)
			(end 0.67945 -0.3048)
			(stroke
				(width 0.1)
				(type default)
			)
			(layer "F.Fab")
		)
		(fp_line
			(start 0.120396 0.3048)
			(end 0.120396 0.2794)
			(stroke
				(width 0.1)
				(type default)
			)
			(layer "F.Fab")
		)
		(fp_line
			(start 0.120396 0.2794)
			(end -0.12065 0.2794)
			(stroke
				(width 0.1)
				(type default)
			)
			(layer "F.Fab")
		)
		(fp_line
			(start -0.12065 0.3048)
			(end -0.67945 0.3048)
			(stroke
				(width 0.1)
				(type default)
			)
			(layer "F.Fab")
		)
		(fp_line
			(start -0.12065 0.2794)
			(end -0.12065 0.3048)
			(stroke
				(width 0.1)
				(type default)
			)
			(layer "F.Fab")
		)
		(fp_line
			(start -0.12065 -0.2794)
			(end 0.12065 -0.2794)
			(stroke
				(width 0.1)
				(type default)
			)
			(layer "F.Fab")
		)
		(fp_line
			(start -0.12065 -0.305054)
			(end -0.12065 -0.2794)
			(stroke
				(width 0.1)
				(type default)
			)
			(layer "F.Fab")
		)
		(fp_line
			(start -0.67945 0.3048)
			(end -0.67945 -0.305054)
			(stroke
				(width 0.1)
				(type default)
			)
			(layer "F.Fab")
		)
		(fp_line
			(start -0.67945 -0.305054)
			(end -0.12065 -0.305054)
			(stroke
				(width 0.1)
				(type default)
			)
			(layer "F.Fab")
		)
		(pad "1" smd circle
			(at -0.40005 0 180)
			(size 0 0)
			(layers "F.Cu" "F.Mask" "F.Paste")
			(net "FAN_2_ON")
		)
		(pad "2" smd circle
			(at 0.40005 0 180)
			(size 0 0)
			(layers "F.Cu" "F.Mask" "F.Paste")
			(net "P52V_FAN_2_EN")
		)
	)
	(footprint ""
		(layer "F.Cu")
		(at 14.351 -200.180956 180)
		(property "Reference" "R5223"
			(at 0 0 180)
			(layer "F.SilkS")
			(hide yes)
			(effects
				(font
					(size 1.27 1.27)
				)
			)
		)
		(property "Value" ""
			(at 0 0 180)
			(layer "F.Fab")
			(effects
				(font
					(size 1.27 1.27)
				)
			)
		)
		(duplicate_pad_numbers_are_jumpers no)
		(fp_line
			(start 0.7874 0.4064)
			(end -0.7874 0.4064)
			(stroke
				(width 0.1524)
				(type default)
			)
			(layer "F.SilkS")
		)
		(fp_line
			(start 0.7874 -0.4064)
			(end 0.7874 0.4064)
			(stroke
				(width 0.1524)
				(type default)
			)
			(layer "F.SilkS")
		)
		(fp_line
			(start -0.7874 0.4064)
			(end -0.7874 -0.4064)
			(stroke
				(width 0.1524)
				(type default)
			)
			(layer "F.SilkS")
		)
		(fp_line
			(start -0.7874 -0.4064)
			(end 0.7874 -0.4064)
			(stroke
				(width 0.1524)
				(type default)
			)
			(layer "F.SilkS")
		)
		(fp_line
			(start 0.67945 0.3048)
			(end 0.120396 0.3048)
			(stroke
				(width 0.1)
				(type default)
			)
			(layer "F.Fab")
		)
		(fp_line
			(start 0.67945 -0.3048)
			(end 0.67945 0.3048)
			(stroke
				(width 0.1)
				(type default)
			)
			(layer "F.Fab")
		)
		(fp_line
			(start 0.12065 -0.2794)
			(end 0.12065 -0.3048)
			(stroke
				(width 0.1)
				(type default)
			)
			(layer "F.Fab")
		)
		(fp_line
			(start 0.12065 -0.3048)
			(end 0.67945 -0.3048)
			(stroke
				(width 0.1)
				(type default)
			)
			(layer "F.Fab")
		)
		(fp_line
			(start 0.120396 0.3048)
			(end 0.120396 0.2794)
			(stroke
				(width 0.1)
				(type default)
			)
			(layer "F.Fab")
		)
		(fp_line
			(start 0.120396 0.2794)
			(end -0.12065 0.2794)
			(stroke
				(width 0.1)
				(type default)
			)
			(layer "F.Fab")
		)
		(fp_line
			(start -0.12065 0.3048)
			(end -0.67945 0.3048)
			(stroke
				(width 0.1)
				(type default)
			)
			(layer "F.Fab")
		)
		(fp_line
			(start -0.12065 0.2794)
			(end -0.12065 0.3048)
			(stroke
				(width 0.1)
				(type default)
			)
			(layer "F.Fab")
		)
		(fp_line
			(start -0.12065 -0.2794)
			(end 0.12065 -0.2794)
			(stroke
				(width 0.1)
				(type default)
			)
			(layer "F.Fab")
		)
		(fp_line
			(start -0.12065 -0.305054)
			(end -0.12065 -0.2794)
			(stroke
				(width 0.1)
				(type default)
			)
			(layer "F.Fab")
		)
		(fp_line
			(start -0.67945 0.3048)
			(end -0.67945 -0.305054)
			(stroke
				(width 0.1)
				(type default)
			)
			(layer "F.Fab")
		)
		(fp_line
			(start -0.67945 -0.305054)
			(end -0.12065 -0.305054)
			(stroke
				(width 0.1)
				(type default)
			)
			(layer "F.Fab")
		)
		(pad "1" smd circle
			(at -0.40005 0 180)
			(size 0 0)
			(layers "F.Cu" "F.Mask" "F.Paste")
			(net "SMB_FAN6_SCL")
		)
		(pad "2" smd circle
			(at 0.40005 0 180)
			(size 0 0)
			(layers "F.Cu" "F.Mask" "F.Paste")
			(net "SMB_FAN6_SCL_R")
		)
	)
	(footprint ""
		(layer "F.Cu")
		(at 36.322 -302.26)
		(property "Reference" "D131"
			(at 2.20472 -1.04775 0)
			(unlocked yes)
			(layer "F.SilkS")
			(effects
				(font
					(size 0.7874 0.5842)
					(thickness 0.1524)
				)
				(justify left)
			)
		)
		(property "Value" ""
			(at 0 0 0)
			(layer "F.Fab")
			(effects
				(font
					(size 1.27 1.27)
				)
			)
		)
		(duplicate_pad_numbers_are_jumpers no)
		(fp_line
			(start -0.299974 -0.500126)
			(end -0.299974 0.500126)
			(stroke
				(width 0.1524)
				(type default)
			)
			(layer "F.SilkS")
		)
		(fp_line
			(start -0.299974 0.500126)
			(end 0.199898 0)
			(stroke
				(width 0.1524)
				(type default)
			)
			(layer "F.SilkS")
		)
		(fp_line
			(start 0.199898 0)
			(end -0.299974 -0.500126)
			(stroke
				(width 0.1524)
				(type default)
			)
			(layer "F.SilkS")
		)
		(fp_line
			(start 0.299974 -0.500126)
			(end 0.299974 0.500126)
			(stroke
				(width 0.1524)
				(type default)
			)
			(layer "F.SilkS")
		)
		(fp_line
			(start 1.651 -0.6858)
			(end 1.651 0.6858)
			(stroke
				(width 0.1524)
				(type default)
			)
			(layer "F.SilkS")
		)
		(fp_line
			(start 1.778 0.6858)
			(end 1.778 -0.6858)
			(stroke
				(width 0.1524)
				(type default)
			)
			(layer "F.SilkS")
		)
		(fp_line
			(start -1.35001 -0.225044)
			(end -0.899922 -0.225044)
			(stroke
				(width 0.1)
				(type default)
			)
			(layer "F.Fab")
		)
		(fp_line
			(start -1.35001 0.175006)
			(end -1.35001 -0.225044)
			(stroke
				(width 0.1)
				(type default)
			)
			(layer "F.Fab")
		)
		(fp_line
			(start -0.899922 -0.700024)
			(end 0.899922 -0.700024)
			(stroke
				(width 0.1)
				(type default)
			)
			(layer "F.Fab")
		)
		(fp_line
			(start -0.899922 -0.225044)
			(end -0.899922 -0.700024)
			(stroke
				(width 0.1)
				(type default)
			)
			(layer "F.Fab")
		)
		(fp_line
			(start -0.899922 0.175006)
			(end -1.35001 0.175006)
			(stroke
				(width 0.1)
				(type default)
			)
			(layer "F.Fab")
		)
		(fp_line
			(start -0.899922 0.700024)
			(end -0.899922 0.175006)
			(stroke
				(width 0.1)
				(type default)
			)
			(layer "F.Fab")
		)
		(fp_line
			(start -0.299974 -0.500126)
			(end -0.299974 0.500126)
			(stroke
				(width 0.1)
				(type default)
			)
			(layer "F.Fab")
		)
		(fp_line
			(start -0.299974 0.500126)
			(end 0.199898 0)
			(stroke
				(width 0.1)
				(type default)
			)
			(layer "F.Fab")
		)
		(fp_line
			(start 0.199898 0)
			(end -0.299974 -0.500126)
			(stroke
				(width 0.1)
				(type default)
			)
			(layer "F.Fab")
		)
		(fp_line
			(start 0.299974 -0.500126)
			(end 0.299974 0.500126)
			(stroke
				(width 0.1)
				(type default)
			)
			(layer "F.Fab")
		)
		(fp_line
			(start 0.899922 -0.700024)
			(end 0.899922 -0.225044)
			(stroke
				(width 0.1)
				(type default)
			)
			(layer "F.Fab")
		)
		(fp_line
			(start 0.899922 -0.225044)
			(end 1.35001 -0.225044)
			(stroke
				(width 0.1)
				(type default)
			)
			(layer "F.Fab")
		)
		(fp_line
			(start 0.899922 0.175006)
			(end 0.899922 0.700024)
			(stroke
				(width 0.1)
				(type default)
			)
			(layer "F.Fab")
		)
		(fp_line
			(start 0.899922 0.700024)
			(end -0.899922 0.700024)
			(stroke
				(width 0.1)
				(type default)
			)
			(layer "F.Fab")
		)
		(fp_line
			(start 1.35001 -0.225044)
			(end 1.35001 0.175006)
			(stroke
				(width 0.1)
				(type default)
			)
			(layer "F.Fab")
		)
		(fp_line
			(start 1.35001 0.175006)
			(end 0.899922 0.175006)
			(stroke
				(width 0.1)
				(type default)
			)
			(layer "F.Fab")
		)
		(fp_text user "+"
			(at -2.794 0.66675 0)
			(unlocked yes)
			(layer "F.SilkS")
			(effects
				(font
					(size 1.905 1.4224)
					(thickness 0.1524)
				)
				(justify left)
			)
		)
		(fp_text user "-"
			(at 0.762 0.79375 0)
			(unlocked yes)
			(layer "F.SilkS")
			(effects
				(font
					(size 1.905 1.4224)
					(thickness 0.1524)
				)
				(justify left)
			)
		)
		(fp_text user "+"
			(at -2.794 -0.19685 0)
			(unlocked yes)
			(layer "F.Fab")
			(effects
				(font
					(size 1.905 1.4224)
					(thickness 0.1524)
				)
				(justify left)
			)
		)
		(fp_text user "-"
			(at 1.8288 -0.24765 0)
			(unlocked yes)
			(layer "F.Fab")
			(effects
				(font
					(size 1.905 1.4224)
					(thickness 0.1524)
				)
				(justify left)
			)
		)
		(pad "1" smd rect
			(at -1.0922 0 180)
			(size 0.8128 0.8636)
			(layers "F.Cu" "F.Mask" "F.Paste")
			(net "FAN_0_TACH_IL_R")
		)
		(pad "2" smd rect
			(at 1.0922 0)
			(size 0.8128 0.8636)
			(layers "F.Cu" "F.Mask" "F.Paste")
			(net "FAN_0_TACH_IL_D")
		)
	)
	(footprint ""
		(layer "F.Cu")
		(at 17.907 -172.466 180)
		(property "Reference" "R5501"
			(at 0 0 180)
			(layer "F.SilkS")
			(hide yes)
			(effects
				(font
					(size 1.27 1.27)
				)
			)
		)
		(property "Value" ""
			(at 0 0 180)
			(layer "F.Fab")
			(effects
				(font
					(size 1.27 1.27)
				)
			)
		)
		(duplicate_pad_numbers_are_jumpers no)
		(fp_line
			(start 0.7874 0.4064)
			(end -0.7874 0.4064)
			(stroke
				(width 0.1524)
				(type default)
			)
			(layer "F.SilkS")
		)
		(fp_line
			(start 0.7874 -0.4064)
			(end 0.7874 0.4064)
			(stroke
				(width 0.1524)
				(type default)
			)
			(layer "F.SilkS")
		)
		(fp_line
			(start -0.7874 0.4064)
			(end -0.7874 -0.4064)
			(stroke
				(width 0.1524)
				(type default)
			)
			(layer "F.SilkS")
		)
		(fp_line
			(start -0.7874 -0.4064)
			(end 0.7874 -0.4064)
			(stroke
				(width 0.1524)
				(type default)
			)
			(layer "F.SilkS")
		)
		(fp_line
			(start 0.67945 0.3048)
			(end 0.120396 0.3048)
			(stroke
				(width 0.1)
				(type default)
			)
			(layer "F.Fab")
		)
		(fp_line
			(start 0.67945 -0.3048)
			(end 0.67945 0.3048)
			(stroke
				(width 0.1)
				(type default)
			)
			(layer "F.Fab")
		)
		(fp_line
			(start 0.12065 -0.2794)
			(end 0.12065 -0.3048)
			(stroke
				(width 0.1)
				(type default)
			)
			(layer "F.Fab")
		)
		(fp_line
			(start 0.12065 -0.3048)
			(end 0.67945 -0.3048)
			(stroke
				(width 0.1)
				(type default)
			)
			(layer "F.Fab")
		)
		(fp_line
			(start 0.120396 0.3048)
			(end 0.120396 0.2794)
			(stroke
				(width 0.1)
				(type default)
			)
			(layer "F.Fab")
		)
		(fp_line
			(start 0.120396 0.2794)
			(end -0.12065 0.2794)
			(stroke
				(width 0.1)
				(type default)
			)
			(layer "F.Fab")
		)
		(fp_line
			(start -0.12065 0.3048)
			(end -0.67945 0.3048)
			(stroke
				(width 0.1)
				(type default)
			)
			(layer "F.Fab")
		)
		(fp_line
			(start -0.12065 0.2794)
			(end -0.12065 0.3048)
			(stroke
				(width 0.1)
				(type default)
			)
			(layer "F.Fab")
		)
		(fp_line
			(start -0.12065 -0.2794)
			(end 0.12065 -0.2794)
			(stroke
				(width 0.1)
				(type default)
			)
			(layer "F.Fab")
		)
		(fp_line
			(start -0.12065 -0.305054)
			(end -0.12065 -0.2794)
			(stroke
				(width 0.1)
				(type default)
			)
			(layer "F.Fab")
		)
		(fp_line
			(start -0.67945 0.3048)
			(end -0.67945 -0.305054)
			(stroke
				(width 0.1)
				(type default)
			)
			(layer "F.Fab")
		)
		(fp_line
			(start -0.67945 -0.305054)
			(end -0.12065 -0.305054)
			(stroke
				(width 0.1)
				(type default)
			)
			(layer "F.Fab")
		)
		(pad "1" smd circle
			(at -0.40005 0 180)
			(size 0 0)
			(layers "F.Cu" "F.Mask" "F.Paste")
			(net "FAN_6_PRESENT_R_N")
		)
		(pad "2" smd circle
			(at 0.40005 0 180)
			(size 0 0)
			(layers "F.Cu" "F.Mask" "F.Paste")
			(net "FAN_6_PRESENT_N")
		)
	)
	(footprint ""
		(layer "F.Cu")
		(at 25.4 -104.394)
		(property "Reference" "U325"
			(at -1.524 -1.87833 0)
			(unlocked yes)
			(layer "F.SilkS")
			(effects
				(font
					(size 0.7874 0.5842)
					(thickness 0.1524)
				)
				(justify left)
			)
		)
		(property "Value" ""
			(at 0 0 0)
			(layer "F.Fab")
			(effects
				(font
					(size 1.27 1.27)
				)
			)
		)
		(duplicate_pad_numbers_are_jumpers no)
		(fp_line
			(start -1.538478 -1.150874)
			(end -1.538478 1.150874)
			(stroke
				(width 0.1524)
				(type default)
			)
			(layer "F.SilkS")
		)
		(fp_line
			(start -1.538478 1.150874)
			(end 1.538478 1.150874)
			(stroke
				(width 0.1524)
				(type default)
			)
			(layer "F.SilkS")
		)
		(fp_line
			(start 1.538478 -1.150874)
			(end -1.538478 -1.150874)
			(stroke
				(width 0.1524)
				(type default)
			)
			(layer "F.SilkS")
		)
		(fp_line
			(start 1.538478 1.150874)
			(end 1.538478 -1.150874)
			(stroke
				(width 0.1524)
				(type default)
			)
			(layer "F.SilkS")
		)
		(fp_line
			(start -0.674878 -1.100074)
			(end -0.674878 1.100074)
			(stroke
				(width 0.1)
				(type default)
			)
			(layer "F.Fab")
		)
		(fp_line
			(start -0.674878 1.100074)
			(end 0.674878 1.100074)
			(stroke
				(width 0.1)
				(type default)
			)
			(layer "F.Fab")
		)
		(fp_line
			(start 0.674878 -1.100074)
			(end -0.674878 -1.100074)
			(stroke
				(width 0.1)
				(type default)
			)
			(layer "F.Fab")
		)
		(fp_line
			(start 0.674878 1.100074)
			(end 0.674878 -1.100074)
			(stroke
				(width 0.1)
				(type default)
			)
			(layer "F.Fab")
		)
		(pad "1" smd rect
			(at -0.94996 -0.649986 90)
			(size 0.7112 0.9144)
			(layers "F.Cu" "F.Mask" "F.Paste")
			(net "FAN_5_PWM_IL")
		)
		(pad "2" smd rect
			(at -0.94996 0.649986 90)
			(size 0.7112 0.9144)
			(layers "F.Cu" "F.Mask" "F.Paste")
			(net "FAN_5_PWM_OL")
		)
		(pad "3" smd rect
			(at 0.94996 0 90)
			(size 0.7112 0.9144)
			(layers "F.Cu" "F.Mask" "F.Paste")
			(net "FAN_5_PWM_BUF")
		)
	)
	(footprint ""
		(layer "F.Cu")
		(at 36.195 -196.370956)
		(property "Reference" "D135"
			(at 2.286 0.944626 0)
			(unlocked yes)
			(layer "F.SilkS")
			(effects
				(font
					(size 0.7874 0.5842)
					(thickness 0.1524)
				)
				(justify left)
			)
		)
		(property "Value" ""
			(at 0 0 0)
			(layer "F.Fab")
			(effects
				(font
					(size 1.27 1.27)
				)
			)
		)
		(duplicate_pad_numbers_are_jumpers no)
		(fp_line
			(start -0.299974 -0.500126)
			(end -0.299974 0.500126)
			(stroke
				(width 0.1524)
				(type default)
			)
			(layer "F.SilkS")
		)
		(fp_line
			(start -0.299974 0.500126)
			(end 0.199898 0)
			(stroke
				(width 0.1524)
				(type default)
			)
			(layer "F.SilkS")
		)
		(fp_line
			(start 0.199898 0)
			(end -0.299974 -0.500126)
			(stroke
				(width 0.1524)
				(type default)
			)
			(layer "F.SilkS")
		)
		(fp_line
			(start 0.299974 -0.500126)
			(end 0.299974 0.500126)
			(stroke
				(width 0.1524)
				(type default)
			)
			(layer "F.SilkS")
		)
		(fp_line
			(start 1.651 -0.6858)
			(end 1.651 0.6858)
			(stroke
				(width 0.1524)
				(type default)
			)
			(layer "F.SilkS")
		)
		(fp_line
			(start 1.778 0.6858)
			(end 1.778 -0.6858)
			(stroke
				(width 0.1524)
				(type default)
			)
			(layer "F.SilkS")
		)
		(fp_line
			(start -1.35001 -0.225044)
			(end -0.899922 -0.225044)
			(stroke
				(width 0.1)
				(type default)
			)
			(layer "F.Fab")
		)
		(fp_line
			(start -1.35001 0.175006)
			(end -1.35001 -0.225044)
			(stroke
				(width 0.1)
				(type default)
			)
			(layer "F.Fab")
		)
		(fp_line
			(start -0.899922 -0.700024)
			(end 0.899922 -0.700024)
			(stroke
				(width 0.1)
				(type default)
			)
			(layer "F.Fab")
		)
		(fp_line
			(start -0.899922 -0.225044)
			(end -0.899922 -0.700024)
			(stroke
				(width 0.1)
				(type default)
			)
			(layer "F.Fab")
		)
		(fp_line
			(start -0.899922 0.175006)
			(end -1.35001 0.175006)
			(stroke
				(width 0.1)
				(type default)
			)
			(layer "F.Fab")
		)
		(fp_line
			(start -0.899922 0.700024)
			(end -0.899922 0.175006)
			(stroke
				(width 0.1)
				(type default)
			)
			(layer "F.Fab")
		)
		(fp_line
			(start -0.299974 -0.500126)
			(end -0.299974 0.500126)
			(stroke
				(width 0.1)
				(type default)
			)
			(layer "F.Fab")
		)
		(fp_line
			(start -0.299974 0.500126)
			(end 0.199898 0)
			(stroke
				(width 0.1)
				(type default)
			)
			(layer "F.Fab")
		)
		(fp_line
			(start 0.199898 0)
			(end -0.299974 -0.500126)
			(stroke
				(width 0.1)
				(type default)
			)
			(layer "F.Fab")
		)
		(fp_line
			(start 0.299974 -0.500126)
			(end 0.299974 0.500126)
			(stroke
				(width 0.1)
				(type default)
			)
			(layer "F.Fab")
		)
		(fp_line
			(start 0.899922 -0.700024)
			(end 0.899922 -0.225044)
			(stroke
				(width 0.1)
				(type default)
			)
			(layer "F.Fab")
		)
		(fp_line
			(start 0.899922 -0.225044)
			(end 1.35001 -0.225044)
			(stroke
				(width 0.1)
				(type default)
			)
			(layer "F.Fab")
		)
		(fp_line
			(start 0.899922 0.175006)
			(end 0.899922 0.700024)
			(stroke
				(width 0.1)
				(type default)
			)
			(layer "F.Fab")
		)
		(fp_line
			(start 0.899922 0.700024)
			(end -0.899922 0.700024)
			(stroke
				(width 0.1)
				(type default)
			)
			(layer "F.Fab")
		)
		(fp_line
			(start 1.35001 -0.225044)
			(end 1.35001 0.175006)
			(stroke
				(width 0.1)
				(type default)
			)
			(layer "F.Fab")
		)
		(fp_line
			(start 1.35001 0.175006)
			(end 0.899922 0.175006)
			(stroke
				(width 0.1)
				(type default)
			)
			(layer "F.Fab")
		)
		(fp_text user "+"
			(at -2.667 0.822706 0)
			(unlocked yes)
			(layer "F.SilkS")
			(effects
				(font
					(size 1.905 1.4224)
					(thickness 0.1524)
				)
				(justify left)
			)
		)
		(fp_text user "-"
			(at 0.762 0.822706 0)
			(unlocked yes)
			(layer "F.SilkS")
			(effects
				(font
					(size 1.905 1.4224)
					(thickness 0.1524)
				)
				(justify left)
			)
		)
		(fp_text user "+"
			(at -2.794 -0.19685 0)
			(unlocked yes)
			(layer "F.Fab")
			(effects
				(font
					(size 1.905 1.4224)
					(thickness 0.1524)
				)
				(justify left)
			)
		)
		(fp_text user "-"
			(at 1.8288 -0.24765 0)
			(unlocked yes)
			(layer "F.Fab")
			(effects
				(font
					(size 1.905 1.4224)
					(thickness 0.1524)
				)
				(justify left)
			)
		)
		(pad "1" smd rect
			(at -1.0922 0 180)
			(size 0.8128 0.8636)
			(layers "F.Cu" "F.Mask" "F.Paste")
			(net "FAN_1_TACH_OL_R")
		)
		(pad "2" smd rect
			(at 1.0922 0)
			(size 0.8128 0.8636)
			(layers "F.Cu" "F.Mask" "F.Paste")
			(net "FAN_1_TACH_OL_D")
		)
	)
	(footprint ""
		(layer "F.Cu")
		(at 36.703 -64.262 180)
		(property "Reference" "PR24"
			(at 0 0 180)
			(layer "F.SilkS")
			(hide yes)
			(effects
				(font
					(size 1.27 1.27)
				)
			)
		)
		(property "Value" ""
			(at 0 0 180)
			(layer "F.Fab")
			(effects
				(font
					(size 1.27 1.27)
				)
			)
		)
		(duplicate_pad_numbers_are_jumpers no)
		(fp_line
			(start 0.7874 0.4064)
			(end -0.7874 0.4064)
			(stroke
				(width 0.1524)
				(type default)
			)
			(layer "F.SilkS")
		)
		(fp_line
			(start 0.7874 -0.4064)
			(end 0.7874 0.4064)
			(stroke
				(width 0.1524)
				(type default)
			)
			(layer "F.SilkS")
		)
		(fp_line
			(start -0.7874 0.4064)
			(end -0.7874 -0.4064)
			(stroke
				(width 0.1524)
				(type default)
			)
			(layer "F.SilkS")
		)
		(fp_line
			(start -0.7874 -0.4064)
			(end 0.7874 -0.4064)
			(stroke
				(width 0.1524)
				(type default)
			)
			(layer "F.SilkS")
		)
		(fp_line
			(start 0.67945 0.3048)
			(end 0.120396 0.3048)
			(stroke
				(width 0.1)
				(type default)
			)
			(layer "F.Fab")
		)
		(fp_line
			(start 0.67945 -0.3048)
			(end 0.67945 0.3048)
			(stroke
				(width 0.1)
				(type default)
			)
			(layer "F.Fab")
		)
		(fp_line
			(start 0.12065 -0.2794)
			(end 0.12065 -0.3048)
			(stroke
				(width 0.1)
				(type default)
			)
			(layer "F.Fab")
		)
		(fp_line
			(start 0.12065 -0.3048)
			(end 0.67945 -0.3048)
			(stroke
				(width 0.1)
				(type default)
			)
			(layer "F.Fab")
		)
		(fp_line
			(start 0.120396 0.3048)
			(end 0.120396 0.2794)
			(stroke
				(width 0.1)
				(type default)
			)
			(layer "F.Fab")
		)
		(fp_line
			(start 0.120396 0.2794)
			(end -0.12065 0.2794)
			(stroke
				(width 0.1)
				(type default)
			)
			(layer "F.Fab")
		)
		(fp_line
			(start -0.12065 0.3048)
			(end -0.67945 0.3048)
			(stroke
				(width 0.1)
				(type default)
			)
			(layer "F.Fab")
		)
		(fp_line
			(start -0.12065 0.2794)
			(end -0.12065 0.3048)
			(stroke
				(width 0.1)
				(type default)
			)
			(layer "F.Fab")
		)
		(fp_line
			(start -0.12065 -0.2794)
			(end 0.12065 -0.2794)
			(stroke
				(width 0.1)
				(type default)
			)
			(layer "F.Fab")
		)
		(fp_line
			(start -0.12065 -0.305054)
			(end -0.12065 -0.2794)
			(stroke
				(width 0.1)
				(type default)
			)
			(layer "F.Fab")
		)
		(fp_line
			(start -0.67945 0.3048)
			(end -0.67945 -0.305054)
			(stroke
				(width 0.1)
				(type default)
			)
			(layer "F.Fab")
		)
		(fp_line
			(start -0.67945 -0.305054)
			(end -0.12065 -0.305054)
			(stroke
				(width 0.1)
				(type default)
			)
			(layer "F.Fab")
		)
		(pad "1" smd circle
			(at -0.40005 0 180)
			(size 0 0)
			(layers "F.Cu" "F.Mask" "F.Paste")
			(net "FAN_3_P3V_R")
		)
		(pad "2" smd circle
			(at 0.40005 0 180)
			(size 0 0)
			(layers "F.Cu" "F.Mask" "F.Paste")
			(net "FAN_3_MODE")
		)
	)
	(footprint ""
		(layer "F.Cu")
		(at 26.162 -18.796)
		(property "Reference" "U323"
			(at -1.524 1.93167 0)
			(unlocked yes)
			(layer "F.SilkS")
			(effects
				(font
					(size 0.7874 0.5842)
					(thickness 0.1524)
				)
				(justify left)
			)
		)
		(property "Value" ""
			(at 0 0 0)
			(layer "F.Fab")
			(effects
				(font
					(size 1.27 1.27)
				)
			)
		)
		(duplicate_pad_numbers_are_jumpers no)
		(fp_line
			(start -1.538478 -1.150874)
			(end -1.538478 1.150874)
			(stroke
				(width 0.1524)
				(type default)
			)
			(layer "F.SilkS")
		)
		(fp_line
			(start -1.538478 1.150874)
			(end 1.538478 1.150874)
			(stroke
				(width 0.1524)
				(type default)
			)
			(layer "F.SilkS")
		)
		(fp_line
			(start 1.538478 -1.150874)
			(end -1.538478 -1.150874)
			(stroke
				(width 0.1524)
				(type default)
			)
			(layer "F.SilkS")
		)
		(fp_line
			(start 1.538478 1.150874)
			(end 1.538478 -1.150874)
			(stroke
				(width 0.1524)
				(type default)
			)
			(layer "F.SilkS")
		)
		(fp_line
			(start -0.674878 -1.100074)
			(end -0.674878 1.100074)
			(stroke
				(width 0.1)
				(type default)
			)
			(layer "F.Fab")
		)
		(fp_line
			(start -0.674878 1.100074)
			(end 0.674878 1.100074)
			(stroke
				(width 0.1)
				(type default)
			)
			(layer "F.Fab")
		)
		(fp_line
			(start 0.674878 -1.100074)
			(end -0.674878 -1.100074)
			(stroke
				(width 0.1)
				(type default)
			)
			(layer "F.Fab")
		)
		(fp_line
			(start 0.674878 1.100074)
			(end 0.674878 -1.100074)
			(stroke
				(width 0.1)
				(type default)
			)
			(layer "F.Fab")
		)
		(pad "1" smd rect
			(at -0.94996 -0.649986 90)
			(size 0.7112 0.9144)
			(layers "F.Cu" "F.Mask" "F.Paste")
			(net "FAN_4_PWM_IL")
		)
		(pad "2" smd rect
			(at -0.94996 0.649986 90)
			(size 0.7112 0.9144)
			(layers "F.Cu" "F.Mask" "F.Paste")
			(net "FAN_4_PWM_OL")
		)
		(pad "3" smd rect
			(at 0.94996 0 90)
			(size 0.7112 0.9144)
			(layers "F.Cu" "F.Mask" "F.Paste")
			(net "FAN_4_PWM_BUF")
		)
	)
	(footprint ""
		(layer "F.Cu")
		(at 15.377922 -119.476012 180)
		(property "Reference" "D247"
			(at 5.471922 1.528318 0)
			(unlocked yes)
			(layer "F.SilkS")
			(effects
				(font
					(size 0.7874 0.5842)
					(thickness 0.1524)
				)
				(justify left)
			)
		)
		(property "Value" ""
			(at 0 0 180)
			(layer "F.Fab")
			(effects
				(font
					(size 1.27 1.27)
				)
			)
		)
		(duplicate_pad_numbers_are_jumpers no)
		(fp_line
			(start 0.94488 0.450088)
			(end 0.94488 -0.450088)
			(stroke
				(width 0.1524)
				(type default)
			)
			(layer "F.SilkS")
		)
		(fp_line
			(start 0.94488 -0.450088)
			(end -0.854964 -0.450088)
			(stroke
				(width 0.1524)
				(type default)
			)
			(layer "F.SilkS")
		)
		(fp_line
			(start 0.870458 -0.2794)
			(end 0.845058 0.4064)
			(stroke
				(width 0.1524)
				(type default)
			)
			(layer "F.SilkS")
		)
		(fp_line
			(start 0.845058 0.4064)
			(end 0.845058 -0.381)
			(stroke
				(width 0.1524)
				(type default)
			)
			(layer "F.SilkS")
		)
		(fp_line
			(start -0.854964 0.450088)
			(end 0.925068 0.450088)
			(stroke
				(width 0.1524)
				(type default)
			)
			(layer "F.SilkS")
		)
		(fp_line
			(start -0.854964 -0.450088)
			(end -0.854964 0.450088)
			(stroke
				(width 0.1524)
				(type default)
			)
			(layer "F.SilkS")
		)
		(fp_line
			(start 0.54991 0.350012)
			(end 0.54991 -0.350012)
			(stroke
				(width 0.1)
				(type default)
			)
			(layer "F.Fab")
		)
		(fp_line
			(start 0.54991 -0.350012)
			(end -0.54991 -0.350012)
			(stroke
				(width 0.1)
				(type default)
			)
			(layer "F.Fab")
		)
		(fp_line
			(start -0.54991 0.350012)
			(end 0.54991 0.350012)
			(stroke
				(width 0.1)
				(type default)
			)
			(layer "F.Fab")
		)
		(fp_line
			(start -0.54991 -0.350012)
			(end -0.54991 0.350012)
			(stroke
				(width 0.1)
				(type default)
			)
			(layer "F.Fab")
		)
		(fp_text user "-"
			(at 2.423922 0.253238 0)
			(unlocked yes)
			(layer "F.SilkS")
			(effects
				(font
					(size 1.905 1.4224)
					(thickness 0.1524)
				)
				(justify left)
			)
		)
		(fp_text user "+"
			(at -0.497078 1.015238 0)
			(unlocked yes)
			(layer "F.SilkS")
			(effects
				(font
					(size 1.905 1.4224)
					(thickness 0.1524)
				)
				(justify left)
			)
		)
		(fp_text user "-"
			(at 2.48539 0.239014 0)
			(unlocked yes)
			(layer "F.Fab")
			(effects
				(font
					(size 1.905 1.4224)
					(thickness 0.1524)
				)
				(justify left)
			)
		)
		(fp_text user "+"
			(at -0.808228 0.239014 0)
			(unlocked yes)
			(layer "F.Fab")
			(effects
				(font
					(size 1.905 1.4224)
					(thickness 0.1524)
				)
				(justify left)
			)
		)
		(pad "A" smd rect
			(at -0.424942 0 180)
			(size 0.5588 0.6096)
			(layers "F.Cu" "F.Mask" "F.Paste")
			(net "GND")
		)
		(pad "C" smd rect
			(at 0.424942 0)
			(size 0.5588 0.6096)
			(layers "F.Cu" "F.Mask" "F.Paste")
			(net "FAN_5_TACH_OL_D")
		)
	)
	(footprint ""
		(layer "F.Cu")
		(at 40.850058 -157.661102)
		(property "Reference" "H4"
			(at -0.464058 17.225772 0)
			(unlocked yes)
			(layer "F.SilkS")
			(effects
				(font
					(size 0.7874 0.5842)
					(thickness 0.1524)
				)
				(justify left)
			)
		)
		(property "Value" ""
			(at 0 0 0)
			(layer "F.Fab")
			(effects
				(font
					(size 1.27 1.27)
				)
			)
		)
		(duplicate_pad_numbers_are_jumpers no)
		(pad "1" thru_hole oval
			(at 0 0)
			(size 9.017 21.0058)
			(drill 3.0226
				(offset 0 5.999988)
			)
			(layers "*.Cu" "*.Mask")
			(remove_unused_layers no)
			(net "GND")
			(clearance -1.500378)
			(padstack
				(mode front_inner_back)
				(layer "Inner"
					(shape circle)
					(size 0 0)
					(clearance 0)
				)
				(layer "B.Cu"
					(shape oval)
					(size 9.017 21.0058)
					(offset 0 5.999988)
					(clearance -1.500378)
				)
			)
		)
	)
	(footprint ""
		(layer "F.Cu")
		(at 16.51 -304.419 90)
		(property "Reference" "C2059"
			(at 0 0 90)
			(layer "F.SilkS")
			(hide yes)
			(effects
				(font
					(size 1.27 1.27)
				)
			)
		)
		(property "Value" ""
			(at 0 0 90)
			(layer "F.Fab")
			(effects
				(font
					(size 1.27 1.27)
				)
			)
		)
		(duplicate_pad_numbers_are_jumpers no)
		(fp_line
			(start 0.7874 -0.4064)
			(end 0.7874 0.4064)
			(stroke
				(width 0.1524)
				(type default)
			)
			(layer "F.SilkS")
		)
		(fp_line
			(start -0.7874 -0.4064)
			(end 0.7874 -0.4064)
			(stroke
				(width 0.1524)
				(type default)
			)
			(layer "F.SilkS")
		)
		(fp_line
			(start 0.7874 0.4064)
			(end -0.7874 0.4064)
			(stroke
				(width 0.1524)
				(type default)
			)
			(layer "F.SilkS")
		)
		(fp_line
			(start -0.7874 0.4064)
			(end -0.7874 -0.4064)
			(stroke
				(width 0.1524)
				(type default)
			)
			(layer "F.SilkS")
		)
		(fp_line
			(start -0.12065 -0.305054)
			(end -0.12065 -0.2794)
			(stroke
				(width 0.1)
				(type default)
			)
			(layer "F.Fab")
		)
		(fp_line
			(start -0.67945 -0.305054)
			(end -0.12065 -0.305054)
			(stroke
				(width 0.1)
				(type default)
			)
			(layer "F.Fab")
		)
		(fp_line
			(start 0.67945 -0.3048)
			(end 0.67945 0.3048)
			(stroke
				(width 0.1)
				(type default)
			)
			(layer "F.Fab")
		)
		(fp_line
			(start 0.12065 -0.3048)
			(end 0.67945 -0.3048)
			(stroke
				(width 0.1)
				(type default)
			)
			(layer "F.Fab")
		)
		(fp_line
			(start 0.12065 -0.2794)
			(end 0.12065 -0.3048)
			(stroke
				(width 0.1)
				(type default)
			)
			(layer "F.Fab")
		)
		(fp_line
			(start -0.12065 -0.2794)
			(end 0.12065 -0.2794)
			(stroke
				(width 0.1)
				(type default)
			)
			(layer "F.Fab")
		)
		(fp_line
			(start 0.120396 0.2794)
			(end -0.12065 0.2794)
			(stroke
				(width 0.1)
				(type default)
			)
			(layer "F.Fab")
		)
		(fp_line
			(start -0.12065 0.2794)
			(end -0.12065 0.3048)
			(stroke
				(width 0.1)
				(type default)
			)
			(layer "F.Fab")
		)
		(fp_line
			(start 0.67945 0.3048)
			(end 0.120396 0.3048)
			(stroke
				(width 0.1)
				(type default)
			)
			(layer "F.Fab")
		)
		(fp_line
			(start 0.120396 0.3048)
			(end 0.120396 0.2794)
			(stroke
				(width 0.1)
				(type default)
			)
			(layer "F.Fab")
		)
		(fp_line
			(start -0.12065 0.3048)
			(end -0.67945 0.3048)
			(stroke
				(width 0.1)
				(type default)
			)
			(layer "F.Fab")
		)
		(fp_line
			(start -0.67945 0.3048)
			(end -0.67945 -0.305054)
			(stroke
				(width 0.1)
				(type default)
			)
			(layer "F.Fab")
		)
		(pad "1" smd circle
			(at -0.40005 0 90)
			(size 0 0)
			(layers "F.Cu" "F.Mask" "F.Paste")
			(net "FAN_7_TACH_OL_R")
		)
		(pad "2" smd circle
			(at 0.40005 0 90)
			(size 0 0)
			(layers "F.Cu" "F.Mask" "F.Paste")
			(net "GND")
		)
	)
	(footprint ""
		(layer "F.Cu")
		(at 14.732 -259.08)
		(property "Reference" "PR73"
			(at 0 0 0)
			(layer "F.SilkS")
			(hide yes)
			(effects
				(font
					(size 1.27 1.27)
				)
			)
		)
		(property "Value" ""
			(at 0 0 0)
			(layer "F.Fab")
			(effects
				(font
					(size 1.27 1.27)
				)
			)
		)
		(duplicate_pad_numbers_are_jumpers no)
		(fp_line
			(start -0.7874 -0.4064)
			(end 0.7874 -0.4064)
			(stroke
				(width 0.1524)
				(type default)
			)
			(layer "F.SilkS")
		)
		(fp_line
			(start -0.7874 0.4064)
			(end -0.7874 -0.4064)
			(stroke
				(width 0.1524)
				(type default)
			)
			(layer "F.SilkS")
		)
		(fp_line
			(start 0.7874 -0.4064)
			(end 0.7874 0.4064)
			(stroke
				(width 0.1524)
				(type default)
			)
			(layer "F.SilkS")
		)
		(fp_line
			(start 0.7874 0.4064)
			(end -0.7874 0.4064)
			(stroke
				(width 0.1524)
				(type default)
			)
			(layer "F.SilkS")
		)
		(fp_line
			(start -0.67945 -0.305054)
			(end -0.12065 -0.305054)
			(stroke
				(width 0.1)
				(type default)
			)
			(layer "F.Fab")
		)
		(fp_line
			(start -0.67945 0.3048)
			(end -0.67945 -0.305054)
			(stroke
				(width 0.1)
				(type default)
			)
			(layer "F.Fab")
		)
		(fp_line
			(start -0.12065 -0.305054)
			(end -0.12065 -0.2794)
			(stroke
				(width 0.1)
				(type default)
			)
			(layer "F.Fab")
		)
		(fp_line
			(start -0.12065 -0.2794)
			(end 0.12065 -0.2794)
			(stroke
				(width 0.1)
				(type default)
			)
			(layer "F.Fab")
		)
		(fp_line
			(start -0.12065 0.2794)
			(end -0.12065 0.3048)
			(stroke
				(width 0.1)
				(type default)
			)
			(layer "F.Fab")
		)
		(fp_line
			(start -0.12065 0.3048)
			(end -0.67945 0.3048)
			(stroke
				(width 0.1)
				(type default)
			)
			(layer "F.Fab")
		)
		(fp_line
			(start 0.120396 0.2794)
			(end -0.12065 0.2794)
			(stroke
				(width 0.1)
				(type default)
			)
			(layer "F.Fab")
		)
		(fp_line
			(start 0.120396 0.3048)
			(end 0.120396 0.2794)
			(stroke
				(width 0.1)
				(type default)
			)
			(layer "F.Fab")
		)
		(fp_line
			(start 0.12065 -0.3048)
			(end 0.67945 -0.3048)
			(stroke
				(width 0.1)
				(type default)
			)
			(layer "F.Fab")
		)
		(fp_line
			(start 0.12065 -0.2794)
			(end 0.12065 -0.3048)
			(stroke
				(width 0.1)
				(type default)
			)
			(layer "F.Fab")
		)
		(fp_line
			(start 0.67945 -0.3048)
			(end 0.67945 0.3048)
			(stroke
				(width 0.1)
				(type default)
			)
			(layer "F.Fab")
		)
		(fp_line
			(start 0.67945 0.3048)
			(end 0.120396 0.3048)
			(stroke
				(width 0.1)
				(type default)
			)
			(layer "F.Fab")
		)
		(pad "1" smd circle
			(at -0.40005 0)
			(size 0 0)
			(layers "F.Cu" "F.Mask" "F.Paste")
			(net "FAN_7_P3V_R")
		)
		(pad "2" smd circle
			(at 0.40005 0)
			(size 0 0)
			(layers "F.Cu" "F.Mask" "F.Paste")
			(net "FAN_7_MODE")
		)
	)
	(footprint ""
		(layer "F.Cu")
		(at 28.575 -287.02 90)
		(property "Reference" "R5518"
			(at 0 0 90)
			(layer "F.SilkS")
			(hide yes)
			(effects
				(font
					(size 1.27 1.27)
				)
			)
		)
		(property "Value" ""
			(at 0 0 90)
			(layer "F.Fab")
			(effects
				(font
					(size 1.27 1.27)
				)
			)
		)
		(duplicate_pad_numbers_are_jumpers no)
		(fp_line
			(start 0.7874 -0.4064)
			(end 0.7874 0.4064)
			(stroke
				(width 0.1524)
				(type default)
			)
			(layer "F.SilkS")
		)
		(fp_line
			(start -0.7874 -0.4064)
			(end 0.7874 -0.4064)
			(stroke
				(width 0.1524)
				(type default)
			)
			(layer "F.SilkS")
		)
		(fp_line
			(start 0.7874 0.4064)
			(end -0.7874 0.4064)
			(stroke
				(width 0.1524)
				(type default)
			)
			(layer "F.SilkS")
		)
		(fp_line
			(start -0.7874 0.4064)
			(end -0.7874 -0.4064)
			(stroke
				(width 0.1524)
				(type default)
			)
			(layer "F.SilkS")
		)
		(fp_line
			(start -0.12065 -0.305054)
			(end -0.12065 -0.2794)
			(stroke
				(width 0.1)
				(type default)
			)
			(layer "F.Fab")
		)
		(fp_line
			(start -0.67945 -0.305054)
			(end -0.12065 -0.305054)
			(stroke
				(width 0.1)
				(type default)
			)
			(layer "F.Fab")
		)
		(fp_line
			(start 0.67945 -0.3048)
			(end 0.67945 0.3048)
			(stroke
				(width 0.1)
				(type default)
			)
			(layer "F.Fab")
		)
		(fp_line
			(start 0.12065 -0.3048)
			(end 0.67945 -0.3048)
			(stroke
				(width 0.1)
				(type default)
			)
			(layer "F.Fab")
		)
		(fp_line
			(start 0.12065 -0.2794)
			(end 0.12065 -0.3048)
			(stroke
				(width 0.1)
				(type default)
			)
			(layer "F.Fab")
		)
		(fp_line
			(start -0.12065 -0.2794)
			(end 0.12065 -0.2794)
			(stroke
				(width 0.1)
				(type default)
			)
			(layer "F.Fab")
		)
		(fp_line
			(start 0.120396 0.2794)
			(end -0.12065 0.2794)
			(stroke
				(width 0.1)
				(type default)
			)
			(layer "F.Fab")
		)
		(fp_line
			(start -0.12065 0.2794)
			(end -0.12065 0.3048)
			(stroke
				(width 0.1)
				(type default)
			)
			(layer "F.Fab")
		)
		(fp_line
			(start 0.67945 0.3048)
			(end 0.120396 0.3048)
			(stroke
				(width 0.1)
				(type default)
			)
			(layer "F.Fab")
		)
		(fp_line
			(start 0.120396 0.3048)
			(end 0.120396 0.2794)
			(stroke
				(width 0.1)
				(type default)
			)
			(layer "F.Fab")
		)
		(fp_line
			(start -0.12065 0.3048)
			(end -0.67945 0.3048)
			(stroke
				(width 0.1)
				(type default)
			)
			(layer "F.Fab")
		)
		(fp_line
			(start -0.67945 0.3048)
			(end -0.67945 -0.305054)
			(stroke
				(width 0.1)
				(type default)
			)
			(layer "F.Fab")
		)
		(pad "1" smd circle
			(at -0.40005 0 90)
			(size 0 0)
			(layers "F.Cu" "F.Mask" "F.Paste")
			(net "P3V3_AUX")
		)
		(pad "2" smd circle
			(at 0.40005 0 90)
			(size 0 0)
			(layers "F.Cu" "F.Mask" "F.Paste")
			(net "FAN_7_PWM_BUF")
		)
	)
	(footprint ""
		(layer "F.Cu")
		(at 27.686 -121.92 90)
		(property "Reference" "R5681"
			(at 0 0 90)
			(layer "F.SilkS")
			(hide yes)
			(effects
				(font
					(size 1.27 1.27)
				)
			)
		)
		(property "Value" ""
			(at 0 0 90)
			(layer "F.Fab")
			(effects
				(font
					(size 1.27 1.27)
				)
			)
		)
		(duplicate_pad_numbers_are_jumpers no)
		(fp_line
			(start 0.7874 -0.4064)
			(end 0.7874 0.4064)
			(stroke
				(width 0.1524)
				(type default)
			)
			(layer "F.SilkS")
		)
		(fp_line
			(start -0.7874 -0.4064)
			(end 0.7874 -0.4064)
			(stroke
				(width 0.1524)
				(type default)
			)
			(layer "F.SilkS")
		)
		(fp_line
			(start 0.7874 0.4064)
			(end -0.7874 0.4064)
			(stroke
				(width 0.1524)
				(type default)
			)
			(layer "F.SilkS")
		)
		(fp_line
			(start -0.7874 0.4064)
			(end -0.7874 -0.4064)
			(stroke
				(width 0.1524)
				(type default)
			)
			(layer "F.SilkS")
		)
		(fp_line
			(start -0.12065 -0.305054)
			(end -0.12065 -0.2794)
			(stroke
				(width 0.1)
				(type default)
			)
			(layer "F.Fab")
		)
		(fp_line
			(start -0.67945 -0.305054)
			(end -0.12065 -0.305054)
			(stroke
				(width 0.1)
				(type default)
			)
			(layer "F.Fab")
		)
		(fp_line
			(start 0.67945 -0.3048)
			(end 0.67945 0.3048)
			(stroke
				(width 0.1)
				(type default)
			)
			(layer "F.Fab")
		)
		(fp_line
			(start 0.12065 -0.3048)
			(end 0.67945 -0.3048)
			(stroke
				(width 0.1)
				(type default)
			)
			(layer "F.Fab")
		)
		(fp_line
			(start 0.12065 -0.2794)
			(end 0.12065 -0.3048)
			(stroke
				(width 0.1)
				(type default)
			)
			(layer "F.Fab")
		)
		(fp_line
			(start -0.12065 -0.2794)
			(end 0.12065 -0.2794)
			(stroke
				(width 0.1)
				(type default)
			)
			(layer "F.Fab")
		)
		(fp_line
			(start 0.120396 0.2794)
			(end -0.12065 0.2794)
			(stroke
				(width 0.1)
				(type default)
			)
			(layer "F.Fab")
		)
		(fp_line
			(start -0.12065 0.2794)
			(end -0.12065 0.3048)
			(stroke
				(width 0.1)
				(type default)
			)
			(layer "F.Fab")
		)
		(fp_line
			(start 0.67945 0.3048)
			(end 0.120396 0.3048)
			(stroke
				(width 0.1)
				(type default)
			)
			(layer "F.Fab")
		)
		(fp_line
			(start 0.120396 0.3048)
			(end 0.120396 0.2794)
			(stroke
				(width 0.1)
				(type default)
			)
			(layer "F.Fab")
		)
		(fp_line
			(start -0.12065 0.3048)
			(end -0.67945 0.3048)
			(stroke
				(width 0.1)
				(type default)
			)
			(layer "F.Fab")
		)
		(fp_line
			(start -0.67945 0.3048)
			(end -0.67945 -0.305054)
			(stroke
				(width 0.1)
				(type default)
			)
			(layer "F.Fab")
		)
		(pad "1" smd circle
			(at -0.40005 0 90)
			(size 0 0)
			(layers "F.Cu" "F.Mask" "F.Paste")
			(net "P3V3_AUX")
		)
		(pad "2" smd circle
			(at 0.40005 0 90)
			(size 0 0)
			(layers "F.Cu" "F.Mask" "F.Paste")
			(net "U317_FAN FAIL_N")
		)
	)
	(footprint ""
		(layer "F.Cu")
		(at 32.512 -302.895)
		(property "Reference" "R5300"
			(at 0 0 0)
			(layer "F.SilkS")
			(hide yes)
			(effects
				(font
					(size 1.27 1.27)
				)
			)
		)
		(property "Value" ""
			(at 0 0 0)
			(layer "F.Fab")
			(effects
				(font
					(size 1.27 1.27)
				)
			)
		)
		(duplicate_pad_numbers_are_jumpers no)
		(fp_line
			(start -1.2954 -0.5842)
			(end 1.2954 -0.5842)
			(stroke
				(width 0.1524)
				(type default)
			)
			(layer "F.SilkS")
		)
		(fp_line
			(start -1.2954 0.5842)
			(end -1.2954 -0.5842)
			(stroke
				(width 0.1524)
				(type default)
			)
			(layer "F.SilkS")
		)
		(fp_line
			(start 1.2954 -0.5842)
			(end 1.2954 0.5842)
			(stroke
				(width 0.1524)
				(type default)
			)
			(layer "F.SilkS")
		)
		(fp_line
			(start 1.2954 0.5842)
			(end -1.2954 0.5842)
			(stroke
				(width 0.1524)
				(type default)
			)
			(layer "F.SilkS")
		)
		(fp_line
			(start -1.1938 -0.406654)
			(end -0.8636 -0.406654)
			(stroke
				(width 0.1)
				(type default)
			)
			(layer "F.Fab")
		)
		(fp_line
			(start -1.1938 0.4064)
			(end -1.1938 -0.406654)
			(stroke
				(width 0.1)
				(type default)
			)
			(layer "F.Fab")
		)
		(fp_line
			(start -0.8636 -0.4572)
			(end 0.8636 -0.4572)
			(stroke
				(width 0.1)
				(type default)
			)
			(layer "F.Fab")
		)
		(fp_line
			(start -0.8636 -0.406654)
			(end -0.8636 -0.4572)
			(stroke
				(width 0.1)
				(type default)
			)
			(layer "F.Fab")
		)
		(fp_line
			(start -0.8636 0.4064)
			(end -1.1938 0.4064)
			(stroke
				(width 0.1)
				(type default)
			)
			(layer "F.Fab")
		)
		(fp_line
			(start -0.8636 0.4318)
			(end -0.8636 0.4064)
			(stroke
				(width 0.1)
				(type default)
			)
			(layer "F.Fab")
		)
		(fp_line
			(start -0.8636 0.4572)
			(end -0.8636 0.4318)
			(stroke
				(width 0.1)
				(type default)
			)
			(layer "F.Fab")
		)
		(fp_line
			(start 0.8636 -0.4572)
			(end 0.8636 -0.406654)
			(stroke
				(width 0.1)
				(type default)
			)
			(layer "F.Fab")
		)
		(fp_line
			(start 0.8636 -0.406654)
			(end 1.1938 -0.406654)
			(stroke
				(width 0.1)
				(type default)
			)
			(layer "F.Fab")
		)
		(fp_line
			(start 0.8636 0.4064)
			(end 0.8636 0.4572)
			(stroke
				(width 0.1)
				(type default)
			)
			(layer "F.Fab")
		)
		(fp_line
			(start 0.8636 0.4572)
			(end -0.8636 0.4572)
			(stroke
				(width 0.1)
				(type default)
			)
			(layer "F.Fab")
		)
		(fp_line
			(start 1.1938 -0.406654)
			(end 1.1938 0.4064)
			(stroke
				(width 0.1)
				(type default)
			)
			(layer "F.Fab")
		)
		(fp_line
			(start 1.1938 0.4064)
			(end 0.8636 0.4064)
			(stroke
				(width 0.1)
				(type default)
			)
			(layer "F.Fab")
		)
		(pad "1" smd rect
			(at -0.7366 0 270)
			(size 0.7112 0.8128)
			(layers "F.Cu" "F.Mask" "F.Paste")
			(net "P52V_FAN_0")
		)
		(pad "2" smd rect
			(at 0.7366 0 270)
			(size 0.7112 0.8128)
			(layers "F.Cu" "F.Mask" "F.Paste")
			(net "FAN_0_TACH_IL_R")
		)
	)
	(footprint ""
		(layer "F.Cu")
		(at 14.351 -73.914 90)
		(property "Reference" "PR56"
			(at 0 0 90)
			(layer "F.SilkS")
			(hide yes)
			(effects
				(font
					(size 1.27 1.27)
				)
			)
		)
		(property "Value" ""
			(at 0 0 90)
			(layer "F.Fab")
			(effects
				(font
					(size 1.27 1.27)
				)
			)
		)
		(duplicate_pad_numbers_are_jumpers no)
		(fp_line
			(start 0.7874 -0.4064)
			(end 0.7874 0.4064)
			(stroke
				(width 0.1524)
				(type default)
			)
			(layer "F.SilkS")
		)
		(fp_line
			(start -0.7874 -0.4064)
			(end 0.7874 -0.4064)
			(stroke
				(width 0.1524)
				(type default)
			)
			(layer "F.SilkS")
		)
		(fp_line
			(start 0.7874 0.4064)
			(end -0.7874 0.4064)
			(stroke
				(width 0.1524)
				(type default)
			)
			(layer "F.SilkS")
		)
		(fp_line
			(start -0.7874 0.4064)
			(end -0.7874 -0.4064)
			(stroke
				(width 0.1524)
				(type default)
			)
			(layer "F.SilkS")
		)
		(fp_line
			(start -0.12065 -0.305054)
			(end -0.12065 -0.2794)
			(stroke
				(width 0.1)
				(type default)
			)
			(layer "F.Fab")
		)
		(fp_line
			(start -0.67945 -0.305054)
			(end -0.12065 -0.305054)
			(stroke
				(width 0.1)
				(type default)
			)
			(layer "F.Fab")
		)
		(fp_line
			(start 0.67945 -0.3048)
			(end 0.67945 0.3048)
			(stroke
				(width 0.1)
				(type default)
			)
			(layer "F.Fab")
		)
		(fp_line
			(start 0.12065 -0.3048)
			(end 0.67945 -0.3048)
			(stroke
				(width 0.1)
				(type default)
			)
			(layer "F.Fab")
		)
		(fp_line
			(start 0.12065 -0.2794)
			(end 0.12065 -0.3048)
			(stroke
				(width 0.1)
				(type default)
			)
			(layer "F.Fab")
		)
		(fp_line
			(start -0.12065 -0.2794)
			(end 0.12065 -0.2794)
			(stroke
				(width 0.1)
				(type default)
			)
			(layer "F.Fab")
		)
		(fp_line
			(start 0.120396 0.2794)
			(end -0.12065 0.2794)
			(stroke
				(width 0.1)
				(type default)
			)
			(layer "F.Fab")
		)
		(fp_line
			(start -0.12065 0.2794)
			(end -0.12065 0.3048)
			(stroke
				(width 0.1)
				(type default)
			)
			(layer "F.Fab")
		)
		(fp_line
			(start 0.67945 0.3048)
			(end 0.120396 0.3048)
			(stroke
				(width 0.1)
				(type default)
			)
			(layer "F.Fab")
		)
		(fp_line
			(start 0.120396 0.3048)
			(end 0.120396 0.2794)
			(stroke
				(width 0.1)
				(type default)
			)
			(layer "F.Fab")
		)
		(fp_line
			(start -0.12065 0.3048)
			(end -0.67945 0.3048)
			(stroke
				(width 0.1)
				(type default)
			)
			(layer "F.Fab")
		)
		(fp_line
			(start -0.67945 0.3048)
			(end -0.67945 -0.305054)
			(stroke
				(width 0.1)
				(type default)
			)
			(layer "F.Fab")
		)
		(pad "1" smd rect
			(at -0.40005 0 270)
			(size 0.4572 0.508)
			(layers "F.Cu" "F.Mask" "F.Paste")
			(net "FAN_5_FAULT_R")
		)
		(pad "2" smd rect
			(at 0.40005 0 270)
			(size 0.4572 0.508)
			(layers "F.Cu" "F.Mask" "F.Paste")
			(net "FAN_5_FAULT")
		)
	)
	(footprint ""
		(layer "F.Cu")
		(at 45.085 -186.182)
		(property "Reference" "R5494"
			(at 0 0 0)
			(layer "F.SilkS")
			(hide yes)
			(effects
				(font
					(size 1.27 1.27)
				)
			)
		)
		(property "Value" ""
			(at 0 0 0)
			(layer "F.Fab")
			(effects
				(font
					(size 1.27 1.27)
				)
			)
		)
		(duplicate_pad_numbers_are_jumpers no)
		(fp_line
			(start -0.7874 -0.4064)
			(end 0.7874 -0.4064)
			(stroke
				(width 0.1524)
				(type default)
			)
			(layer "F.SilkS")
		)
		(fp_line
			(start -0.7874 0.4064)
			(end -0.7874 -0.4064)
			(stroke
				(width 0.1524)
				(type default)
			)
			(layer "F.SilkS")
		)
		(fp_line
			(start 0.7874 -0.4064)
			(end 0.7874 0.4064)
			(stroke
				(width 0.1524)
				(type default)
			)
			(layer "F.SilkS")
		)
		(fp_line
			(start 0.7874 0.4064)
			(end -0.7874 0.4064)
			(stroke
				(width 0.1524)
				(type default)
			)
			(layer "F.SilkS")
		)
		(fp_line
			(start -0.67945 -0.305054)
			(end -0.12065 -0.305054)
			(stroke
				(width 0.1)
				(type default)
			)
			(layer "F.Fab")
		)
		(fp_line
			(start -0.67945 0.3048)
			(end -0.67945 -0.305054)
			(stroke
				(width 0.1)
				(type default)
			)
			(layer "F.Fab")
		)
		(fp_line
			(start -0.12065 -0.305054)
			(end -0.12065 -0.2794)
			(stroke
				(width 0.1)
				(type default)
			)
			(layer "F.Fab")
		)
		(fp_line
			(start -0.12065 -0.2794)
			(end 0.12065 -0.2794)
			(stroke
				(width 0.1)
				(type default)
			)
			(layer "F.Fab")
		)
		(fp_line
			(start -0.12065 0.2794)
			(end -0.12065 0.3048)
			(stroke
				(width 0.1)
				(type default)
			)
			(layer "F.Fab")
		)
		(fp_line
			(start -0.12065 0.3048)
			(end -0.67945 0.3048)
			(stroke
				(width 0.1)
				(type default)
			)
			(layer "F.Fab")
		)
		(fp_line
			(start 0.120396 0.2794)
			(end -0.12065 0.2794)
			(stroke
				(width 0.1)
				(type default)
			)
			(layer "F.Fab")
		)
		(fp_line
			(start 0.120396 0.3048)
			(end 0.120396 0.2794)
			(stroke
				(width 0.1)
				(type default)
			)
			(layer "F.Fab")
		)
		(fp_line
			(start 0.12065 -0.3048)
			(end 0.67945 -0.3048)
			(stroke
				(width 0.1)
				(type default)
			)
			(layer "F.Fab")
		)
		(fp_line
			(start 0.12065 -0.2794)
			(end 0.12065 -0.3048)
			(stroke
				(width 0.1)
				(type default)
			)
			(layer "F.Fab")
		)
		(fp_line
			(start 0.67945 -0.3048)
			(end 0.67945 0.3048)
			(stroke
				(width 0.1)
				(type default)
			)
			(layer "F.Fab")
		)
		(fp_line
			(start 0.67945 0.3048)
			(end 0.120396 0.3048)
			(stroke
				(width 0.1)
				(type default)
			)
			(layer "F.Fab")
		)
		(pad "1" smd circle
			(at -0.40005 0)
			(size 0 0)
			(layers "F.Cu" "F.Mask" "F.Paste")
			(net "P52V_FAN_7_BUFF_EN")
		)
		(pad "2" smd circle
			(at 0.40005 0)
			(size 0 0)
			(layers "F.Cu" "F.Mask" "F.Paste")
			(net "P52V_FAN_7_BUFF_EN_R")
		)
	)
	(footprint ""
		(layer "F.Cu")
		(at 35.179 -162.941 90)
		(property "Reference" "R5269"
			(at 0 0 90)
			(layer "F.SilkS")
			(hide yes)
			(effects
				(font
					(size 1.27 1.27)
				)
			)
		)
		(property "Value" ""
			(at 0 0 90)
			(layer "F.Fab")
			(effects
				(font
					(size 1.27 1.27)
				)
			)
		)
		(duplicate_pad_numbers_are_jumpers no)
		(fp_line
			(start 0.7874 -0.4064)
			(end 0.7874 0.4064)
			(stroke
				(width 0.1524)
				(type default)
			)
			(layer "F.SilkS")
		)
		(fp_line
			(start -0.7874 -0.4064)
			(end 0.7874 -0.4064)
			(stroke
				(width 0.1524)
				(type default)
			)
			(layer "F.SilkS")
		)
		(fp_line
			(start 0.7874 0.4064)
			(end -0.7874 0.4064)
			(stroke
				(width 0.1524)
				(type default)
			)
			(layer "F.SilkS")
		)
		(fp_line
			(start -0.7874 0.4064)
			(end -0.7874 -0.4064)
			(stroke
				(width 0.1524)
				(type default)
			)
			(layer "F.SilkS")
		)
		(fp_line
			(start -0.12065 -0.305054)
			(end -0.12065 -0.2794)
			(stroke
				(width 0.1)
				(type default)
			)
			(layer "F.Fab")
		)
		(fp_line
			(start -0.67945 -0.305054)
			(end -0.12065 -0.305054)
			(stroke
				(width 0.1)
				(type default)
			)
			(layer "F.Fab")
		)
		(fp_line
			(start 0.67945 -0.3048)
			(end 0.67945 0.3048)
			(stroke
				(width 0.1)
				(type default)
			)
			(layer "F.Fab")
		)
		(fp_line
			(start 0.12065 -0.3048)
			(end 0.67945 -0.3048)
			(stroke
				(width 0.1)
				(type default)
			)
			(layer "F.Fab")
		)
		(fp_line
			(start 0.12065 -0.2794)
			(end 0.12065 -0.3048)
			(stroke
				(width 0.1)
				(type default)
			)
			(layer "F.Fab")
		)
		(fp_line
			(start -0.12065 -0.2794)
			(end 0.12065 -0.2794)
			(stroke
				(width 0.1)
				(type default)
			)
			(layer "F.Fab")
		)
		(fp_line
			(start 0.120396 0.2794)
			(end -0.12065 0.2794)
			(stroke
				(width 0.1)
				(type default)
			)
			(layer "F.Fab")
		)
		(fp_line
			(start -0.12065 0.2794)
			(end -0.12065 0.3048)
			(stroke
				(width 0.1)
				(type default)
			)
			(layer "F.Fab")
		)
		(fp_line
			(start 0.67945 0.3048)
			(end 0.120396 0.3048)
			(stroke
				(width 0.1)
				(type default)
			)
			(layer "F.Fab")
		)
		(fp_line
			(start 0.120396 0.3048)
			(end 0.120396 0.2794)
			(stroke
				(width 0.1)
				(type default)
			)
			(layer "F.Fab")
		)
		(fp_line
			(start -0.12065 0.3048)
			(end -0.67945 0.3048)
			(stroke
				(width 0.1)
				(type default)
			)
			(layer "F.Fab")
		)
		(fp_line
			(start -0.67945 0.3048)
			(end -0.67945 -0.305054)
			(stroke
				(width 0.1)
				(type default)
			)
			(layer "F.Fab")
		)
		(pad "1" smd circle
			(at -0.40005 0 90)
			(size 0 0)
			(layers "F.Cu" "F.Mask" "F.Paste")
			(net "SMB_FAN4_R_SDA")
		)
		(pad "2" smd circle
			(at 0.40005 0 90)
			(size 0 0)
			(layers "F.Cu" "F.Mask" "F.Paste")
			(net "P3V3_AUX")
		)
	)
	(footprint ""
		(layer "F.Cu")
		(at 37.211 -199.771)
		(property "Reference" "R5402"
			(at 0 0 0)
			(layer "F.SilkS")
			(hide yes)
			(effects
				(font
					(size 1.27 1.27)
				)
			)
		)
		(property "Value" ""
			(at 0 0 0)
			(layer "F.Fab")
			(effects
				(font
					(size 1.27 1.27)
				)
			)
		)
		(duplicate_pad_numbers_are_jumpers no)
		(fp_line
			(start -0.7874 -0.4064)
			(end 0.7874 -0.4064)
			(stroke
				(width 0.1524)
				(type default)
			)
			(layer "F.SilkS")
		)
		(fp_line
			(start -0.7874 0.4064)
			(end -0.7874 -0.4064)
			(stroke
				(width 0.1524)
				(type default)
			)
			(layer "F.SilkS")
		)
		(fp_line
			(start 0.7874 -0.4064)
			(end 0.7874 0.4064)
			(stroke
				(width 0.1524)
				(type default)
			)
			(layer "F.SilkS")
		)
		(fp_line
			(start 0.7874 0.4064)
			(end -0.7874 0.4064)
			(stroke
				(width 0.1524)
				(type default)
			)
			(layer "F.SilkS")
		)
		(fp_line
			(start -0.67945 -0.305054)
			(end -0.12065 -0.305054)
			(stroke
				(width 0.1)
				(type default)
			)
			(layer "F.Fab")
		)
		(fp_line
			(start -0.67945 0.3048)
			(end -0.67945 -0.305054)
			(stroke
				(width 0.1)
				(type default)
			)
			(layer "F.Fab")
		)
		(fp_line
			(start -0.12065 -0.305054)
			(end -0.12065 -0.2794)
			(stroke
				(width 0.1)
				(type default)
			)
			(layer "F.Fab")
		)
		(fp_line
			(start -0.12065 -0.2794)
			(end 0.12065 -0.2794)
			(stroke
				(width 0.1)
				(type default)
			)
			(layer "F.Fab")
		)
		(fp_line
			(start -0.12065 0.2794)
			(end -0.12065 0.3048)
			(stroke
				(width 0.1)
				(type default)
			)
			(layer "F.Fab")
		)
		(fp_line
			(start -0.12065 0.3048)
			(end -0.67945 0.3048)
			(stroke
				(width 0.1)
				(type default)
			)
			(layer "F.Fab")
		)
		(fp_line
			(start 0.120396 0.2794)
			(end -0.12065 0.2794)
			(stroke
				(width 0.1)
				(type default)
			)
			(layer "F.Fab")
		)
		(fp_line
			(start 0.120396 0.3048)
			(end 0.120396 0.2794)
			(stroke
				(width 0.1)
				(type default)
			)
			(layer "F.Fab")
		)
		(fp_line
			(start 0.12065 -0.3048)
			(end 0.67945 -0.3048)
			(stroke
				(width 0.1)
				(type default)
			)
			(layer "F.Fab")
		)
		(fp_line
			(start 0.12065 -0.2794)
			(end 0.12065 -0.3048)
			(stroke
				(width 0.1)
				(type default)
			)
			(layer "F.Fab")
		)
		(fp_line
			(start 0.67945 -0.3048)
			(end 0.67945 0.3048)
			(stroke
				(width 0.1)
				(type default)
			)
			(layer "F.Fab")
		)
		(fp_line
			(start 0.67945 0.3048)
			(end 0.120396 0.3048)
			(stroke
				(width 0.1)
				(type default)
			)
			(layer "F.Fab")
		)
		(pad "1" smd rect
			(at -0.40005 0 180)
			(size 0.4572 0.508)
			(layers "F.Cu" "F.Mask" "F.Paste")
			(net "FAN_1_OK_LED_R_N")
		)
		(pad "2" smd rect
			(at 0.40005 0 180)
			(size 0.4572 0.508)
			(layers "F.Cu" "F.Mask" "F.Paste")
			(net "FAN_1_OK_R_LED_N")
		)
	)
	(footprint ""
		(layer "F.Cu")
		(at 29.21 -104.648 -90)
		(property "Reference" "U400"
			(at -2.667 -1.16967 90)
			(unlocked yes)
			(layer "F.SilkS")
			(effects
				(font
					(size 0.7874 0.5842)
					(thickness 0.1524)
				)
				(justify left)
			)
		)
		(property "Value" ""
			(at 0 0 270)
			(layer "F.Fab")
			(effects
				(font
					(size 1.27 1.27)
				)
			)
		)
		(duplicate_pad_numbers_are_jumpers no)
		(fp_line
			(start -1.33096 1.100074)
			(end -1.33096 -1.100074)
			(stroke
				(width 0.1524)
				(type default)
			)
			(layer "F.SilkS")
		)
		(fp_line
			(start 1.33096 1.100074)
			(end -1.33096 1.100074)
			(stroke
				(width 0.1524)
				(type default)
			)
			(layer "F.SilkS")
		)
		(fp_line
			(start 0 -0.649986)
			(end 0.381 -1.100074)
			(stroke
				(width 0.1524)
				(type default)
			)
			(layer "F.SilkS")
		)
		(fp_line
			(start -1.33096 -1.100074)
			(end -0.381 -1.100074)
			(stroke
				(width 0.1524)
				(type default)
			)
			(layer "F.SilkS")
		)
		(fp_line
			(start -0.381 -1.100074)
			(end 0 -0.649986)
			(stroke
				(width 0.1524)
				(type default)
			)
			(layer "F.SilkS")
		)
		(fp_line
			(start 0.381 -1.100074)
			(end 1.33096 -1.100074)
			(stroke
				(width 0.1524)
				(type default)
			)
			(layer "F.SilkS")
		)
		(fp_line
			(start 1.33096 -1.100074)
			(end 1.33096 1.100074)
			(stroke
				(width 0.1524)
				(type default)
			)
			(layer "F.SilkS")
		)
		(fp_poly
			(pts
				(xy -2.209292 -1.029462) (xy -2.209292 -0.521462) (xy -1.447292 -0.775462)
			)
			(stroke
				(width 0)
				(type default)
			)
			(fill yes)
			(layer "F.SilkS")
		)
		(fp_line
			(start -0.674878 1.100074)
			(end -0.674878 -1.100074)
			(stroke
				(width 0.1)
				(type default)
			)
			(layer "F.Fab")
		)
		(fp_line
			(start 0.674878 1.100074)
			(end -0.674878 1.100074)
			(stroke
				(width 0.1)
				(type default)
			)
			(layer "F.Fab")
		)
		(fp_line
			(start -0.674878 -1.100074)
			(end 0.674878 -1.100074)
			(stroke
				(width 0.1)
				(type default)
			)
			(layer "F.Fab")
		)
		(fp_line
			(start 0.674878 -1.100074)
			(end 0.674878 1.100074)
			(stroke
				(width 0.1)
				(type default)
			)
			(layer "F.Fab")
		)
		(fp_poly
			(pts
				(xy -2.209292 -0.902462) (xy -2.209292 -0.394462) (xy -1.447292 -0.648462)
			)
			(stroke
				(width 0)
				(type default)
			)
			(fill yes)
			(layer "F.Fab")
		)
		(pad "1" smd rect
			(at -0.94996 -0.649986)
			(size 0.4064 0.508)
			(layers "F.Cu" "F.Mask" "F.Paste")
			(net "NC_U400_P1")
		)
		(pad "2" smd rect
			(at -0.94996 0)
			(size 0.4064 0.508)
			(layers "F.Cu" "F.Mask" "F.Paste")
			(net "FAN_5_PWM")
		)
		(pad "3" smd rect
			(at -0.94996 0.649986)
			(size 0.4064 0.508)
			(layers "F.Cu" "F.Mask" "F.Paste")
			(net "GND")
		)
		(pad "4" smd rect
			(at 0.94996 0.649986)
			(size 0.4064 0.508)
			(layers "F.Cu" "F.Mask" "F.Paste")
			(net "FAN_5_PWM_BUF")
		)
		(pad "5" smd rect
			(at 0.94996 -0.649986)
			(size 0.4064 0.508)
			(layers "F.Cu" "F.Mask" "F.Paste")
			(net "P3V3_AUX")
		)
	)
	(footprint ""
		(layer "F.Cu")
		(at 2.794 -189.992)
		(property "Reference" "R317"
			(at 0 0 0)
			(layer "F.SilkS")
			(hide yes)
			(effects
				(font
					(size 1.27 1.27)
				)
			)
		)
		(property "Value" ""
			(at 0 0 0)
			(layer "F.Fab")
			(effects
				(font
					(size 1.27 1.27)
				)
			)
		)
		(duplicate_pad_numbers_are_jumpers no)
		(fp_line
			(start -0.7874 -0.4064)
			(end 0.7874 -0.4064)
			(stroke
				(width 0.1524)
				(type default)
			)
			(layer "F.SilkS")
		)
		(fp_line
			(start -0.7874 0.4064)
			(end -0.7874 -0.4064)
			(stroke
				(width 0.1524)
				(type default)
			)
			(layer "F.SilkS")
		)
		(fp_line
			(start 0.7874 -0.4064)
			(end 0.7874 0.4064)
			(stroke
				(width 0.1524)
				(type default)
			)
			(layer "F.SilkS")
		)
		(fp_line
			(start 0.7874 0.4064)
			(end -0.7874 0.4064)
			(stroke
				(width 0.1524)
				(type default)
			)
			(layer "F.SilkS")
		)
		(fp_line
			(start -0.67945 -0.305054)
			(end -0.12065 -0.305054)
			(stroke
				(width 0.1)
				(type default)
			)
			(layer "F.Fab")
		)
		(fp_line
			(start -0.67945 0.3048)
			(end -0.67945 -0.305054)
			(stroke
				(width 0.1)
				(type default)
			)
			(layer "F.Fab")
		)
		(fp_line
			(start -0.12065 -0.305054)
			(end -0.12065 -0.2794)
			(stroke
				(width 0.1)
				(type default)
			)
			(layer "F.Fab")
		)
		(fp_line
			(start -0.12065 -0.2794)
			(end 0.12065 -0.2794)
			(stroke
				(width 0.1)
				(type default)
			)
			(layer "F.Fab")
		)
		(fp_line
			(start -0.12065 0.2794)
			(end -0.12065 0.3048)
			(stroke
				(width 0.1)
				(type default)
			)
			(layer "F.Fab")
		)
		(fp_line
			(start -0.12065 0.3048)
			(end -0.67945 0.3048)
			(stroke
				(width 0.1)
				(type default)
			)
			(layer "F.Fab")
		)
		(fp_line
			(start 0.120396 0.2794)
			(end -0.12065 0.2794)
			(stroke
				(width 0.1)
				(type default)
			)
			(layer "F.Fab")
		)
		(fp_line
			(start 0.120396 0.3048)
			(end 0.120396 0.2794)
			(stroke
				(width 0.1)
				(type default)
			)
			(layer "F.Fab")
		)
		(fp_line
			(start 0.12065 -0.3048)
			(end 0.67945 -0.3048)
			(stroke
				(width 0.1)
				(type default)
			)
			(layer "F.Fab")
		)
		(fp_line
			(start 0.12065 -0.2794)
			(end 0.12065 -0.3048)
			(stroke
				(width 0.1)
				(type default)
			)
			(layer "F.Fab")
		)
		(fp_line
			(start 0.67945 -0.3048)
			(end 0.67945 0.3048)
			(stroke
				(width 0.1)
				(type default)
			)
			(layer "F.Fab")
		)
		(fp_line
			(start 0.67945 0.3048)
			(end 0.120396 0.3048)
			(stroke
				(width 0.1)
				(type default)
			)
			(layer "F.Fab")
		)
		(pad "1" smd circle
			(at -0.40005 0)
			(size 0 0)
			(layers "F.Cu" "F.Mask" "F.Paste")
			(net "GND")
		)
		(pad "2" smd circle
			(at 0.40005 0)
			(size 0 0)
			(layers "F.Cu" "F.Mask" "F.Paste")
			(net "FRU_ADDR0")
		)
	)
	(footprint ""
		(layer "F.Cu")
		(at 34.417 -295.148)
		(property "Reference" "U369"
			(at -5.588 -1.49733 0)
			(unlocked yes)
			(layer "F.SilkS")
			(effects
				(font
					(size 0.7874 0.5842)
					(thickness 0.1524)
				)
				(justify left)
			)
		)
		(property "Value" ""
			(at 0 0 0)
			(layer "F.Fab")
			(effects
				(font
					(size 1.27 1.27)
				)
			)
		)
		(duplicate_pad_numbers_are_jumpers no)
		(fp_line
			(start -1.335278 -1.100074)
			(end -1.335278 1.100074)
			(stroke
				(width 0.1524)
				(type default)
			)
			(layer "F.SilkS")
		)
		(fp_line
			(start -1.335278 1.100074)
			(end 1.335278 1.100074)
			(stroke
				(width 0.1524)
				(type default)
			)
			(layer "F.SilkS")
		)
		(fp_line
			(start 1.335278 -1.100074)
			(end -1.335278 -1.100074)
			(stroke
				(width 0.1524)
				(type default)
			)
			(layer "F.SilkS")
		)
		(fp_line
			(start 1.335278 1.100074)
			(end 1.335278 -1.100074)
			(stroke
				(width 0.1524)
				(type default)
			)
			(layer "F.SilkS")
		)
		(fp_line
			(start -0.674878 -1.100074)
			(end -0.674878 1.100074)
			(stroke
				(width 0.1)
				(type default)
			)
			(layer "F.Fab")
		)
		(fp_line
			(start -0.674878 1.100074)
			(end 0.674878 1.100074)
			(stroke
				(width 0.1)
				(type default)
			)
			(layer "F.Fab")
		)
		(fp_line
			(start 0.674878 -1.100074)
			(end -0.674878 -1.100074)
			(stroke
				(width 0.1)
				(type default)
			)
			(layer "F.Fab")
		)
		(fp_line
			(start 0.674878 1.100074)
			(end 0.674878 -1.100074)
			(stroke
				(width 0.1)
				(type default)
			)
			(layer "F.Fab")
		)
		(pad "D" smd rect
			(at 0.8001 0 270)
			(size 0.6096 0.8128)
			(layers "F.Cu" "F.Mask" "F.Paste")
			(net "FAN_0_FAIL_LED_R_N")
		)
		(pad "G" smd rect
			(at -0.8001 -0.649986 270)
			(size 0.6096 0.8128)
			(layers "F.Cu" "F.Mask" "F.Paste")
			(net "FAN_0_FAIL_R_LED")
		)
		(pad "S" smd rect
			(at -0.8001 0.649986 270)
			(size 0.6096 0.8128)
			(layers "F.Cu" "F.Mask" "F.Paste")
			(net "GND")
		)
	)
	(footprint ""
		(layer "F.Cu")
		(at 25.527 -126.619 180)
		(property "Reference" "R4954"
			(at 0 0 180)
			(layer "F.SilkS")
			(hide yes)
			(effects
				(font
					(size 1.27 1.27)
				)
			)
		)
		(property "Value" ""
			(at 0 0 180)
			(layer "F.Fab")
			(effects
				(font
					(size 1.27 1.27)
				)
			)
		)
		(duplicate_pad_numbers_are_jumpers no)
		(fp_line
			(start 0.7874 0.4064)
			(end -0.7874 0.4064)
			(stroke
				(width 0.1524)
				(type default)
			)
			(layer "F.SilkS")
		)
		(fp_line
			(start 0.7874 -0.4064)
			(end 0.7874 0.4064)
			(stroke
				(width 0.1524)
				(type default)
			)
			(layer "F.SilkS")
		)
		(fp_line
			(start -0.7874 0.4064)
			(end -0.7874 -0.4064)
			(stroke
				(width 0.1524)
				(type default)
			)
			(layer "F.SilkS")
		)
		(fp_line
			(start -0.7874 -0.4064)
			(end 0.7874 -0.4064)
			(stroke
				(width 0.1524)
				(type default)
			)
			(layer "F.SilkS")
		)
		(fp_line
			(start 0.67945 0.3048)
			(end 0.120396 0.3048)
			(stroke
				(width 0.1)
				(type default)
			)
			(layer "F.Fab")
		)
		(fp_line
			(start 0.67945 -0.3048)
			(end 0.67945 0.3048)
			(stroke
				(width 0.1)
				(type default)
			)
			(layer "F.Fab")
		)
		(fp_line
			(start 0.12065 -0.2794)
			(end 0.12065 -0.3048)
			(stroke
				(width 0.1)
				(type default)
			)
			(layer "F.Fab")
		)
		(fp_line
			(start 0.12065 -0.3048)
			(end 0.67945 -0.3048)
			(stroke
				(width 0.1)
				(type default)
			)
			(layer "F.Fab")
		)
		(fp_line
			(start 0.120396 0.3048)
			(end 0.120396 0.2794)
			(stroke
				(width 0.1)
				(type default)
			)
			(layer "F.Fab")
		)
		(fp_line
			(start 0.120396 0.2794)
			(end -0.12065 0.2794)
			(stroke
				(width 0.1)
				(type default)
			)
			(layer "F.Fab")
		)
		(fp_line
			(start -0.12065 0.3048)
			(end -0.67945 0.3048)
			(stroke
				(width 0.1)
				(type default)
			)
			(layer "F.Fab")
		)
		(fp_line
			(start -0.12065 0.2794)
			(end -0.12065 0.3048)
			(stroke
				(width 0.1)
				(type default)
			)
			(layer "F.Fab")
		)
		(fp_line
			(start -0.12065 -0.2794)
			(end 0.12065 -0.2794)
			(stroke
				(width 0.1)
				(type default)
			)
			(layer "F.Fab")
		)
		(fp_line
			(start -0.12065 -0.305054)
			(end -0.12065 -0.2794)
			(stroke
				(width 0.1)
				(type default)
			)
			(layer "F.Fab")
		)
		(fp_line
			(start -0.67945 0.3048)
			(end -0.67945 -0.305054)
			(stroke
				(width 0.1)
				(type default)
			)
			(layer "F.Fab")
		)
		(fp_line
			(start -0.67945 -0.305054)
			(end -0.12065 -0.305054)
			(stroke
				(width 0.1)
				(type default)
			)
			(layer "F.Fab")
		)
		(pad "1" smd circle
			(at -0.40005 0 180)
			(size 0 0)
			(layers "F.Cu" "F.Mask" "F.Paste")
			(net "GND")
		)
		(pad "2" smd circle
			(at 0.40005 0 180)
			(size 0 0)
			(layers "F.Cu" "F.Mask" "F.Paste")
			(net "MAX31790_U330_PWM_START1")
		)
	)
	(footprint ""
		(layer "F.Cu")
		(at 18.679922 -290.2331)
		(property "Reference" "C2058"
			(at 0 0 0)
			(layer "F.SilkS")
			(hide yes)
			(effects
				(font
					(size 1.27 1.27)
				)
			)
		)
		(property "Value" ""
			(at 0 0 0)
			(layer "F.Fab")
			(effects
				(font
					(size 1.27 1.27)
				)
			)
		)
		(duplicate_pad_numbers_are_jumpers no)
		(fp_line
			(start -0.7874 -0.4064)
			(end 0.7874 -0.4064)
			(stroke
				(width 0.1524)
				(type default)
			)
			(layer "F.SilkS")
		)
		(fp_line
			(start -0.7874 0.4064)
			(end -0.7874 -0.4064)
			(stroke
				(width 0.1524)
				(type default)
			)
			(layer "F.SilkS")
		)
		(fp_line
			(start 0.7874 -0.4064)
			(end 0.7874 0.4064)
			(stroke
				(width 0.1524)
				(type default)
			)
			(layer "F.SilkS")
		)
		(fp_line
			(start 0.7874 0.4064)
			(end -0.7874 0.4064)
			(stroke
				(width 0.1524)
				(type default)
			)
			(layer "F.SilkS")
		)
		(fp_line
			(start -0.67945 -0.305054)
			(end -0.12065 -0.305054)
			(stroke
				(width 0.1)
				(type default)
			)
			(layer "F.Fab")
		)
		(fp_line
			(start -0.67945 0.3048)
			(end -0.67945 -0.305054)
			(stroke
				(width 0.1)
				(type default)
			)
			(layer "F.Fab")
		)
		(fp_line
			(start -0.12065 -0.305054)
			(end -0.12065 -0.2794)
			(stroke
				(width 0.1)
				(type default)
			)
			(layer "F.Fab")
		)
		(fp_line
			(start -0.12065 -0.2794)
			(end 0.12065 -0.2794)
			(stroke
				(width 0.1)
				(type default)
			)
			(layer "F.Fab")
		)
		(fp_line
			(start -0.12065 0.2794)
			(end -0.12065 0.3048)
			(stroke
				(width 0.1)
				(type default)
			)
			(layer "F.Fab")
		)
		(fp_line
			(start -0.12065 0.3048)
			(end -0.67945 0.3048)
			(stroke
				(width 0.1)
				(type default)
			)
			(layer "F.Fab")
		)
		(fp_line
			(start 0.120396 0.2794)
			(end -0.12065 0.2794)
			(stroke
				(width 0.1)
				(type default)
			)
			(layer "F.Fab")
		)
		(fp_line
			(start 0.120396 0.3048)
			(end 0.120396 0.2794)
			(stroke
				(width 0.1)
				(type default)
			)
			(layer "F.Fab")
		)
		(fp_line
			(start 0.12065 -0.3048)
			(end 0.67945 -0.3048)
			(stroke
				(width 0.1)
				(type default)
			)
			(layer "F.Fab")
		)
		(fp_line
			(start 0.12065 -0.2794)
			(end 0.12065 -0.3048)
			(stroke
				(width 0.1)
				(type default)
			)
			(layer "F.Fab")
		)
		(fp_line
			(start 0.67945 -0.3048)
			(end 0.67945 0.3048)
			(stroke
				(width 0.1)
				(type default)
			)
			(layer "F.Fab")
		)
		(fp_line
			(start 0.67945 0.3048)
			(end 0.120396 0.3048)
			(stroke
				(width 0.1)
				(type default)
			)
			(layer "F.Fab")
		)
		(pad "1" smd circle
			(at -0.40005 0)
			(size 0 0)
			(layers "F.Cu" "F.Mask" "F.Paste")
			(net "FAN_7_TACH_IL_R")
		)
		(pad "2" smd circle
			(at 0.40005 0)
			(size 0 0)
			(layers "F.Cu" "F.Mask" "F.Paste")
			(net "GND")
		)
	)
	(footprint ""
		(layer "F.Cu")
		(at 4.191 -169.291 180)
		(property "Reference" "R4855"
			(at 0 0 180)
			(layer "F.SilkS")
			(hide yes)
			(effects
				(font
					(size 1.27 1.27)
				)
			)
		)
		(property "Value" ""
			(at 0 0 180)
			(layer "F.Fab")
			(effects
				(font
					(size 1.27 1.27)
				)
			)
		)
		(duplicate_pad_numbers_are_jumpers no)
		(fp_line
			(start 0.7874 0.4064)
			(end -0.7874 0.4064)
			(stroke
				(width 0.1524)
				(type default)
			)
			(layer "F.SilkS")
		)
		(fp_line
			(start 0.7874 -0.4064)
			(end 0.7874 0.4064)
			(stroke
				(width 0.1524)
				(type default)
			)
			(layer "F.SilkS")
		)
		(fp_line
			(start -0.7874 0.4064)
			(end -0.7874 -0.4064)
			(stroke
				(width 0.1524)
				(type default)
			)
			(layer "F.SilkS")
		)
		(fp_line
			(start -0.7874 -0.4064)
			(end 0.7874 -0.4064)
			(stroke
				(width 0.1524)
				(type default)
			)
			(layer "F.SilkS")
		)
		(fp_line
			(start 0.67945 0.3048)
			(end 0.120396 0.3048)
			(stroke
				(width 0.1)
				(type default)
			)
			(layer "F.Fab")
		)
		(fp_line
			(start 0.67945 -0.3048)
			(end 0.67945 0.3048)
			(stroke
				(width 0.1)
				(type default)
			)
			(layer "F.Fab")
		)
		(fp_line
			(start 0.12065 -0.2794)
			(end 0.12065 -0.3048)
			(stroke
				(width 0.1)
				(type default)
			)
			(layer "F.Fab")
		)
		(fp_line
			(start 0.12065 -0.3048)
			(end 0.67945 -0.3048)
			(stroke
				(width 0.1)
				(type default)
			)
			(layer "F.Fab")
		)
		(fp_line
			(start 0.120396 0.3048)
			(end 0.120396 0.2794)
			(stroke
				(width 0.1)
				(type default)
			)
			(layer "F.Fab")
		)
		(fp_line
			(start 0.120396 0.2794)
			(end -0.12065 0.2794)
			(stroke
				(width 0.1)
				(type default)
			)
			(layer "F.Fab")
		)
		(fp_line
			(start -0.12065 0.3048)
			(end -0.67945 0.3048)
			(stroke
				(width 0.1)
				(type default)
			)
			(layer "F.Fab")
		)
		(fp_line
			(start -0.12065 0.2794)
			(end -0.12065 0.3048)
			(stroke
				(width 0.1)
				(type default)
			)
			(layer "F.Fab")
		)
		(fp_line
			(start -0.12065 -0.2794)
			(end 0.12065 -0.2794)
			(stroke
				(width 0.1)
				(type default)
			)
			(layer "F.Fab")
		)
		(fp_line
			(start -0.12065 -0.305054)
			(end -0.12065 -0.2794)
			(stroke
				(width 0.1)
				(type default)
			)
			(layer "F.Fab")
		)
		(fp_line
			(start -0.67945 0.3048)
			(end -0.67945 -0.305054)
			(stroke
				(width 0.1)
				(type default)
			)
			(layer "F.Fab")
		)
		(fp_line
			(start -0.67945 -0.305054)
			(end -0.12065 -0.305054)
			(stroke
				(width 0.1)
				(type default)
			)
			(layer "F.Fab")
		)
		(pad "1" smd circle
			(at -0.40005 0 180)
			(size 0 0)
			(layers "F.Cu" "F.Mask" "F.Paste")
			(net "FAN_4_PRSNT_BUF_R_N")
		)
		(pad "2" smd circle
			(at 0.40005 0 180)
			(size 0 0)
			(layers "F.Cu" "F.Mask" "F.Paste")
			(net "FAN_4_PRSNT_BUF_N")
		)
	)
	(footprint ""
		(layer "F.Cu")
		(at 28.956 -162.941 90)
		(property "Reference" "R5270"
			(at 0 0 90)
			(layer "F.SilkS")
			(hide yes)
			(effects
				(font
					(size 1.27 1.27)
				)
			)
		)
		(property "Value" ""
			(at 0 0 90)
			(layer "F.Fab")
			(effects
				(font
					(size 1.27 1.27)
				)
			)
		)
		(duplicate_pad_numbers_are_jumpers no)
		(fp_line
			(start 0.7874 -0.4064)
			(end 0.7874 0.4064)
			(stroke
				(width 0.1524)
				(type default)
			)
			(layer "F.SilkS")
		)
		(fp_line
			(start -0.7874 -0.4064)
			(end 0.7874 -0.4064)
			(stroke
				(width 0.1524)
				(type default)
			)
			(layer "F.SilkS")
		)
		(fp_line
			(start 0.7874 0.4064)
			(end -0.7874 0.4064)
			(stroke
				(width 0.1524)
				(type default)
			)
			(layer "F.SilkS")
		)
		(fp_line
			(start -0.7874 0.4064)
			(end -0.7874 -0.4064)
			(stroke
				(width 0.1524)
				(type default)
			)
			(layer "F.SilkS")
		)
		(fp_line
			(start -0.12065 -0.305054)
			(end -0.12065 -0.2794)
			(stroke
				(width 0.1)
				(type default)
			)
			(layer "F.Fab")
		)
		(fp_line
			(start -0.67945 -0.305054)
			(end -0.12065 -0.305054)
			(stroke
				(width 0.1)
				(type default)
			)
			(layer "F.Fab")
		)
		(fp_line
			(start 0.67945 -0.3048)
			(end 0.67945 0.3048)
			(stroke
				(width 0.1)
				(type default)
			)
			(layer "F.Fab")
		)
		(fp_line
			(start 0.12065 -0.3048)
			(end 0.67945 -0.3048)
			(stroke
				(width 0.1)
				(type default)
			)
			(layer "F.Fab")
		)
		(fp_line
			(start 0.12065 -0.2794)
			(end 0.12065 -0.3048)
			(stroke
				(width 0.1)
				(type default)
			)
			(layer "F.Fab")
		)
		(fp_line
			(start -0.12065 -0.2794)
			(end 0.12065 -0.2794)
			(stroke
				(width 0.1)
				(type default)
			)
			(layer "F.Fab")
		)
		(fp_line
			(start 0.120396 0.2794)
			(end -0.12065 0.2794)
			(stroke
				(width 0.1)
				(type default)
			)
			(layer "F.Fab")
		)
		(fp_line
			(start -0.12065 0.2794)
			(end -0.12065 0.3048)
			(stroke
				(width 0.1)
				(type default)
			)
			(layer "F.Fab")
		)
		(fp_line
			(start 0.67945 0.3048)
			(end 0.120396 0.3048)
			(stroke
				(width 0.1)
				(type default)
			)
			(layer "F.Fab")
		)
		(fp_line
			(start 0.120396 0.3048)
			(end 0.120396 0.2794)
			(stroke
				(width 0.1)
				(type default)
			)
			(layer "F.Fab")
		)
		(fp_line
			(start -0.12065 0.3048)
			(end -0.67945 0.3048)
			(stroke
				(width 0.1)
				(type default)
			)
			(layer "F.Fab")
		)
		(fp_line
			(start -0.67945 0.3048)
			(end -0.67945 -0.305054)
			(stroke
				(width 0.1)
				(type default)
			)
			(layer "F.Fab")
		)
		(pad "1" smd circle
			(at -0.40005 0 90)
			(size 0 0)
			(layers "F.Cu" "F.Mask" "F.Paste")
			(net "SMB_FAN5_R_SCL")
		)
		(pad "2" smd circle
			(at 0.40005 0 90)
			(size 0 0)
			(layers "F.Cu" "F.Mask" "F.Paste")
			(net "P3V3_AUX")
		)
	)
	(footprint ""
		(layer "F.Cu")
		(at 4.191 -166.116 180)
		(property "Reference" "R104"
			(at 0 0 180)
			(layer "F.SilkS")
			(hide yes)
			(effects
				(font
					(size 1.27 1.27)
				)
			)
		)
		(property "Value" ""
			(at 0 0 180)
			(layer "F.Fab")
			(effects
				(font
					(size 1.27 1.27)
				)
			)
		)
		(duplicate_pad_numbers_are_jumpers no)
		(fp_line
			(start 0.7874 0.4064)
			(end -0.7874 0.4064)
			(stroke
				(width 0.1524)
				(type default)
			)
			(layer "F.SilkS")
		)
		(fp_line
			(start 0.7874 -0.4064)
			(end 0.7874 0.4064)
			(stroke
				(width 0.1524)
				(type default)
			)
			(layer "F.SilkS")
		)
		(fp_line
			(start -0.7874 0.4064)
			(end -0.7874 -0.4064)
			(stroke
				(width 0.1524)
				(type default)
			)
			(layer "F.SilkS")
		)
		(fp_line
			(start -0.7874 -0.4064)
			(end 0.7874 -0.4064)
			(stroke
				(width 0.1524)
				(type default)
			)
			(layer "F.SilkS")
		)
		(fp_line
			(start 0.67945 0.3048)
			(end 0.120396 0.3048)
			(stroke
				(width 0.1)
				(type default)
			)
			(layer "F.Fab")
		)
		(fp_line
			(start 0.67945 -0.3048)
			(end 0.67945 0.3048)
			(stroke
				(width 0.1)
				(type default)
			)
			(layer "F.Fab")
		)
		(fp_line
			(start 0.12065 -0.2794)
			(end 0.12065 -0.3048)
			(stroke
				(width 0.1)
				(type default)
			)
			(layer "F.Fab")
		)
		(fp_line
			(start 0.12065 -0.3048)
			(end 0.67945 -0.3048)
			(stroke
				(width 0.1)
				(type default)
			)
			(layer "F.Fab")
		)
		(fp_line
			(start 0.120396 0.3048)
			(end 0.120396 0.2794)
			(stroke
				(width 0.1)
				(type default)
			)
			(layer "F.Fab")
		)
		(fp_line
			(start 0.120396 0.2794)
			(end -0.12065 0.2794)
			(stroke
				(width 0.1)
				(type default)
			)
			(layer "F.Fab")
		)
		(fp_line
			(start -0.12065 0.3048)
			(end -0.67945 0.3048)
			(stroke
				(width 0.1)
				(type default)
			)
			(layer "F.Fab")
		)
		(fp_line
			(start -0.12065 0.2794)
			(end -0.12065 0.3048)
			(stroke
				(width 0.1)
				(type default)
			)
			(layer "F.Fab")
		)
		(fp_line
			(start -0.12065 -0.2794)
			(end 0.12065 -0.2794)
			(stroke
				(width 0.1)
				(type default)
			)
			(layer "F.Fab")
		)
		(fp_line
			(start -0.12065 -0.305054)
			(end -0.12065 -0.2794)
			(stroke
				(width 0.1)
				(type default)
			)
			(layer "F.Fab")
		)
		(fp_line
			(start -0.67945 0.3048)
			(end -0.67945 -0.305054)
			(stroke
				(width 0.1)
				(type default)
			)
			(layer "F.Fab")
		)
		(fp_line
			(start -0.67945 -0.305054)
			(end -0.12065 -0.305054)
			(stroke
				(width 0.1)
				(type default)
			)
			(layer "F.Fab")
		)
		(pad "1" smd circle
			(at -0.40005 0 180)
			(size 0 0)
			(layers "F.Cu" "F.Mask" "F.Paste")
			(net "FAN_2_PRSNT_BUF_R_N")
		)
		(pad "2" smd circle
			(at 0.40005 0 180)
			(size 0 0)
			(layers "F.Cu" "F.Mask" "F.Paste")
			(net "FAN_2_PRSNT_BUF_N")
		)
	)
	(footprint ""
		(layer "F.Cu")
		(at 4.191 -172.847 180)
		(property "Reference" "R4863"
			(at 0 0 180)
			(layer "F.SilkS")
			(hide yes)
			(effects
				(font
					(size 1.27 1.27)
				)
			)
		)
		(property "Value" ""
			(at 0 0 180)
			(layer "F.Fab")
			(effects
				(font
					(size 1.27 1.27)
				)
			)
		)
		(duplicate_pad_numbers_are_jumpers no)
		(fp_line
			(start 0.7874 0.4064)
			(end -0.7874 0.4064)
			(stroke
				(width 0.1524)
				(type default)
			)
			(layer "F.SilkS")
		)
		(fp_line
			(start 0.7874 -0.4064)
			(end 0.7874 0.4064)
			(stroke
				(width 0.1524)
				(type default)
			)
			(layer "F.SilkS")
		)
		(fp_line
			(start -0.7874 0.4064)
			(end -0.7874 -0.4064)
			(stroke
				(width 0.1524)
				(type default)
			)
			(layer "F.SilkS")
		)
		(fp_line
			(start -0.7874 -0.4064)
			(end 0.7874 -0.4064)
			(stroke
				(width 0.1524)
				(type default)
			)
			(layer "F.SilkS")
		)
		(fp_line
			(start 0.67945 0.3048)
			(end 0.120396 0.3048)
			(stroke
				(width 0.1)
				(type default)
			)
			(layer "F.Fab")
		)
		(fp_line
			(start 0.67945 -0.3048)
			(end 0.67945 0.3048)
			(stroke
				(width 0.1)
				(type default)
			)
			(layer "F.Fab")
		)
		(fp_line
			(start 0.12065 -0.2794)
			(end 0.12065 -0.3048)
			(stroke
				(width 0.1)
				(type default)
			)
			(layer "F.Fab")
		)
		(fp_line
			(start 0.12065 -0.3048)
			(end 0.67945 -0.3048)
			(stroke
				(width 0.1)
				(type default)
			)
			(layer "F.Fab")
		)
		(fp_line
			(start 0.120396 0.3048)
			(end 0.120396 0.2794)
			(stroke
				(width 0.1)
				(type default)
			)
			(layer "F.Fab")
		)
		(fp_line
			(start 0.120396 0.2794)
			(end -0.12065 0.2794)
			(stroke
				(width 0.1)
				(type default)
			)
			(layer "F.Fab")
		)
		(fp_line
			(start -0.12065 0.3048)
			(end -0.67945 0.3048)
			(stroke
				(width 0.1)
				(type default)
			)
			(layer "F.Fab")
		)
		(fp_line
			(start -0.12065 0.2794)
			(end -0.12065 0.3048)
			(stroke
				(width 0.1)
				(type default)
			)
			(layer "F.Fab")
		)
		(fp_line
			(start -0.12065 -0.2794)
			(end 0.12065 -0.2794)
			(stroke
				(width 0.1)
				(type default)
			)
			(layer "F.Fab")
		)
		(fp_line
			(start -0.12065 -0.305054)
			(end -0.12065 -0.2794)
			(stroke
				(width 0.1)
				(type default)
			)
			(layer "F.Fab")
		)
		(fp_line
			(start -0.67945 0.3048)
			(end -0.67945 -0.305054)
			(stroke
				(width 0.1)
				(type default)
			)
			(layer "F.Fab")
		)
		(fp_line
			(start -0.67945 -0.305054)
			(end -0.12065 -0.305054)
			(stroke
				(width 0.1)
				(type default)
			)
			(layer "F.Fab")
		)
		(pad "1" smd circle
			(at -0.40005 0 180)
			(size 0 0)
			(layers "F.Cu" "F.Mask" "F.Paste")
			(net "FAN_6_PRSNT_BUF_R_N")
		)
		(pad "2" smd circle
			(at 0.40005 0 180)
			(size 0 0)
			(layers "F.Cu" "F.Mask" "F.Paste")
			(net "FAN_6_PRSNT_BUF_N")
		)
	)
	(footprint ""
		(layer "F.Cu")
		(at 33.02 -193.548 180)
		(property "Reference" "R5307"
			(at 0 0 180)
			(layer "F.SilkS")
			(hide yes)
			(effects
				(font
					(size 1.27 1.27)
				)
			)
		)
		(property "Value" ""
			(at 0 0 180)
			(layer "F.Fab")
			(effects
				(font
					(size 1.27 1.27)
				)
			)
		)
		(duplicate_pad_numbers_are_jumpers no)
		(fp_line
			(start 0.7874 0.4064)
			(end -0.7874 0.4064)
			(stroke
				(width 0.1524)
				(type default)
			)
			(layer "F.SilkS")
		)
		(fp_line
			(start 0.7874 -0.4064)
			(end 0.7874 0.4064)
			(stroke
				(width 0.1524)
				(type default)
			)
			(layer "F.SilkS")
		)
		(fp_line
			(start -0.7874 0.4064)
			(end -0.7874 -0.4064)
			(stroke
				(width 0.1524)
				(type default)
			)
			(layer "F.SilkS")
		)
		(fp_line
			(start -0.7874 -0.4064)
			(end 0.7874 -0.4064)
			(stroke
				(width 0.1524)
				(type default)
			)
			(layer "F.SilkS")
		)
		(fp_line
			(start 0.67945 0.3048)
			(end 0.120396 0.3048)
			(stroke
				(width 0.1)
				(type default)
			)
			(layer "F.Fab")
		)
		(fp_line
			(start 0.67945 -0.3048)
			(end 0.67945 0.3048)
			(stroke
				(width 0.1)
				(type default)
			)
			(layer "F.Fab")
		)
		(fp_line
			(start 0.12065 -0.2794)
			(end 0.12065 -0.3048)
			(stroke
				(width 0.1)
				(type default)
			)
			(layer "F.Fab")
		)
		(fp_line
			(start 0.12065 -0.3048)
			(end 0.67945 -0.3048)
			(stroke
				(width 0.1)
				(type default)
			)
			(layer "F.Fab")
		)
		(fp_line
			(start 0.120396 0.3048)
			(end 0.120396 0.2794)
			(stroke
				(width 0.1)
				(type default)
			)
			(layer "F.Fab")
		)
		(fp_line
			(start 0.120396 0.2794)
			(end -0.12065 0.2794)
			(stroke
				(width 0.1)
				(type default)
			)
			(layer "F.Fab")
		)
		(fp_line
			(start -0.12065 0.3048)
			(end -0.67945 0.3048)
			(stroke
				(width 0.1)
				(type default)
			)
			(layer "F.Fab")
		)
		(fp_line
			(start -0.12065 0.2794)
			(end -0.12065 0.3048)
			(stroke
				(width 0.1)
				(type default)
			)
			(layer "F.Fab")
		)
		(fp_line
			(start -0.12065 -0.2794)
			(end 0.12065 -0.2794)
			(stroke
				(width 0.1)
				(type default)
			)
			(layer "F.Fab")
		)
		(fp_line
			(start -0.12065 -0.305054)
			(end -0.12065 -0.2794)
			(stroke
				(width 0.1)
				(type default)
			)
			(layer "F.Fab")
		)
		(fp_line
			(start -0.67945 0.3048)
			(end -0.67945 -0.305054)
			(stroke
				(width 0.1)
				(type default)
			)
			(layer "F.Fab")
		)
		(fp_line
			(start -0.67945 -0.305054)
			(end -0.12065 -0.305054)
			(stroke
				(width 0.1)
				(type default)
			)
			(layer "F.Fab")
		)
		(pad "1" smd rect
			(at -0.40005 0)
			(size 0.4572 0.508)
			(layers "F.Cu" "F.Mask" "F.Paste")
			(net "FAN_1_TACH_OL_R")
		)
		(pad "2" smd rect
			(at 0.40005 0)
			(size 0.4572 0.508)
			(layers "F.Cu" "F.Mask" "F.Paste")
			(net "FAN_1_TACH_OL")
		)
	)
	(footprint ""
		(layer "F.Cu")
		(at 14.234922 -194.250056 180)
		(property "Reference" "R5218"
			(at 0 0 180)
			(layer "F.SilkS")
			(hide yes)
			(effects
				(font
					(size 1.27 1.27)
				)
			)
		)
		(property "Value" ""
			(at 0 0 180)
			(layer "F.Fab")
			(effects
				(font
					(size 1.27 1.27)
				)
			)
		)
		(duplicate_pad_numbers_are_jumpers no)
		(fp_line
			(start 0.7874 0.4064)
			(end -0.7874 0.4064)
			(stroke
				(width 0.1524)
				(type default)
			)
			(layer "F.SilkS")
		)
		(fp_line
			(start 0.7874 -0.4064)
			(end 0.7874 0.4064)
			(stroke
				(width 0.1524)
				(type default)
			)
			(layer "F.SilkS")
		)
		(fp_line
			(start -0.7874 0.4064)
			(end -0.7874 -0.4064)
			(stroke
				(width 0.1524)
				(type default)
			)
			(layer "F.SilkS")
		)
		(fp_line
			(start -0.7874 -0.4064)
			(end 0.7874 -0.4064)
			(stroke
				(width 0.1524)
				(type default)
			)
			(layer "F.SilkS")
		)
		(fp_line
			(start 0.67945 0.3048)
			(end 0.120396 0.3048)
			(stroke
				(width 0.1)
				(type default)
			)
			(layer "F.Fab")
		)
		(fp_line
			(start 0.67945 -0.3048)
			(end 0.67945 0.3048)
			(stroke
				(width 0.1)
				(type default)
			)
			(layer "F.Fab")
		)
		(fp_line
			(start 0.12065 -0.2794)
			(end 0.12065 -0.3048)
			(stroke
				(width 0.1)
				(type default)
			)
			(layer "F.Fab")
		)
		(fp_line
			(start 0.12065 -0.3048)
			(end 0.67945 -0.3048)
			(stroke
				(width 0.1)
				(type default)
			)
			(layer "F.Fab")
		)
		(fp_line
			(start 0.120396 0.3048)
			(end 0.120396 0.2794)
			(stroke
				(width 0.1)
				(type default)
			)
			(layer "F.Fab")
		)
		(fp_line
			(start 0.120396 0.2794)
			(end -0.12065 0.2794)
			(stroke
				(width 0.1)
				(type default)
			)
			(layer "F.Fab")
		)
		(fp_line
			(start -0.12065 0.3048)
			(end -0.67945 0.3048)
			(stroke
				(width 0.1)
				(type default)
			)
			(layer "F.Fab")
		)
		(fp_line
			(start -0.12065 0.2794)
			(end -0.12065 0.3048)
			(stroke
				(width 0.1)
				(type default)
			)
			(layer "F.Fab")
		)
		(fp_line
			(start -0.12065 -0.2794)
			(end 0.12065 -0.2794)
			(stroke
				(width 0.1)
				(type default)
			)
			(layer "F.Fab")
		)
		(fp_line
			(start -0.12065 -0.305054)
			(end -0.12065 -0.2794)
			(stroke
				(width 0.1)
				(type default)
			)
			(layer "F.Fab")
		)
		(fp_line
			(start -0.67945 0.3048)
			(end -0.67945 -0.305054)
			(stroke
				(width 0.1)
				(type default)
			)
			(layer "F.Fab")
		)
		(fp_line
			(start -0.67945 -0.305054)
			(end -0.12065 -0.305054)
			(stroke
				(width 0.1)
				(type default)
			)
			(layer "F.Fab")
		)
		(pad "1" smd circle
			(at -0.40005 0 180)
			(size 0 0)
			(layers "F.Cu" "F.Mask" "F.Paste")
			(net "FAN_6_PWM_OL")
		)
		(pad "2" smd circle
			(at 0.40005 0 180)
			(size 0 0)
			(layers "F.Cu" "F.Mask" "F.Paste")
			(net "FAN_6_PWM_OL_R")
		)
	)
	(footprint ""
		(layer "F.Cu")
		(at 32.893 -28.956 180)
		(property "Reference" "R5326"
			(at 0 0 180)
			(layer "F.SilkS")
			(hide yes)
			(effects
				(font
					(size 1.27 1.27)
				)
			)
		)
		(property "Value" ""
			(at 0 0 180)
			(layer "F.Fab")
			(effects
				(font
					(size 1.27 1.27)
				)
			)
		)
		(duplicate_pad_numbers_are_jumpers no)
		(fp_line
			(start 0.7874 0.4064)
			(end -0.7874 0.4064)
			(stroke
				(width 0.1524)
				(type default)
			)
			(layer "F.SilkS")
		)
		(fp_line
			(start 0.7874 -0.4064)
			(end 0.7874 0.4064)
			(stroke
				(width 0.1524)
				(type default)
			)
			(layer "F.SilkS")
		)
		(fp_line
			(start -0.7874 0.4064)
			(end -0.7874 -0.4064)
			(stroke
				(width 0.1524)
				(type default)
			)
			(layer "F.SilkS")
		)
		(fp_line
			(start -0.7874 -0.4064)
			(end 0.7874 -0.4064)
			(stroke
				(width 0.1524)
				(type default)
			)
			(layer "F.SilkS")
		)
		(fp_line
			(start 0.67945 0.3048)
			(end 0.120396 0.3048)
			(stroke
				(width 0.1)
				(type default)
			)
			(layer "F.Fab")
		)
		(fp_line
			(start 0.67945 -0.3048)
			(end 0.67945 0.3048)
			(stroke
				(width 0.1)
				(type default)
			)
			(layer "F.Fab")
		)
		(fp_line
			(start 0.12065 -0.2794)
			(end 0.12065 -0.3048)
			(stroke
				(width 0.1)
				(type default)
			)
			(layer "F.Fab")
		)
		(fp_line
			(start 0.12065 -0.3048)
			(end 0.67945 -0.3048)
			(stroke
				(width 0.1)
				(type default)
			)
			(layer "F.Fab")
		)
		(fp_line
			(start 0.120396 0.3048)
			(end 0.120396 0.2794)
			(stroke
				(width 0.1)
				(type default)
			)
			(layer "F.Fab")
		)
		(fp_line
			(start 0.120396 0.2794)
			(end -0.12065 0.2794)
			(stroke
				(width 0.1)
				(type default)
			)
			(layer "F.Fab")
		)
		(fp_line
			(start -0.12065 0.3048)
			(end -0.67945 0.3048)
			(stroke
				(width 0.1)
				(type default)
			)
			(layer "F.Fab")
		)
		(fp_line
			(start -0.12065 0.2794)
			(end -0.12065 0.3048)
			(stroke
				(width 0.1)
				(type default)
			)
			(layer "F.Fab")
		)
		(fp_line
			(start -0.12065 -0.2794)
			(end 0.12065 -0.2794)
			(stroke
				(width 0.1)
				(type default)
			)
			(layer "F.Fab")
		)
		(fp_line
			(start -0.12065 -0.305054)
			(end -0.12065 -0.2794)
			(stroke
				(width 0.1)
				(type default)
			)
			(layer "F.Fab")
		)
		(fp_line
			(start -0.67945 0.3048)
			(end -0.67945 -0.305054)
			(stroke
				(width 0.1)
				(type default)
			)
			(layer "F.Fab")
		)
		(fp_line
			(start -0.67945 -0.305054)
			(end -0.12065 -0.305054)
			(stroke
				(width 0.1)
				(type default)
			)
			(layer "F.Fab")
		)
		(pad "1" smd rect
			(at -0.40005 0)
			(size 0.4572 0.508)
			(layers "F.Cu" "F.Mask" "F.Paste")
			(net "FAN_3_TACH_IL_R")
		)
		(pad "2" smd rect
			(at 0.40005 0)
			(size 0.4572 0.508)
			(layers "F.Cu" "F.Mask" "F.Paste")
			(net "FAN_3_TACH_IL")
		)
	)
	(footprint ""
		(layer "F.Cu")
		(at 32.893 -288.925)
		(property "Reference" "R5301"
			(at 0 0 0)
			(layer "F.SilkS")
			(hide yes)
			(effects
				(font
					(size 1.27 1.27)
				)
			)
		)
		(property "Value" ""
			(at 0 0 0)
			(layer "F.Fab")
			(effects
				(font
					(size 1.27 1.27)
				)
			)
		)
		(duplicate_pad_numbers_are_jumpers no)
		(fp_line
			(start -1.2954 -0.5842)
			(end 1.2954 -0.5842)
			(stroke
				(width 0.1524)
				(type default)
			)
			(layer "F.SilkS")
		)
		(fp_line
			(start -1.2954 0.5842)
			(end -1.2954 -0.5842)
			(stroke
				(width 0.1524)
				(type default)
			)
			(layer "F.SilkS")
		)
		(fp_line
			(start 1.2954 -0.5842)
			(end 1.2954 0.5842)
			(stroke
				(width 0.1524)
				(type default)
			)
			(layer "F.SilkS")
		)
		(fp_line
			(start 1.2954 0.5842)
			(end -1.2954 0.5842)
			(stroke
				(width 0.1524)
				(type default)
			)
			(layer "F.SilkS")
		)
		(fp_line
			(start -1.1938 -0.406654)
			(end -0.8636 -0.406654)
			(stroke
				(width 0.1)
				(type default)
			)
			(layer "F.Fab")
		)
		(fp_line
			(start -1.1938 0.4064)
			(end -1.1938 -0.406654)
			(stroke
				(width 0.1)
				(type default)
			)
			(layer "F.Fab")
		)
		(fp_line
			(start -0.8636 -0.4572)
			(end 0.8636 -0.4572)
			(stroke
				(width 0.1)
				(type default)
			)
			(layer "F.Fab")
		)
		(fp_line
			(start -0.8636 -0.406654)
			(end -0.8636 -0.4572)
			(stroke
				(width 0.1)
				(type default)
			)
			(layer "F.Fab")
		)
		(fp_line
			(start -0.8636 0.4064)
			(end -1.1938 0.4064)
			(stroke
				(width 0.1)
				(type default)
			)
			(layer "F.Fab")
		)
		(fp_line
			(start -0.8636 0.4318)
			(end -0.8636 0.4064)
			(stroke
				(width 0.1)
				(type default)
			)
			(layer "F.Fab")
		)
		(fp_line
			(start -0.8636 0.4572)
			(end -0.8636 0.4318)
			(stroke
				(width 0.1)
				(type default)
			)
			(layer "F.Fab")
		)
		(fp_line
			(start 0.8636 -0.4572)
			(end 0.8636 -0.406654)
			(stroke
				(width 0.1)
				(type default)
			)
			(layer "F.Fab")
		)
		(fp_line
			(start 0.8636 -0.406654)
			(end 1.1938 -0.406654)
			(stroke
				(width 0.1)
				(type default)
			)
			(layer "F.Fab")
		)
		(fp_line
			(start 0.8636 0.4064)
			(end 0.8636 0.4572)
			(stroke
				(width 0.1)
				(type default)
			)
			(layer "F.Fab")
		)
		(fp_line
			(start 0.8636 0.4572)
			(end -0.8636 0.4572)
			(stroke
				(width 0.1)
				(type default)
			)
			(layer "F.Fab")
		)
		(fp_line
			(start 1.1938 -0.406654)
			(end 1.1938 0.4064)
			(stroke
				(width 0.1)
				(type default)
			)
			(layer "F.Fab")
		)
		(fp_line
			(start 1.1938 0.4064)
			(end 0.8636 0.4064)
			(stroke
				(width 0.1)
				(type default)
			)
			(layer "F.Fab")
		)
		(pad "1" smd rect
			(at -0.7366 0 270)
			(size 0.7112 0.8128)
			(layers "F.Cu" "F.Mask" "F.Paste")
			(net "P52V_FAN_0")
		)
		(pad "2" smd rect
			(at 0.7366 0 270)
			(size 0.7112 0.8128)
			(layers "F.Cu" "F.Mask" "F.Paste")
			(net "FAN_0_TACH_OL_R")
		)
	)
	(footprint ""
		(layer "F.Cu")
		(at 34.925 -293.116)
		(property "Reference" "R5525"
			(at 0 0 0)
			(layer "F.SilkS")
			(hide yes)
			(effects
				(font
					(size 1.27 1.27)
				)
			)
		)
		(property "Value" ""
			(at 0 0 0)
			(layer "F.Fab")
			(effects
				(font
					(size 1.27 1.27)
				)
			)
		)
		(duplicate_pad_numbers_are_jumpers no)
		(fp_line
			(start -0.7874 -0.4064)
			(end 0.7874 -0.4064)
			(stroke
				(width 0.1524)
				(type default)
			)
			(layer "F.SilkS")
		)
		(fp_line
			(start -0.7874 0.4064)
			(end -0.7874 -0.4064)
			(stroke
				(width 0.1524)
				(type default)
			)
			(layer "F.SilkS")
		)
		(fp_line
			(start 0.7874 -0.4064)
			(end 0.7874 0.4064)
			(stroke
				(width 0.1524)
				(type default)
			)
			(layer "F.SilkS")
		)
		(fp_line
			(start 0.7874 0.4064)
			(end -0.7874 0.4064)
			(stroke
				(width 0.1524)
				(type default)
			)
			(layer "F.SilkS")
		)
		(fp_line
			(start -0.67945 -0.305054)
			(end -0.12065 -0.305054)
			(stroke
				(width 0.1)
				(type default)
			)
			(layer "F.Fab")
		)
		(fp_line
			(start -0.67945 0.3048)
			(end -0.67945 -0.305054)
			(stroke
				(width 0.1)
				(type default)
			)
			(layer "F.Fab")
		)
		(fp_line
			(start -0.12065 -0.305054)
			(end -0.12065 -0.2794)
			(stroke
				(width 0.1)
				(type default)
			)
			(layer "F.Fab")
		)
		(fp_line
			(start -0.12065 -0.2794)
			(end 0.12065 -0.2794)
			(stroke
				(width 0.1)
				(type default)
			)
			(layer "F.Fab")
		)
		(fp_line
			(start -0.12065 0.2794)
			(end -0.12065 0.3048)
			(stroke
				(width 0.1)
				(type default)
			)
			(layer "F.Fab")
		)
		(fp_line
			(start -0.12065 0.3048)
			(end -0.67945 0.3048)
			(stroke
				(width 0.1)
				(type default)
			)
			(layer "F.Fab")
		)
		(fp_line
			(start 0.120396 0.2794)
			(end -0.12065 0.2794)
			(stroke
				(width 0.1)
				(type default)
			)
			(layer "F.Fab")
		)
		(fp_line
			(start 0.120396 0.3048)
			(end 0.120396 0.2794)
			(stroke
				(width 0.1)
				(type default)
			)
			(layer "F.Fab")
		)
		(fp_line
			(start 0.12065 -0.3048)
			(end 0.67945 -0.3048)
			(stroke
				(width 0.1)
				(type default)
			)
			(layer "F.Fab")
		)
		(fp_line
			(start 0.12065 -0.2794)
			(end 0.12065 -0.3048)
			(stroke
				(width 0.1)
				(type default)
			)
			(layer "F.Fab")
		)
		(fp_line
			(start 0.67945 -0.3048)
			(end 0.67945 0.3048)
			(stroke
				(width 0.1)
				(type default)
			)
			(layer "F.Fab")
		)
		(fp_line
			(start 0.67945 0.3048)
			(end 0.120396 0.3048)
			(stroke
				(width 0.1)
				(type default)
			)
			(layer "F.Fab")
		)
		(pad "1" smd rect
			(at -0.40005 0 180)
			(size 0.4572 0.508)
			(layers "F.Cu" "F.Mask" "F.Paste")
			(net "P12V_LED_FAN0")
		)
		(pad "2" smd rect
			(at 0.40005 0 180)
			(size 0.4572 0.508)
			(layers "F.Cu" "F.Mask" "F.Paste")
			(net "FAN_0_OK_LED_R_N")
		)
	)
	(footprint ""
		(layer "F.Cu")
		(at 2.794 -186.436)
		(property "Reference" "R315"
			(at 0 0 0)
			(layer "F.SilkS")
			(hide yes)
			(effects
				(font
					(size 1.27 1.27)
				)
			)
		)
		(property "Value" ""
			(at 0 0 0)
			(layer "F.Fab")
			(effects
				(font
					(size 1.27 1.27)
				)
			)
		)
		(duplicate_pad_numbers_are_jumpers no)
		(fp_line
			(start -0.7874 -0.4064)
			(end 0.7874 -0.4064)
			(stroke
				(width 0.1524)
				(type default)
			)
			(layer "F.SilkS")
		)
		(fp_line
			(start -0.7874 0.4064)
			(end -0.7874 -0.4064)
			(stroke
				(width 0.1524)
				(type default)
			)
			(layer "F.SilkS")
		)
		(fp_line
			(start 0.7874 -0.4064)
			(end 0.7874 0.4064)
			(stroke
				(width 0.1524)
				(type default)
			)
			(layer "F.SilkS")
		)
		(fp_line
			(start 0.7874 0.4064)
			(end -0.7874 0.4064)
			(stroke
				(width 0.1524)
				(type default)
			)
			(layer "F.SilkS")
		)
		(fp_line
			(start -0.67945 -0.305054)
			(end -0.12065 -0.305054)
			(stroke
				(width 0.1)
				(type default)
			)
			(layer "F.Fab")
		)
		(fp_line
			(start -0.67945 0.3048)
			(end -0.67945 -0.305054)
			(stroke
				(width 0.1)
				(type default)
			)
			(layer "F.Fab")
		)
		(fp_line
			(start -0.12065 -0.305054)
			(end -0.12065 -0.2794)
			(stroke
				(width 0.1)
				(type default)
			)
			(layer "F.Fab")
		)
		(fp_line
			(start -0.12065 -0.2794)
			(end 0.12065 -0.2794)
			(stroke
				(width 0.1)
				(type default)
			)
			(layer "F.Fab")
		)
		(fp_line
			(start -0.12065 0.2794)
			(end -0.12065 0.3048)
			(stroke
				(width 0.1)
				(type default)
			)
			(layer "F.Fab")
		)
		(fp_line
			(start -0.12065 0.3048)
			(end -0.67945 0.3048)
			(stroke
				(width 0.1)
				(type default)
			)
			(layer "F.Fab")
		)
		(fp_line
			(start 0.120396 0.2794)
			(end -0.12065 0.2794)
			(stroke
				(width 0.1)
				(type default)
			)
			(layer "F.Fab")
		)
		(fp_line
			(start 0.120396 0.3048)
			(end 0.120396 0.2794)
			(stroke
				(width 0.1)
				(type default)
			)
			(layer "F.Fab")
		)
		(fp_line
			(start 0.12065 -0.3048)
			(end 0.67945 -0.3048)
			(stroke
				(width 0.1)
				(type default)
			)
			(layer "F.Fab")
		)
		(fp_line
			(start 0.12065 -0.2794)
			(end 0.12065 -0.3048)
			(stroke
				(width 0.1)
				(type default)
			)
			(layer "F.Fab")
		)
		(fp_line
			(start 0.67945 -0.3048)
			(end 0.67945 0.3048)
			(stroke
				(width 0.1)
				(type default)
			)
			(layer "F.Fab")
		)
		(fp_line
			(start 0.67945 0.3048)
			(end 0.120396 0.3048)
			(stroke
				(width 0.1)
				(type default)
			)
			(layer "F.Fab")
		)
		(pad "1" smd circle
			(at -0.40005 0)
			(size 0 0)
			(layers "F.Cu" "F.Mask" "F.Paste")
			(net "GND")
		)
		(pad "2" smd circle
			(at 0.40005 0)
			(size 0 0)
			(layers "F.Cu" "F.Mask" "F.Paste")
			(net "FRU_ADDR2")
		)
	)
	(footprint ""
		(layer "F.Cu")
		(at 18.669 -104.14)
		(property "Reference" "C2034"
			(at 0 0 0)
			(layer "F.SilkS")
			(hide yes)
			(effects
				(font
					(size 1.27 1.27)
				)
			)
		)
		(property "Value" ""
			(at 0 0 0)
			(layer "F.Fab")
			(effects
				(font
					(size 1.27 1.27)
				)
			)
		)
		(duplicate_pad_numbers_are_jumpers no)
		(fp_line
			(start -0.7874 -0.4064)
			(end 0.7874 -0.4064)
			(stroke
				(width 0.1524)
				(type default)
			)
			(layer "F.SilkS")
		)
		(fp_line
			(start -0.7874 0.4064)
			(end -0.7874 -0.4064)
			(stroke
				(width 0.1524)
				(type default)
			)
			(layer "F.SilkS")
		)
		(fp_line
			(start 0.7874 -0.4064)
			(end 0.7874 0.4064)
			(stroke
				(width 0.1524)
				(type default)
			)
			(layer "F.SilkS")
		)
		(fp_line
			(start 0.7874 0.4064)
			(end -0.7874 0.4064)
			(stroke
				(width 0.1524)
				(type default)
			)
			(layer "F.SilkS")
		)
		(fp_line
			(start -0.67945 -0.305054)
			(end -0.12065 -0.305054)
			(stroke
				(width 0.1)
				(type default)
			)
			(layer "F.Fab")
		)
		(fp_line
			(start -0.67945 0.3048)
			(end -0.67945 -0.305054)
			(stroke
				(width 0.1)
				(type default)
			)
			(layer "F.Fab")
		)
		(fp_line
			(start -0.12065 -0.305054)
			(end -0.12065 -0.2794)
			(stroke
				(width 0.1)
				(type default)
			)
			(layer "F.Fab")
		)
		(fp_line
			(start -0.12065 -0.2794)
			(end 0.12065 -0.2794)
			(stroke
				(width 0.1)
				(type default)
			)
			(layer "F.Fab")
		)
		(fp_line
			(start -0.12065 0.2794)
			(end -0.12065 0.3048)
			(stroke
				(width 0.1)
				(type default)
			)
			(layer "F.Fab")
		)
		(fp_line
			(start -0.12065 0.3048)
			(end -0.67945 0.3048)
			(stroke
				(width 0.1)
				(type default)
			)
			(layer "F.Fab")
		)
		(fp_line
			(start 0.120396 0.2794)
			(end -0.12065 0.2794)
			(stroke
				(width 0.1)
				(type default)
			)
			(layer "F.Fab")
		)
		(fp_line
			(start 0.120396 0.3048)
			(end 0.120396 0.2794)
			(stroke
				(width 0.1)
				(type default)
			)
			(layer "F.Fab")
		)
		(fp_line
			(start 0.12065 -0.3048)
			(end 0.67945 -0.3048)
			(stroke
				(width 0.1)
				(type default)
			)
			(layer "F.Fab")
		)
		(fp_line
			(start 0.12065 -0.2794)
			(end 0.12065 -0.3048)
			(stroke
				(width 0.1)
				(type default)
			)
			(layer "F.Fab")
		)
		(fp_line
			(start 0.67945 -0.3048)
			(end 0.67945 0.3048)
			(stroke
				(width 0.1)
				(type default)
			)
			(layer "F.Fab")
		)
		(fp_line
			(start 0.67945 0.3048)
			(end 0.120396 0.3048)
			(stroke
				(width 0.1)
				(type default)
			)
			(layer "F.Fab")
		)
		(pad "1" smd circle
			(at -0.40005 0)
			(size 0 0)
			(layers "F.Cu" "F.Mask" "F.Paste")
			(net "FAN_5_TACH_IL_R")
		)
		(pad "2" smd circle
			(at 0.40005 0)
			(size 0 0)
			(layers "F.Cu" "F.Mask" "F.Paste")
			(net "GND")
		)
	)
	(footprint ""
		(layer "F.Cu")
		(at 14.351 -112.706912 180)
		(property "Reference" "D245"
			(at 4.191 0.042418 0)
			(unlocked yes)
			(layer "F.SilkS")
			(effects
				(font
					(size 0.7874 0.5842)
					(thickness 0.1524)
				)
				(justify left)
			)
		)
		(property "Value" ""
			(at 0 0 180)
			(layer "F.Fab")
			(effects
				(font
					(size 1.27 1.27)
				)
			)
		)
		(duplicate_pad_numbers_are_jumpers no)
		(fp_line
			(start 0.94488 0.450088)
			(end 0.94488 -0.450088)
			(stroke
				(width 0.1524)
				(type default)
			)
			(layer "F.SilkS")
		)
		(fp_line
			(start 0.94488 -0.450088)
			(end -0.854964 -0.450088)
			(stroke
				(width 0.1524)
				(type default)
			)
			(layer "F.SilkS")
		)
		(fp_line
			(start 0.870458 -0.2794)
			(end 0.845058 0.4064)
			(stroke
				(width 0.1524)
				(type default)
			)
			(layer "F.SilkS")
		)
		(fp_line
			(start 0.845058 0.4064)
			(end 0.845058 -0.381)
			(stroke
				(width 0.1524)
				(type default)
			)
			(layer "F.SilkS")
		)
		(fp_line
			(start -0.854964 0.450088)
			(end 0.925068 0.450088)
			(stroke
				(width 0.1524)
				(type default)
			)
			(layer "F.SilkS")
		)
		(fp_line
			(start -0.854964 -0.450088)
			(end -0.854964 0.450088)
			(stroke
				(width 0.1524)
				(type default)
			)
			(layer "F.SilkS")
		)
		(fp_line
			(start 0.54991 0.350012)
			(end 0.54991 -0.350012)
			(stroke
				(width 0.1)
				(type default)
			)
			(layer "F.Fab")
		)
		(fp_line
			(start 0.54991 -0.350012)
			(end -0.54991 -0.350012)
			(stroke
				(width 0.1)
				(type default)
			)
			(layer "F.Fab")
		)
		(fp_line
			(start -0.54991 0.350012)
			(end 0.54991 0.350012)
			(stroke
				(width 0.1)
				(type default)
			)
			(layer "F.Fab")
		)
		(fp_line
			(start -0.54991 -0.350012)
			(end -0.54991 0.350012)
			(stroke
				(width 0.1)
				(type default)
			)
			(layer "F.Fab")
		)
		(fp_text user "-"
			(at 1.778 -0.470662 0)
			(unlocked yes)
			(layer "F.SilkS")
			(effects
				(font
					(size 1.905 1.4224)
					(thickness 0.1524)
				)
				(justify left)
			)
		)
		(fp_text user "+"
			(at -0.635 -0.470662 0)
			(unlocked yes)
			(layer "F.SilkS")
			(effects
				(font
					(size 1.905 1.4224)
					(thickness 0.1524)
				)
				(justify left)
			)
		)
		(fp_text user "-"
			(at 2.48539 0.239014 0)
			(unlocked yes)
			(layer "F.Fab")
			(effects
				(font
					(size 1.905 1.4224)
					(thickness 0.1524)
				)
				(justify left)
			)
		)
		(fp_text user "+"
			(at -0.808228 0.239014 0)
			(unlocked yes)
			(layer "F.Fab")
			(effects
				(font
					(size 1.905 1.4224)
					(thickness 0.1524)
				)
				(justify left)
			)
		)
		(pad "A" smd rect
			(at -0.424942 0 180)
			(size 0.5588 0.6096)
			(layers "F.Cu" "F.Mask" "F.Paste")
			(net "GND")
		)
		(pad "C" smd rect
			(at 0.424942 0)
			(size 0.5588 0.6096)
			(layers "F.Cu" "F.Mask" "F.Paste")
			(net "FAN_5_FAIL_R_LED_N")
		)
	)
	(footprint ""
		(layer "F.Cu")
		(at 9.398 -98.425 90)
		(property "Reference" "C2125"
			(at 0 0 90)
			(layer "F.SilkS")
			(hide yes)
			(effects
				(font
					(size 1.27 1.27)
				)
			)
		)
		(property "Value" ""
			(at 0 0 90)
			(layer "F.Fab")
			(effects
				(font
					(size 1.27 1.27)
				)
			)
		)
		(duplicate_pad_numbers_are_jumpers no)
		(fp_line
			(start 1.2954 -0.5842)
			(end 1.2954 0.5842)
			(stroke
				(width 0.1524)
				(type default)
			)
			(layer "F.SilkS")
		)
		(fp_line
			(start -1.2954 -0.5842)
			(end 1.2954 -0.5842)
			(stroke
				(width 0.1524)
				(type default)
			)
			(layer "F.SilkS")
		)
		(fp_line
			(start 1.2954 0.5842)
			(end -1.2954 0.5842)
			(stroke
				(width 0.1524)
				(type default)
			)
			(layer "F.SilkS")
		)
		(fp_line
			(start -1.2954 0.5842)
			(end -1.2954 -0.5842)
			(stroke
				(width 0.1524)
				(type default)
			)
			(layer "F.SilkS")
		)
		(fp_line
			(start 0.8636 -0.4572)
			(end 0.8636 -0.4064)
			(stroke
				(width 0.1)
				(type default)
			)
			(layer "F.Fab")
		)
		(fp_line
			(start -0.8636 -0.4572)
			(end 0.8636 -0.4572)
			(stroke
				(width 0.1)
				(type default)
			)
			(layer "F.Fab")
		)
		(fp_line
			(start 1.1938 -0.4064)
			(end 1.1938 0.4064)
			(stroke
				(width 0.1)
				(type default)
			)
			(layer "F.Fab")
		)
		(fp_line
			(start 0.8636 -0.4064)
			(end 1.1938 -0.4064)
			(stroke
				(width 0.1)
				(type default)
			)
			(layer "F.Fab")
		)
		(fp_line
			(start -0.8636 -0.4064)
			(end -0.8636 -0.4572)
			(stroke
				(width 0.1)
				(type default)
			)
			(layer "F.Fab")
		)
		(fp_line
			(start -1.1938 -0.4064)
			(end -0.8636 -0.4064)
			(stroke
				(width 0.1)
				(type default)
			)
			(layer "F.Fab")
		)
		(fp_line
			(start 1.1938 0.4064)
			(end 0.8636 0.4064)
			(stroke
				(width 0.1)
				(type default)
			)
			(layer "F.Fab")
		)
		(fp_line
			(start 0.8636 0.4064)
			(end 0.8636 0.4572)
			(stroke
				(width 0.1)
				(type default)
			)
			(layer "F.Fab")
		)
		(fp_line
			(start -0.8636 0.4064)
			(end -1.1938 0.4064)
			(stroke
				(width 0.1)
				(type default)
			)
			(layer "F.Fab")
		)
		(fp_line
			(start -1.1938 0.4064)
			(end -1.1938 -0.4064)
			(stroke
				(width 0.1)
				(type default)
			)
			(layer "F.Fab")
		)
		(fp_line
			(start 0.8636 0.4572)
			(end -0.8636 0.4572)
			(stroke
				(width 0.1)
				(type default)
			)
			(layer "F.Fab")
		)
		(fp_line
			(start -0.8636 0.4572)
			(end -0.8636 0.4064)
			(stroke
				(width 0.1)
				(type default)
			)
			(layer "F.Fab")
		)
		(pad "1" smd rect
			(at -0.7366 0)
			(size 0.7112 0.8128)
			(layers "F.Cu" "F.Mask" "F.Paste")
			(net "U410_D1")
		)
		(pad "2" smd rect
			(at 0.7366 0)
			(size 0.7112 0.8128)
			(layers "F.Cu" "F.Mask" "F.Paste")
			(net "GND")
		)
	)
	(footprint ""
		(layer "F.Cu")
		(at 26.924 -135.382 -90)
		(property "Reference" "R5459"
			(at 0 0 270)
			(layer "F.SilkS")
			(hide yes)
			(effects
				(font
					(size 1.27 1.27)
				)
			)
		)
		(property "Value" ""
			(at 0 0 270)
			(layer "F.Fab")
			(effects
				(font
					(size 1.27 1.27)
				)
			)
		)
		(duplicate_pad_numbers_are_jumpers no)
		(fp_line
			(start -0.7874 0.4064)
			(end -0.7874 -0.4064)
			(stroke
				(width 0.1524)
				(type default)
			)
			(layer "F.SilkS")
		)
		(fp_line
			(start 0.7874 0.4064)
			(end -0.7874 0.4064)
			(stroke
				(width 0.1524)
				(type default)
			)
			(layer "F.SilkS")
		)
		(fp_line
			(start -0.7874 -0.4064)
			(end 0.7874 -0.4064)
			(stroke
				(width 0.1524)
				(type default)
			)
			(layer "F.SilkS")
		)
		(fp_line
			(start 0.7874 -0.4064)
			(end 0.7874 0.4064)
			(stroke
				(width 0.1524)
				(type default)
			)
			(layer "F.SilkS")
		)
		(fp_line
			(start -0.67945 0.3048)
			(end -0.67945 -0.305054)
			(stroke
				(width 0.1)
				(type default)
			)
			(layer "F.Fab")
		)
		(fp_line
			(start -0.12065 0.3048)
			(end -0.67945 0.3048)
			(stroke
				(width 0.1)
				(type default)
			)
			(layer "F.Fab")
		)
		(fp_line
			(start 0.120396 0.3048)
			(end 0.120396 0.2794)
			(stroke
				(width 0.1)
				(type default)
			)
			(layer "F.Fab")
		)
		(fp_line
			(start 0.67945 0.3048)
			(end 0.120396 0.3048)
			(stroke
				(width 0.1)
				(type default)
			)
			(layer "F.Fab")
		)
		(fp_line
			(start -0.12065 0.2794)
			(end -0.12065 0.3048)
			(stroke
				(width 0.1)
				(type default)
			)
			(layer "F.Fab")
		)
		(fp_line
			(start 0.120396 0.2794)
			(end -0.12065 0.2794)
			(stroke
				(width 0.1)
				(type default)
			)
			(layer "F.Fab")
		)
		(fp_line
			(start -0.12065 -0.2794)
			(end 0.12065 -0.2794)
			(stroke
				(width 0.1)
				(type default)
			)
			(layer "F.Fab")
		)
		(fp_line
			(start 0.12065 -0.2794)
			(end 0.12065 -0.3048)
			(stroke
				(width 0.1)
				(type default)
			)
			(layer "F.Fab")
		)
		(fp_line
			(start 0.12065 -0.3048)
			(end 0.67945 -0.3048)
			(stroke
				(width 0.1)
				(type default)
			)
			(layer "F.Fab")
		)
		(fp_line
			(start 0.67945 -0.3048)
			(end 0.67945 0.3048)
			(stroke
				(width 0.1)
				(type default)
			)
			(layer "F.Fab")
		)
		(fp_line
			(start -0.67945 -0.305054)
			(end -0.12065 -0.305054)
			(stroke
				(width 0.1)
				(type default)
			)
			(layer "F.Fab")
		)
		(fp_line
			(start -0.12065 -0.305054)
			(end -0.12065 -0.2794)
			(stroke
				(width 0.1)
				(type default)
			)
			(layer "F.Fab")
		)
		(pad "1" smd circle
			(at -0.40005 0 270)
			(size 0 0)
			(layers "F.Cu" "F.Mask" "F.Paste")
			(net "SMB_PDBV_FAN_SCL")
		)
		(pad "2" smd circle
			(at 0.40005 0 270)
			(size 0 0)
			(layers "F.Cu" "F.Mask" "F.Paste")
			(net "SMB_PDBV_FAN_R_U317_SCL")
		)
	)
	(footprint ""
		(layer "F.Cu")
		(at 48.133 -179.324)
		(property "Reference" "C2082"
			(at 0 0 0)
			(layer "F.SilkS")
			(hide yes)
			(effects
				(font
					(size 1.27 1.27)
				)
			)
		)
		(property "Value" ""
			(at 0 0 0)
			(layer "F.Fab")
			(effects
				(font
					(size 1.27 1.27)
				)
			)
		)
		(duplicate_pad_numbers_are_jumpers no)
		(fp_line
			(start -0.7874 -0.4064)
			(end 0.7874 -0.4064)
			(stroke
				(width 0.1524)
				(type default)
			)
			(layer "F.SilkS")
		)
		(fp_line
			(start -0.7874 0.4064)
			(end -0.7874 -0.4064)
			(stroke
				(width 0.1524)
				(type default)
			)
			(layer "F.SilkS")
		)
		(fp_line
			(start 0.7874 -0.4064)
			(end 0.7874 0.4064)
			(stroke
				(width 0.1524)
				(type default)
			)
			(layer "F.SilkS")
		)
		(fp_line
			(start 0.7874 0.4064)
			(end -0.7874 0.4064)
			(stroke
				(width 0.1524)
				(type default)
			)
			(layer "F.SilkS")
		)
		(fp_line
			(start -0.67945 -0.305054)
			(end -0.12065 -0.305054)
			(stroke
				(width 0.1)
				(type default)
			)
			(layer "F.Fab")
		)
		(fp_line
			(start -0.67945 0.3048)
			(end -0.67945 -0.305054)
			(stroke
				(width 0.1)
				(type default)
			)
			(layer "F.Fab")
		)
		(fp_line
			(start -0.12065 -0.305054)
			(end -0.12065 -0.2794)
			(stroke
				(width 0.1)
				(type default)
			)
			(layer "F.Fab")
		)
		(fp_line
			(start -0.12065 -0.2794)
			(end 0.12065 -0.2794)
			(stroke
				(width 0.1)
				(type default)
			)
			(layer "F.Fab")
		)
		(fp_line
			(start -0.12065 0.2794)
			(end -0.12065 0.3048)
			(stroke
				(width 0.1)
				(type default)
			)
			(layer "F.Fab")
		)
		(fp_line
			(start -0.12065 0.3048)
			(end -0.67945 0.3048)
			(stroke
				(width 0.1)
				(type default)
			)
			(layer "F.Fab")
		)
		(fp_line
			(start 0.120396 0.2794)
			(end -0.12065 0.2794)
			(stroke
				(width 0.1)
				(type default)
			)
			(layer "F.Fab")
		)
		(fp_line
			(start 0.120396 0.3048)
			(end 0.120396 0.2794)
			(stroke
				(width 0.1)
				(type default)
			)
			(layer "F.Fab")
		)
		(fp_line
			(start 0.12065 -0.3048)
			(end 0.67945 -0.3048)
			(stroke
				(width 0.1)
				(type default)
			)
			(layer "F.Fab")
		)
		(fp_line
			(start 0.12065 -0.2794)
			(end 0.12065 -0.3048)
			(stroke
				(width 0.1)
				(type default)
			)
			(layer "F.Fab")
		)
		(fp_line
			(start 0.67945 -0.3048)
			(end 0.67945 0.3048)
			(stroke
				(width 0.1)
				(type default)
			)
			(layer "F.Fab")
		)
		(fp_line
			(start 0.67945 0.3048)
			(end 0.120396 0.3048)
			(stroke
				(width 0.1)
				(type default)
			)
			(layer "F.Fab")
		)
		(pad "1" smd circle
			(at -0.40005 0)
			(size 0 0)
			(layers "F.Cu" "F.Mask" "F.Paste")
			(net "P52V_FAN_3_BUFF_EN_R")
		)
		(pad "2" smd circle
			(at 0.40005 0)
			(size 0 0)
			(layers "F.Cu" "F.Mask" "F.Paste")
			(net "GND")
		)
	)
	(footprint ""
		(layer "F.Cu")
		(at 32.385 -106.68 90)
		(property "Reference" "R5393"
			(at 0 0 90)
			(layer "F.SilkS")
			(hide yes)
			(effects
				(font
					(size 1.27 1.27)
				)
			)
		)
		(property "Value" ""
			(at 0 0 90)
			(layer "F.Fab")
			(effects
				(font
					(size 1.27 1.27)
				)
			)
		)
		(duplicate_pad_numbers_are_jumpers no)
		(fp_line
			(start 0.7874 -0.4064)
			(end 0.7874 0.4064)
			(stroke
				(width 0.1524)
				(type default)
			)
			(layer "F.SilkS")
		)
		(fp_line
			(start -0.7874 -0.4064)
			(end 0.7874 -0.4064)
			(stroke
				(width 0.1524)
				(type default)
			)
			(layer "F.SilkS")
		)
		(fp_line
			(start 0.7874 0.4064)
			(end -0.7874 0.4064)
			(stroke
				(width 0.1524)
				(type default)
			)
			(layer "F.SilkS")
		)
		(fp_line
			(start -0.7874 0.4064)
			(end -0.7874 -0.4064)
			(stroke
				(width 0.1524)
				(type default)
			)
			(layer "F.SilkS")
		)
		(fp_line
			(start -0.12065 -0.305054)
			(end -0.12065 -0.2794)
			(stroke
				(width 0.1)
				(type default)
			)
			(layer "F.Fab")
		)
		(fp_line
			(start -0.67945 -0.305054)
			(end -0.12065 -0.305054)
			(stroke
				(width 0.1)
				(type default)
			)
			(layer "F.Fab")
		)
		(fp_line
			(start 0.67945 -0.3048)
			(end 0.67945 0.3048)
			(stroke
				(width 0.1)
				(type default)
			)
			(layer "F.Fab")
		)
		(fp_line
			(start 0.12065 -0.3048)
			(end 0.67945 -0.3048)
			(stroke
				(width 0.1)
				(type default)
			)
			(layer "F.Fab")
		)
		(fp_line
			(start 0.12065 -0.2794)
			(end 0.12065 -0.3048)
			(stroke
				(width 0.1)
				(type default)
			)
			(layer "F.Fab")
		)
		(fp_line
			(start -0.12065 -0.2794)
			(end 0.12065 -0.2794)
			(stroke
				(width 0.1)
				(type default)
			)
			(layer "F.Fab")
		)
		(fp_line
			(start 0.120396 0.2794)
			(end -0.12065 0.2794)
			(stroke
				(width 0.1)
				(type default)
			)
			(layer "F.Fab")
		)
		(fp_line
			(start -0.12065 0.2794)
			(end -0.12065 0.3048)
			(stroke
				(width 0.1)
				(type default)
			)
			(layer "F.Fab")
		)
		(fp_line
			(start 0.67945 0.3048)
			(end 0.120396 0.3048)
			(stroke
				(width 0.1)
				(type default)
			)
			(layer "F.Fab")
		)
		(fp_line
			(start 0.120396 0.3048)
			(end 0.120396 0.2794)
			(stroke
				(width 0.1)
				(type default)
			)
			(layer "F.Fab")
		)
		(fp_line
			(start -0.12065 0.3048)
			(end -0.67945 0.3048)
			(stroke
				(width 0.1)
				(type default)
			)
			(layer "F.Fab")
		)
		(fp_line
			(start -0.67945 0.3048)
			(end -0.67945 -0.305054)
			(stroke
				(width 0.1)
				(type default)
			)
			(layer "F.Fab")
		)
		(pad "1" smd circle
			(at -0.40005 0 90)
			(size 0 0)
			(layers "F.Cu" "F.Mask" "F.Paste")
			(net "P3V3_AUX")
		)
		(pad "2" smd circle
			(at 0.40005 0 90)
			(size 0 0)
			(layers "F.Cu" "F.Mask" "F.Paste")
			(net "FAN_2_OK_R_LED")
		)
	)
	(footprint ""
		(layer "F.Cu")
		(at 14.07795 -136.144 180)
		(property "Reference" "R5596"
			(at 0 0 180)
			(layer "F.SilkS")
			(hide yes)
			(effects
				(font
					(size 1.27 1.27)
				)
			)
		)
		(property "Value" ""
			(at 0 0 180)
			(layer "F.Fab")
			(effects
				(font
					(size 1.27 1.27)
				)
			)
		)
		(duplicate_pad_numbers_are_jumpers no)
		(fp_line
			(start 0.7874 0.4064)
			(end -0.7874 0.4064)
			(stroke
				(width 0.1524)
				(type default)
			)
			(layer "F.SilkS")
		)
		(fp_line
			(start 0.7874 -0.4064)
			(end 0.7874 0.4064)
			(stroke
				(width 0.1524)
				(type default)
			)
			(layer "F.SilkS")
		)
		(fp_line
			(start -0.7874 0.4064)
			(end -0.7874 -0.4064)
			(stroke
				(width 0.1524)
				(type default)
			)
			(layer "F.SilkS")
		)
		(fp_line
			(start -0.7874 -0.4064)
			(end 0.7874 -0.4064)
			(stroke
				(width 0.1524)
				(type default)
			)
			(layer "F.SilkS")
		)
		(fp_line
			(start 0.67945 0.3048)
			(end 0.120396 0.3048)
			(stroke
				(width 0.1)
				(type default)
			)
			(layer "F.Fab")
		)
		(fp_line
			(start 0.67945 -0.3048)
			(end 0.67945 0.3048)
			(stroke
				(width 0.1)
				(type default)
			)
			(layer "F.Fab")
		)
		(fp_line
			(start 0.12065 -0.2794)
			(end 0.12065 -0.3048)
			(stroke
				(width 0.1)
				(type default)
			)
			(layer "F.Fab")
		)
		(fp_line
			(start 0.12065 -0.3048)
			(end 0.67945 -0.3048)
			(stroke
				(width 0.1)
				(type default)
			)
			(layer "F.Fab")
		)
		(fp_line
			(start 0.120396 0.3048)
			(end 0.120396 0.2794)
			(stroke
				(width 0.1)
				(type default)
			)
			(layer "F.Fab")
		)
		(fp_line
			(start 0.120396 0.2794)
			(end -0.12065 0.2794)
			(stroke
				(width 0.1)
				(type default)
			)
			(layer "F.Fab")
		)
		(fp_line
			(start -0.12065 0.3048)
			(end -0.67945 0.3048)
			(stroke
				(width 0.1)
				(type default)
			)
			(layer "F.Fab")
		)
		(fp_line
			(start -0.12065 0.2794)
			(end -0.12065 0.3048)
			(stroke
				(width 0.1)
				(type default)
			)
			(layer "F.Fab")
		)
		(fp_line
			(start -0.12065 -0.2794)
			(end 0.12065 -0.2794)
			(stroke
				(width 0.1)
				(type default)
			)
			(layer "F.Fab")
		)
		(fp_line
			(start -0.12065 -0.305054)
			(end -0.12065 -0.2794)
			(stroke
				(width 0.1)
				(type default)
			)
			(layer "F.Fab")
		)
		(fp_line
			(start -0.67945 0.3048)
			(end -0.67945 -0.305054)
			(stroke
				(width 0.1)
				(type default)
			)
			(layer "F.Fab")
		)
		(fp_line
			(start -0.67945 -0.305054)
			(end -0.12065 -0.305054)
			(stroke
				(width 0.1)
				(type default)
			)
			(layer "F.Fab")
		)
		(pad "1" smd rect
			(at -0.40005 0)
			(size 0.4572 0.508)
			(layers "F.Cu" "F.Mask" "F.Paste")
			(net "FAN_7_TACH_OL")
		)
		(pad "2" smd rect
			(at 0.40005 0)
			(size 0.4572 0.508)
			(layers "F.Cu" "F.Mask" "F.Paste")
			(net "FAN_7_TACH_OL_R2")
		)
	)
	(footprint ""
		(layer "F.Cu")
		(at 34.29 -194.691)
		(property "Reference" "R5305"
			(at 0 0 0)
			(layer "F.SilkS")
			(hide yes)
			(effects
				(font
					(size 1.27 1.27)
				)
			)
		)
		(property "Value" ""
			(at 0 0 0)
			(layer "F.Fab")
			(effects
				(font
					(size 1.27 1.27)
				)
			)
		)
		(duplicate_pad_numbers_are_jumpers no)
		(fp_line
			(start -1.2954 -0.5842)
			(end 1.2954 -0.5842)
			(stroke
				(width 0.1524)
				(type default)
			)
			(layer "F.SilkS")
		)
		(fp_line
			(start -1.2954 0.5842)
			(end -1.2954 -0.5842)
			(stroke
				(width 0.1524)
				(type default)
			)
			(layer "F.SilkS")
		)
		(fp_line
			(start 1.2954 -0.5842)
			(end 1.2954 0.5842)
			(stroke
				(width 0.1524)
				(type default)
			)
			(layer "F.SilkS")
		)
		(fp_line
			(start 1.2954 0.5842)
			(end -1.2954 0.5842)
			(stroke
				(width 0.1524)
				(type default)
			)
			(layer "F.SilkS")
		)
		(fp_line
			(start -1.1938 -0.406654)
			(end -0.8636 -0.406654)
			(stroke
				(width 0.1)
				(type default)
			)
			(layer "F.Fab")
		)
		(fp_line
			(start -1.1938 0.4064)
			(end -1.1938 -0.406654)
			(stroke
				(width 0.1)
				(type default)
			)
			(layer "F.Fab")
		)
		(fp_line
			(start -0.8636 -0.4572)
			(end 0.8636 -0.4572)
			(stroke
				(width 0.1)
				(type default)
			)
			(layer "F.Fab")
		)
		(fp_line
			(start -0.8636 -0.406654)
			(end -0.8636 -0.4572)
			(stroke
				(width 0.1)
				(type default)
			)
			(layer "F.Fab")
		)
		(fp_line
			(start -0.8636 0.4064)
			(end -1.1938 0.4064)
			(stroke
				(width 0.1)
				(type default)
			)
			(layer "F.Fab")
		)
		(fp_line
			(start -0.8636 0.4318)
			(end -0.8636 0.4064)
			(stroke
				(width 0.1)
				(type default)
			)
			(layer "F.Fab")
		)
		(fp_line
			(start -0.8636 0.4572)
			(end -0.8636 0.4318)
			(stroke
				(width 0.1)
				(type default)
			)
			(layer "F.Fab")
		)
		(fp_line
			(start 0.8636 -0.4572)
			(end 0.8636 -0.406654)
			(stroke
				(width 0.1)
				(type default)
			)
			(layer "F.Fab")
		)
		(fp_line
			(start 0.8636 -0.406654)
			(end 1.1938 -0.406654)
			(stroke
				(width 0.1)
				(type default)
			)
			(layer "F.Fab")
		)
		(fp_line
			(start 0.8636 0.4064)
			(end 0.8636 0.4572)
			(stroke
				(width 0.1)
				(type default)
			)
			(layer "F.Fab")
		)
		(fp_line
			(start 0.8636 0.4572)
			(end -0.8636 0.4572)
			(stroke
				(width 0.1)
				(type default)
			)
			(layer "F.Fab")
		)
		(fp_line
			(start 1.1938 -0.406654)
			(end 1.1938 0.4064)
			(stroke
				(width 0.1)
				(type default)
			)
			(layer "F.Fab")
		)
		(fp_line
			(start 1.1938 0.4064)
			(end 0.8636 0.4064)
			(stroke
				(width 0.1)
				(type default)
			)
			(layer "F.Fab")
		)
		(pad "1" smd rect
			(at -0.7366 0 270)
			(size 0.7112 0.8128)
			(layers "F.Cu" "F.Mask" "F.Paste")
			(net "P52V_FAN_1")
		)
		(pad "2" smd rect
			(at 0.7366 0 270)
			(size 0.7112 0.8128)
			(layers "F.Cu" "F.Mask" "F.Paste")
			(net "FAN_1_TACH_OL_R")
		)
	)
	(footprint ""
		(layer "F.Cu")
		(at 9.906 -164.084 180)
		(property "Reference" "U23"
			(at 2.00533 -1.016 90)
			(unlocked yes)
			(layer "F.SilkS")
			(effects
				(font
					(size 0.7874 0.5842)
					(thickness 0.1524)
				)
				(justify left)
			)
		)
		(property "Value" ""
			(at 0 0 180)
			(layer "F.Fab")
			(effects
				(font
					(size 1.27 1.27)
				)
			)
		)
		(duplicate_pad_numbers_are_jumpers no)
		(fp_line
			(start 1.3462 1.100074)
			(end -1.3462 1.100074)
			(stroke
				(width 0.1524)
				(type default)
			)
			(layer "F.SilkS")
		)
		(fp_line
			(start 1.3462 -1.100074)
			(end 1.3462 1.100074)
			(stroke
				(width 0.1524)
				(type default)
			)
			(layer "F.SilkS")
		)
		(fp_line
			(start 0.670052 -1.100074)
			(end 1.3462 -1.100074)
			(stroke
				(width 0.1524)
				(type default)
			)
			(layer "F.SilkS")
		)
		(fp_line
			(start 0 -0.381)
			(end 0.670052 -1.100074)
			(stroke
				(width 0.1524)
				(type default)
			)
			(layer "F.SilkS")
		)
		(fp_line
			(start -0.670052 -1.100074)
			(end 0 -0.381)
			(stroke
				(width 0.1524)
				(type default)
			)
			(layer "F.SilkS")
		)
		(fp_line
			(start -1.3462 1.100074)
			(end -1.3462 -1.100074)
			(stroke
				(width 0.1524)
				(type default)
			)
			(layer "F.SilkS")
		)
		(fp_line
			(start -1.3462 -1.100074)
			(end -0.670052 -1.100074)
			(stroke
				(width 0.1524)
				(type default)
			)
			(layer "F.SilkS")
		)
		(fp_poly
			(pts
				(xy -1.524 -0.649986) (xy -2.286 -1.030986) (xy -2.286 -0.268986)
			)
			(stroke
				(width 0)
				(type default)
			)
			(fill yes)
			(layer "F.SilkS")
		)
		(fp_line
			(start 1.100074 0.8001)
			(end 0.670052 0.8001)
			(stroke
				(width 0.1)
				(type default)
			)
			(layer "F.Fab")
		)
		(fp_line
			(start 1.100074 -0.8001)
			(end 1.100074 0.8001)
			(stroke
				(width 0.1)
				(type default)
			)
			(layer "F.Fab")
		)
		(fp_line
			(start 0.670052 1.100074)
			(end -0.670052 1.100074)
			(stroke
				(width 0.1)
				(type default)
			)
			(layer "F.Fab")
		)
		(fp_line
			(start 0.670052 0.8001)
			(end 0.670052 1.100074)
			(stroke
				(width 0.1)
				(type default)
			)
			(layer "F.Fab")
		)
		(fp_line
			(start 0.670052 -0.8001)
			(end 1.100074 -0.8001)
			(stroke
				(width 0.1)
				(type default)
			)
			(layer "F.Fab")
		)
		(fp_line
			(start 0.670052 -0.8001)
			(end 0.670052 0.8001)
			(stroke
				(width 0.1)
				(type default)
			)
			(layer "F.Fab")
		)
		(fp_line
			(start 0.670052 -1.100074)
			(end 0.670052 -0.8001)
			(stroke
				(width 0.1)
				(type default)
			)
			(layer "F.Fab")
		)
		(fp_line
			(start -0.670052 1.100074)
			(end -0.670052 0.8001)
			(stroke
				(width 0.1)
				(type default)
			)
			(layer "F.Fab")
		)
		(fp_line
			(start -0.670052 0.8001)
			(end -0.670052 -0.8001)
			(stroke
				(width 0.1)
				(type default)
			)
			(layer "F.Fab")
		)
		(fp_line
			(start -0.670052 0.8001)
			(end -1.100074 0.8001)
			(stroke
				(width 0.1)
				(type default)
			)
			(layer "F.Fab")
		)
		(fp_line
			(start -0.670052 -0.8001)
			(end -0.670052 -1.100074)
			(stroke
				(width 0.1)
				(type default)
			)
			(layer "F.Fab")
		)
		(fp_line
			(start -0.670052 -1.100074)
			(end 0.670052 -1.100074)
			(stroke
				(width 0.1)
				(type default)
			)
			(layer "F.Fab")
		)
		(fp_line
			(start -1.100074 0.8001)
			(end -1.100074 -0.8001)
			(stroke
				(width 0.1)
				(type default)
			)
			(layer "F.Fab")
		)
		(fp_line
			(start -1.100074 -0.8001)
			(end -0.670052 -0.8001)
			(stroke
				(width 0.1)
				(type default)
			)
			(layer "F.Fab")
		)
		(fp_poly
			(pts
				(xy -1.524 -0.649986) (xy -2.286 -1.030986) (xy -2.286 -0.268986)
			)
			(stroke
				(width 0)
				(type default)
			)
			(fill yes)
			(layer "F.Fab")
		)
		(pad "1" smd rect
			(at -0.94996 -0.649986 90)
			(size 0.4064 0.508)
			(layers "F.Cu" "F.Mask" "F.Paste")
			(net "FAN_0_PRESENT_N")
		)
		(pad "2" smd rect
			(at -0.94996 0 90)
			(size 0.4064 0.508)
			(layers "F.Cu" "F.Mask" "F.Paste")
			(net "GND")
		)
		(pad "3" smd rect
			(at -0.94996 0.649986 90)
			(size 0.4064 0.508)
			(layers "F.Cu" "F.Mask" "F.Paste")
			(net "FAN_1_PRESENT_N")
		)
		(pad "4" smd rect
			(at 0.94996 0.649986 90)
			(size 0.4064 0.508)
			(layers "F.Cu" "F.Mask" "F.Paste")
			(net "FAN_1_PRSNT_BUF_R_N")
		)
		(pad "5" smd rect
			(at 0.94996 0 90)
			(size 0.4064 0.508)
			(layers "F.Cu" "F.Mask" "F.Paste")
			(net "P3V3_AUX")
		)
		(pad "6" smd rect
			(at 0.94996 -0.649986 90)
			(size 0.4064 0.508)
			(layers "F.Cu" "F.Mask" "F.Paste")
			(net "FAN_0_PRSNT_BUF_R_N")
		)
	)
	(footprint ""
		(layer "F.Cu")
		(at 42.291 -135.509 -90)
		(property "Reference" "R5562"
			(at 0 0 270)
			(layer "F.SilkS")
			(hide yes)
			(effects
				(font
					(size 1.27 1.27)
				)
			)
		)
		(property "Value" ""
			(at 0 0 270)
			(layer "F.Fab")
			(effects
				(font
					(size 1.27 1.27)
				)
			)
		)
		(duplicate_pad_numbers_are_jumpers no)
		(fp_line
			(start -0.7874 0.4064)
			(end -0.7874 -0.4064)
			(stroke
				(width 0.1524)
				(type default)
			)
			(layer "F.SilkS")
		)
		(fp_line
			(start 0.7874 0.4064)
			(end -0.7874 0.4064)
			(stroke
				(width 0.1524)
				(type default)
			)
			(layer "F.SilkS")
		)
		(fp_line
			(start -0.7874 -0.4064)
			(end 0.7874 -0.4064)
			(stroke
				(width 0.1524)
				(type default)
			)
			(layer "F.SilkS")
		)
		(fp_line
			(start 0.7874 -0.4064)
			(end 0.7874 0.4064)
			(stroke
				(width 0.1524)
				(type default)
			)
			(layer "F.SilkS")
		)
		(fp_line
			(start -0.67945 0.3048)
			(end -0.67945 -0.305054)
			(stroke
				(width 0.1)
				(type default)
			)
			(layer "F.Fab")
		)
		(fp_line
			(start -0.12065 0.3048)
			(end -0.67945 0.3048)
			(stroke
				(width 0.1)
				(type default)
			)
			(layer "F.Fab")
		)
		(fp_line
			(start 0.120396 0.3048)
			(end 0.120396 0.2794)
			(stroke
				(width 0.1)
				(type default)
			)
			(layer "F.Fab")
		)
		(fp_line
			(start 0.67945 0.3048)
			(end 0.120396 0.3048)
			(stroke
				(width 0.1)
				(type default)
			)
			(layer "F.Fab")
		)
		(fp_line
			(start -0.12065 0.2794)
			(end -0.12065 0.3048)
			(stroke
				(width 0.1)
				(type default)
			)
			(layer "F.Fab")
		)
		(fp_line
			(start 0.120396 0.2794)
			(end -0.12065 0.2794)
			(stroke
				(width 0.1)
				(type default)
			)
			(layer "F.Fab")
		)
		(fp_line
			(start -0.12065 -0.2794)
			(end 0.12065 -0.2794)
			(stroke
				(width 0.1)
				(type default)
			)
			(layer "F.Fab")
		)
		(fp_line
			(start 0.12065 -0.2794)
			(end 0.12065 -0.3048)
			(stroke
				(width 0.1)
				(type default)
			)
			(layer "F.Fab")
		)
		(fp_line
			(start 0.12065 -0.3048)
			(end 0.67945 -0.3048)
			(stroke
				(width 0.1)
				(type default)
			)
			(layer "F.Fab")
		)
		(fp_line
			(start 0.67945 -0.3048)
			(end 0.67945 0.3048)
			(stroke
				(width 0.1)
				(type default)
			)
			(layer "F.Fab")
		)
		(fp_line
			(start -0.67945 -0.305054)
			(end -0.12065 -0.305054)
			(stroke
				(width 0.1)
				(type default)
			)
			(layer "F.Fab")
		)
		(fp_line
			(start -0.12065 -0.305054)
			(end -0.12065 -0.2794)
			(stroke
				(width 0.1)
				(type default)
			)
			(layer "F.Fab")
		)
		(pad "1" smd circle
			(at -0.40005 0 270)
			(size 0 0)
			(layers "F.Cu" "F.Mask" "F.Paste")
			(net "P3V3_AUX")
		)
		(pad "2" smd circle
			(at 0.40005 0 270)
			(size 0 0)
			(layers "F.Cu" "F.Mask" "F.Paste")
			(net "U403_ADD2")
		)
	)
	(footprint ""
		(layer "F.Cu")
		(at 35.179 -27.391868 180)
		(property "Reference" "C2053"
			(at 0 0 180)
			(layer "F.SilkS")
			(hide yes)
			(effects
				(font
					(size 1.27 1.27)
				)
			)
		)
		(property "Value" ""
			(at 0 0 180)
			(layer "F.Fab")
			(effects
				(font
					(size 1.27 1.27)
				)
			)
		)
		(duplicate_pad_numbers_are_jumpers no)
		(fp_line
			(start 0.7874 0.4064)
			(end -0.7874 0.4064)
			(stroke
				(width 0.1524)
				(type default)
			)
			(layer "F.SilkS")
		)
		(fp_line
			(start 0.7874 -0.4064)
			(end 0.7874 0.4064)
			(stroke
				(width 0.1524)
				(type default)
			)
			(layer "F.SilkS")
		)
		(fp_line
			(start -0.7874 0.4064)
			(end -0.7874 -0.4064)
			(stroke
				(width 0.1524)
				(type default)
			)
			(layer "F.SilkS")
		)
		(fp_line
			(start -0.7874 -0.4064)
			(end 0.7874 -0.4064)
			(stroke
				(width 0.1524)
				(type default)
			)
			(layer "F.SilkS")
		)
		(fp_line
			(start 0.67945 0.3048)
			(end 0.120396 0.3048)
			(stroke
				(width 0.1)
				(type default)
			)
			(layer "F.Fab")
		)
		(fp_line
			(start 0.67945 -0.3048)
			(end 0.67945 0.3048)
			(stroke
				(width 0.1)
				(type default)
			)
			(layer "F.Fab")
		)
		(fp_line
			(start 0.12065 -0.2794)
			(end 0.12065 -0.3048)
			(stroke
				(width 0.1)
				(type default)
			)
			(layer "F.Fab")
		)
		(fp_line
			(start 0.12065 -0.3048)
			(end 0.67945 -0.3048)
			(stroke
				(width 0.1)
				(type default)
			)
			(layer "F.Fab")
		)
		(fp_line
			(start 0.120396 0.3048)
			(end 0.120396 0.2794)
			(stroke
				(width 0.1)
				(type default)
			)
			(layer "F.Fab")
		)
		(fp_line
			(start 0.120396 0.2794)
			(end -0.12065 0.2794)
			(stroke
				(width 0.1)
				(type default)
			)
			(layer "F.Fab")
		)
		(fp_line
			(start -0.12065 0.3048)
			(end -0.67945 0.3048)
			(stroke
				(width 0.1)
				(type default)
			)
			(layer "F.Fab")
		)
		(fp_line
			(start -0.12065 0.2794)
			(end -0.12065 0.3048)
			(stroke
				(width 0.1)
				(type default)
			)
			(layer "F.Fab")
		)
		(fp_line
			(start -0.12065 -0.2794)
			(end 0.12065 -0.2794)
			(stroke
				(width 0.1)
				(type default)
			)
			(layer "F.Fab")
		)
		(fp_line
			(start -0.12065 -0.305054)
			(end -0.12065 -0.2794)
			(stroke
				(width 0.1)
				(type default)
			)
			(layer "F.Fab")
		)
		(fp_line
			(start -0.67945 0.3048)
			(end -0.67945 -0.305054)
			(stroke
				(width 0.1)
				(type default)
			)
			(layer "F.Fab")
		)
		(fp_line
			(start -0.67945 -0.305054)
			(end -0.12065 -0.305054)
			(stroke
				(width 0.1)
				(type default)
			)
			(layer "F.Fab")
		)
		(pad "1" smd circle
			(at -0.40005 0 180)
			(size 0 0)
			(layers "F.Cu" "F.Mask" "F.Paste")
			(net "FAN_3_PWM_IL_R")
		)
		(pad "2" smd circle
			(at 0.40005 0 180)
			(size 0 0)
			(layers "F.Cu" "F.Mask" "F.Paste")
			(net "GND")
		)
	)
	(footprint ""
		(layer "F.Cu")
		(at 31.496 -129.159 90)
		(property "Reference" "U317"
			(at -2.032 4.34467 90)
			(unlocked yes)
			(layer "F.SilkS")
			(effects
				(font
					(size 0.7874 0.5842)
					(thickness 0.1524)
				)
				(justify left)
			)
		)
		(property "Value" ""
			(at 0 0 90)
			(layer "F.Fab")
			(effects
				(font
					(size 1.27 1.27)
				)
			)
		)
		(duplicate_pad_numbers_are_jumpers no)
		(fp_line
			(start 0 -3.048)
			(end 0 -2.54)
			(stroke
				(width 0.1524)
				(type default)
			)
			(layer "F.SilkS")
		)
		(fp_line
			(start 2.050034 -2.050034)
			(end 1.41859 -2.050034)
			(stroke
				(width 0.1524)
				(type default)
			)
			(layer "F.SilkS")
		)
		(fp_line
			(start -1.42367 -2.050034)
			(end -2.050034 -2.050034)
			(stroke
				(width 0.1524)
				(type default)
			)
			(layer "F.SilkS")
		)
		(fp_line
			(start -2.050034 -2.050034)
			(end -2.050034 -1.4224)
			(stroke
				(width 0.1524)
				(type default)
			)
			(layer "F.SilkS")
		)
		(fp_line
			(start 2.050034 -1.415796)
			(end 2.050034 -2.050034)
			(stroke
				(width 0.1524)
				(type default)
			)
			(layer "F.SilkS")
		)
		(fp_line
			(start 3.302 -0.8128)
			(end 2.54 -0.8128)
			(stroke
				(width 0.1524)
				(type default)
			)
			(layer "F.SilkS")
		)
		(fp_line
			(start -2.54508 0.398272)
			(end -3.05308 0.398272)
			(stroke
				(width 0.1524)
				(type default)
			)
			(layer "F.SilkS")
		)
		(fp_line
			(start 3.048 1.2192)
			(end 2.54 1.2192)
			(stroke
				(width 0.1524)
				(type default)
			)
			(layer "F.SilkS")
		)
		(fp_line
			(start -2.050034 1.41986)
			(end -2.050034 2.050034)
			(stroke
				(width 0.1524)
				(type default)
			)
			(layer "F.SilkS")
		)
		(fp_line
			(start 2.050034 2.050034)
			(end 2.050034 1.41732)
			(stroke
				(width 0.1524)
				(type default)
			)
			(layer "F.SilkS")
		)
		(fp_line
			(start 1.42367 2.050034)
			(end 2.050034 2.050034)
			(stroke
				(width 0.1524)
				(type default)
			)
			(layer "F.SilkS")
		)
		(fp_line
			(start -2.050034 2.050034)
			(end -1.417828 2.050034)
			(stroke
				(width 0.1524)
				(type default)
			)
			(layer "F.SilkS")
		)
		(fp_line
			(start -0.4064 2.54)
			(end -0.4064 3.302)
			(stroke
				(width 0.1524)
				(type default)
			)
			(layer "F.SilkS")
		)
		(fp_poly
			(pts
				(xy -3.6957 -1.890776) (xy -3.6957 -0.874776) (xy -2.6797 -1.382776)
			)
			(stroke
				(width 0)
				(type default)
			)
			(fill yes)
			(layer "F.SilkS")
		)
		(fp_line
			(start 0.009652 -3.052572)
			(end 0.009652 -2.544572)
			(stroke
				(width 0.1)
				(type default)
			)
			(layer "F.Fab")
		)
		(fp_line
			(start 2.050034 -2.050034)
			(end -2.050034 -2.050034)
			(stroke
				(width 0.1)
				(type default)
			)
			(layer "F.Fab")
		)
		(fp_line
			(start -2.050034 -2.050034)
			(end -2.050034 2.050034)
			(stroke
				(width 0.1)
				(type default)
			)
			(layer "F.Fab")
		)
		(fp_line
			(start 3.319272 -0.80264)
			(end 2.557272 -0.80264)
			(stroke
				(width 0.1)
				(type default)
			)
			(layer "F.Fab")
		)
		(fp_line
			(start -2.54508 0.398272)
			(end -3.05308 0.398272)
			(stroke
				(width 0.1)
				(type default)
			)
			(layer "F.Fab")
		)
		(fp_line
			(start 3.062732 1.198372)
			(end 2.554732 1.198372)
			(stroke
				(width 0.1)
				(type default)
			)
			(layer "F.Fab")
		)
		(fp_line
			(start 2.050034 2.050034)
			(end 2.050034 -2.050034)
			(stroke
				(width 0.1)
				(type default)
			)
			(layer "F.Fab")
		)
		(fp_line
			(start -2.050034 2.050034)
			(end 2.050034 2.050034)
			(stroke
				(width 0.1)
				(type default)
			)
			(layer "F.Fab")
		)
		(fp_line
			(start -0.396748 2.568448)
			(end -0.396748 3.330448)
			(stroke
				(width 0.1)
				(type default)
			)
			(layer "F.Fab")
		)
		(fp_poly
			(pts
				(xy -3.5052 -1.707896) (xy -3.5052 -0.691896) (xy -2.4892 -1.199896)
			)
			(stroke
				(width 0)
				(type default)
			)
			(fill yes)
			(layer "F.Fab")
		)
		(fp_text user "22"
			(at 1.41605 -2.684018 90)
			(unlocked yes)
			(layer "F.SilkS")
			(effects
				(font
					(size 0.635 0.4064)
					(thickness 0.1524)
				)
				(justify left)
			)
		)
		(fp_text user "28"
			(at -2.38125 -2.576068 90)
			(unlocked yes)
			(layer "F.SilkS")
			(effects
				(font
					(size 0.635 0.4064)
					(thickness 0.1524)
				)
				(justify left)
			)
		)
		(fp_text user "21"
			(at 2.618232 -1.3843 180)
			(unlocked yes)
			(layer "F.SilkS")
			(effects
				(font
					(size 0.635 0.4064)
					(thickness 0.1524)
				)
				(justify left)
			)
		)
		(fp_text user "7"
			(at -2.69875 2.286 180)
			(unlocked yes)
			(layer "F.SilkS")
			(effects
				(font
					(size 0.635 0.4064)
					(thickness 0.1524)
				)
				(justify left)
			)
		)
		(fp_text user "15"
			(at 2.630932 2.33045 180)
			(unlocked yes)
			(layer "F.SilkS")
			(effects
				(font
					(size 0.635 0.4064)
					(thickness 0.1524)
				)
				(justify left)
			)
		)
		(fp_text user "8"
			(at -1.92405 2.586482 90)
			(unlocked yes)
			(layer "F.SilkS")
			(effects
				(font
					(size 0.635 0.4064)
					(thickness 0.1524)
				)
				(justify left)
			)
		)
		(fp_text user "14"
			(at 1.3208 2.745232 90)
			(unlocked yes)
			(layer "F.SilkS")
			(effects
				(font
					(size 0.635 0.4064)
					(thickness 0.1524)
				)
				(justify left)
			)
		)
		(fp_text user "22"
			(at 1.41605 -2.684018 90)
			(unlocked yes)
			(layer "F.Fab")
			(effects
				(font
					(size 0.635 0.4064)
					(thickness 0.1524)
				)
				(justify left)
			)
		)
		(fp_text user "28"
			(at -2.38125 -2.576068 90)
			(unlocked yes)
			(layer "F.Fab")
			(effects
				(font
					(size 0.635 0.4064)
					(thickness 0.1524)
				)
				(justify left)
			)
		)
		(fp_text user "21"
			(at 2.618232 -1.3843 180)
			(unlocked yes)
			(layer "F.Fab")
			(effects
				(font
					(size 0.635 0.4064)
					(thickness 0.1524)
				)
				(justify left)
			)
		)
		(fp_text user "7"
			(at -2.563368 1.8923 180)
			(unlocked yes)
			(layer "F.Fab")
			(effects
				(font
					(size 0.635 0.4064)
					(thickness 0.1524)
				)
				(justify left)
			)
		)
		(fp_text user "15"
			(at 2.630932 2.33045 180)
			(unlocked yes)
			(layer "F.Fab")
			(effects
				(font
					(size 0.635 0.4064)
					(thickness 0.1524)
				)
				(justify left)
			)
		)
		(fp_text user "8"
			(at -1.92405 2.586482 90)
			(unlocked yes)
			(layer "F.Fab")
			(effects
				(font
					(size 0.635 0.4064)
					(thickness 0.1524)
				)
				(justify left)
			)
		)
		(fp_text user "14"
			(at 1.3208 2.745232 90)
			(unlocked yes)
			(layer "F.Fab")
			(effects
				(font
					(size 0.635 0.4064)
					(thickness 0.1524)
				)
				(justify left)
			)
		)
		(pad "1" smd rect
			(at -1.999996 -1.199896 180)
			(size 0.1778 0.8128)
			(layers "F.Cu" "F.Mask" "F.Paste")
			(net "MAX31790_U317_FREQ_START")
		)
		(pad "2" smd rect
			(at -1.999996 -0.8001 180)
			(size 0.1778 0.8128)
			(layers "F.Cu" "F.Mask" "F.Paste")
			(net "MAX31790_U317_SPIN_START")
		)
		(pad "3" smd rect
			(at -1.999996 -0.40005 180)
			(size 0.1778 0.8128)
			(layers "F.Cu" "F.Mask" "F.Paste")
			(net "MAX31790_U317_ADD1")
		)
		(pad "4" smd rect
			(at -1.999996 0 180)
			(size 0.1778 0.8128)
			(layers "F.Cu" "F.Mask" "F.Paste")
			(net "MAX31790_U317_ADD0")
		)
		(pad "5" smd rect
			(at -1.999996 0.40005 180)
			(size 0.1778 0.8128)
			(layers "F.Cu" "F.Mask" "F.Paste")
			(net "MAX31790_U317_WD_START")
		)
		(pad "6" smd rect
			(at -1.999996 0.8001 180)
			(size 0.1778 0.8128)
			(layers "F.Cu" "F.Mask" "F.Paste")
			(net "TP_U317_XTAL2")
		)
		(pad "7" smd rect
			(at -1.999996 1.199896 180)
			(size 0.1778 0.8128)
			(layers "F.Cu" "F.Mask" "F.Paste")
			(net "TP_U317_XTAL1")
		)
		(pad "8" smd rect
			(at -1.199896 1.999996 90)
			(size 0.1778 0.8128)
			(layers "F.Cu" "F.Mask" "F.Paste")
			(net "GND")
		)
		(pad "9" smd rect
			(at -0.8001 1.999996 90)
			(size 0.1778 0.8128)
			(layers "F.Cu" "F.Mask" "F.Paste")
			(net "FAN_3_TACH_OL_R1")
		)
		(pad "10" smd rect
			(at -0.40005 1.999996 90)
			(size 0.1778 0.8128)
			(layers "F.Cu" "F.Mask" "F.Paste")
			(net "FAN_3_PWM_R1")
		)
		(pad "11" smd rect
			(at 0 1.999996 90)
			(size 0.1778 0.8128)
			(layers "F.Cu" "F.Mask" "F.Paste")
			(net "FAN_2_TACH_OL_R1")
		)
		(pad "12" smd rect
			(at 0.40005 1.999996 90)
			(size 0.1778 0.8128)
			(layers "F.Cu" "F.Mask" "F.Paste")
			(net "FAN_3_TACH_IL_R1")
		)
		(pad "13" smd rect
			(at 0.8001 1.999996 90)
			(size 0.1778 0.8128)
			(layers "F.Cu" "F.Mask" "F.Paste")
			(net "FAN_2_TACH_IL_R1")
		)
		(pad "14" smd rect
			(at 1.199896 1.999996 90)
			(size 0.1778 0.8128)
			(layers "F.Cu" "F.Mask" "F.Paste")
			(net "FAN_2_PWM_R1")
		)
		(pad "15" smd rect
			(at 1.999996 1.199896 180)
			(size 0.1778 0.8128)
			(layers "F.Cu" "F.Mask" "F.Paste")
			(net "FAN_1_TACH_OL_R1")
		)
		(pad "16" smd rect
			(at 1.999996 0.8001 180)
			(size 0.1778 0.8128)
			(layers "F.Cu" "F.Mask" "F.Paste")
			(net "FAN_1_PWM_R1")
		)
		(pad "17" smd rect
			(at 1.999996 0.40005 180)
			(size 0.1778 0.8128)
			(layers "F.Cu" "F.Mask" "F.Paste")
			(net "FAN_0_TACH_OL_R1")
		)
		(pad "18" smd rect
			(at 1.999996 0 180)
			(size 0.1778 0.8128)
			(layers "F.Cu" "F.Mask" "F.Paste")
			(net "FAN_1_TACH_IL_R1")
		)
		(pad "19" smd rect
			(at 1.999996 -0.40005 180)
			(size 0.1778 0.8128)
			(layers "F.Cu" "F.Mask" "F.Paste")
			(net "FAN_0_TACH_IL_R1")
		)
		(pad "20" smd rect
			(at 1.999996 -0.8001 180)
			(size 0.1778 0.8128)
			(layers "F.Cu" "F.Mask" "F.Paste")
			(net "FAN_0_PWM_R1")
		)
		(pad "21" smd rect
			(at 1.999996 -1.199896 180)
			(size 0.1778 0.8128)
			(layers "F.Cu" "F.Mask" "F.Paste")
			(net "P3V3_AUX")
		)
		(pad "22" smd rect
			(at 1.199896 -1.999996 90)
			(size 0.1778 0.8128)
			(layers "F.Cu" "F.Mask" "F.Paste")
			(net "SMB_PDBV_FAN_R_U317_SDA")
		)
		(pad "23" smd rect
			(at 0.8001 -1.999996 90)
			(size 0.1778 0.8128)
			(layers "F.Cu" "F.Mask" "F.Paste")
			(net "SMB_PDBV_FAN_R_U317_SCL")
		)
		(pad "24" smd rect
			(at 0.40005 -1.999996 90)
			(size 0.1778 0.8128)
			(layers "F.Cu" "F.Mask" "F.Paste")
			(net "U317_FAN FAIL_N")
		)
		(pad "25" smd rect
			(at 0 -1.999996 90)
			(size 0.1778 0.8128)
			(layers "F.Cu" "F.Mask" "F.Paste")
			(net "MAX31790_U317_PWM_START0")
		)
		(pad "26" smd rect
			(at -0.40005 -1.999996 90)
			(size 0.1778 0.8128)
			(layers "F.Cu" "F.Mask" "F.Paste")
			(net "MAX31790_U317_PWM_START1")
		)
		(pad "27" smd rect
			(at -0.8001 -1.999996 90)
			(size 0.1778 0.8128)
			(layers "F.Cu" "F.Mask" "F.Paste")
			(net "U317_FAN FS_N")
		)
		(pad "28" smd rect
			(at -1.199896 -1.999996 90)
			(size 0.1778 0.8128)
			(layers "F.Cu" "F.Mask" "F.Paste")
			(net "NC_U317_CLKOUT")
		)
		(pad "TH" smd rect
			(at 0 0 180)
			(size 2.7178 2.7178)
			(layers "F.Cu" "F.Mask" "F.Paste")
			(net "GND")
		)
		(zone
			(layer "F.Cu")
			(hatch none 0.5)
			(connect_pads
				(clearance 0)
			)
			(min_thickness 0.25)
			(keepout
				(tracks not_allowed)
				(vias allowed)
				(pads allowed)
				(copperpour not_allowed)
				(footprints allowed)
			)
			(placement
				(enabled no)
				(sheetname "")
			)
			(fill
				(thermal_gap 0.5)
				(thermal_bridge_width 0.5)
				(island_removal_mode 0)
			)
			(polygon
				(pts
					(xy 29.9593 -128.9304) (xy 30.07995 -128.9304) (xy 30.07995 -127.74295) (xy 32.91205 -127.74295)
					(xy 32.91205 -130.57505) (xy 30.07995 -130.57505) (xy 30.07995 -128.9558) (xy 29.9593 -128.9558)
					(xy 29.9593 -130.6957) (xy 33.0327 -130.6957) (xy 33.0327 -127.6223) (xy 29.9593 -127.6223)
				)
			)
		)
	)
	(footprint ""
		(layer "F.Cu")
		(at 7.112 -64.897 180)
		(property "Reference" "PR49"
			(at 0 0 180)
			(layer "F.SilkS")
			(hide yes)
			(effects
				(font
					(size 1.27 1.27)
				)
			)
		)
		(property "Value" ""
			(at 0 0 180)
			(layer "F.Fab")
			(effects
				(font
					(size 1.27 1.27)
				)
			)
		)
		(duplicate_pad_numbers_are_jumpers no)
		(fp_line
			(start 0.7874 0.4064)
			(end -0.7874 0.4064)
			(stroke
				(width 0.1524)
				(type default)
			)
			(layer "F.SilkS")
		)
		(fp_line
			(start 0.7874 -0.4064)
			(end 0.7874 0.4064)
			(stroke
				(width 0.1524)
				(type default)
			)
			(layer "F.SilkS")
		)
		(fp_line
			(start -0.7874 0.4064)
			(end -0.7874 -0.4064)
			(stroke
				(width 0.1524)
				(type default)
			)
			(layer "F.SilkS")
		)
		(fp_line
			(start -0.7874 -0.4064)
			(end 0.7874 -0.4064)
			(stroke
				(width 0.1524)
				(type default)
			)
			(layer "F.SilkS")
		)
		(fp_line
			(start 0.67945 0.3048)
			(end 0.120396 0.3048)
			(stroke
				(width 0.1)
				(type default)
			)
			(layer "F.Fab")
		)
		(fp_line
			(start 0.67945 -0.3048)
			(end 0.67945 0.3048)
			(stroke
				(width 0.1)
				(type default)
			)
			(layer "F.Fab")
		)
		(fp_line
			(start 0.12065 -0.2794)
			(end 0.12065 -0.3048)
			(stroke
				(width 0.1)
				(type default)
			)
			(layer "F.Fab")
		)
		(fp_line
			(start 0.12065 -0.3048)
			(end 0.67945 -0.3048)
			(stroke
				(width 0.1)
				(type default)
			)
			(layer "F.Fab")
		)
		(fp_line
			(start 0.120396 0.3048)
			(end 0.120396 0.2794)
			(stroke
				(width 0.1)
				(type default)
			)
			(layer "F.Fab")
		)
		(fp_line
			(start 0.120396 0.2794)
			(end -0.12065 0.2794)
			(stroke
				(width 0.1)
				(type default)
			)
			(layer "F.Fab")
		)
		(fp_line
			(start -0.12065 0.3048)
			(end -0.67945 0.3048)
			(stroke
				(width 0.1)
				(type default)
			)
			(layer "F.Fab")
		)
		(fp_line
			(start -0.12065 0.2794)
			(end -0.12065 0.3048)
			(stroke
				(width 0.1)
				(type default)
			)
			(layer "F.Fab")
		)
		(fp_line
			(start -0.12065 -0.2794)
			(end 0.12065 -0.2794)
			(stroke
				(width 0.1)
				(type default)
			)
			(layer "F.Fab")
		)
		(fp_line
			(start -0.12065 -0.305054)
			(end -0.12065 -0.2794)
			(stroke
				(width 0.1)
				(type default)
			)
			(layer "F.Fab")
		)
		(fp_line
			(start -0.67945 0.3048)
			(end -0.67945 -0.305054)
			(stroke
				(width 0.1)
				(type default)
			)
			(layer "F.Fab")
		)
		(fp_line
			(start -0.67945 -0.305054)
			(end -0.12065 -0.305054)
			(stroke
				(width 0.1)
				(type default)
			)
			(layer "F.Fab")
		)
		(pad "1" smd circle
			(at -0.40005 0 180)
			(size 0 0)
			(layers "F.Cu" "F.Mask" "F.Paste")
			(net "FAN_4_P3V_R")
		)
		(pad "2" smd circle
			(at 0.40005 0 180)
			(size 0 0)
			(layers "F.Cu" "F.Mask" "F.Paste")
			(net "FAN_4_MODE")
		)
	)
	(footprint ""
		(layer "F.Cu")
		(at 38.6461 -128.778)
		(property "Reference" "R5580"
			(at 0 0 0)
			(layer "F.SilkS")
			(hide yes)
			(effects
				(font
					(size 1.27 1.27)
				)
			)
		)
		(property "Value" ""
			(at 0 0 0)
			(layer "F.Fab")
			(effects
				(font
					(size 1.27 1.27)
				)
			)
		)
		(duplicate_pad_numbers_are_jumpers no)
		(fp_line
			(start -0.7874 -0.4064)
			(end 0.7874 -0.4064)
			(stroke
				(width 0.1524)
				(type default)
			)
			(layer "F.SilkS")
		)
		(fp_line
			(start -0.7874 0.4064)
			(end -0.7874 -0.4064)
			(stroke
				(width 0.1524)
				(type default)
			)
			(layer "F.SilkS")
		)
		(fp_line
			(start 0.7874 -0.4064)
			(end 0.7874 0.4064)
			(stroke
				(width 0.1524)
				(type default)
			)
			(layer "F.SilkS")
		)
		(fp_line
			(start 0.7874 0.4064)
			(end -0.7874 0.4064)
			(stroke
				(width 0.1524)
				(type default)
			)
			(layer "F.SilkS")
		)
		(fp_line
			(start -0.67945 -0.305054)
			(end -0.12065 -0.305054)
			(stroke
				(width 0.1)
				(type default)
			)
			(layer "F.Fab")
		)
		(fp_line
			(start -0.67945 0.3048)
			(end -0.67945 -0.305054)
			(stroke
				(width 0.1)
				(type default)
			)
			(layer "F.Fab")
		)
		(fp_line
			(start -0.12065 -0.305054)
			(end -0.12065 -0.2794)
			(stroke
				(width 0.1)
				(type default)
			)
			(layer "F.Fab")
		)
		(fp_line
			(start -0.12065 -0.2794)
			(end 0.12065 -0.2794)
			(stroke
				(width 0.1)
				(type default)
			)
			(layer "F.Fab")
		)
		(fp_line
			(start -0.12065 0.2794)
			(end -0.12065 0.3048)
			(stroke
				(width 0.1)
				(type default)
			)
			(layer "F.Fab")
		)
		(fp_line
			(start -0.12065 0.3048)
			(end -0.67945 0.3048)
			(stroke
				(width 0.1)
				(type default)
			)
			(layer "F.Fab")
		)
		(fp_line
			(start 0.120396 0.2794)
			(end -0.12065 0.2794)
			(stroke
				(width 0.1)
				(type default)
			)
			(layer "F.Fab")
		)
		(fp_line
			(start 0.120396 0.3048)
			(end 0.120396 0.2794)
			(stroke
				(width 0.1)
				(type default)
			)
			(layer "F.Fab")
		)
		(fp_line
			(start 0.12065 -0.3048)
			(end 0.67945 -0.3048)
			(stroke
				(width 0.1)
				(type default)
			)
			(layer "F.Fab")
		)
		(fp_line
			(start 0.12065 -0.2794)
			(end 0.12065 -0.3048)
			(stroke
				(width 0.1)
				(type default)
			)
			(layer "F.Fab")
		)
		(fp_line
			(start 0.67945 -0.3048)
			(end 0.67945 0.3048)
			(stroke
				(width 0.1)
				(type default)
			)
			(layer "F.Fab")
		)
		(fp_line
			(start 0.67945 0.3048)
			(end 0.120396 0.3048)
			(stroke
				(width 0.1)
				(type default)
			)
			(layer "F.Fab")
		)
		(pad "1" smd rect
			(at -0.40005 0 180)
			(size 0.4572 0.508)
			(layers "F.Cu" "F.Mask" "F.Paste")
			(net "FAN_2_TACH_IL")
		)
		(pad "2" smd rect
			(at 0.40005 0 180)
			(size 0.4572 0.508)
			(layers "F.Cu" "F.Mask" "F.Paste")
			(net "FAN_2_TACH_IL_R2")
		)
	)
	(footprint ""
		(layer "F.Cu")
		(at 30.353 -182.372)
		(property "Reference" "R509"
			(at 0 0 0)
			(layer "F.SilkS")
			(hide yes)
			(effects
				(font
					(size 1.27 1.27)
				)
			)
		)
		(property "Value" ""
			(at 0 0 0)
			(layer "F.Fab")
			(effects
				(font
					(size 1.27 1.27)
				)
			)
		)
		(duplicate_pad_numbers_are_jumpers no)
		(fp_line
			(start -0.7874 -0.4064)
			(end 0.7874 -0.4064)
			(stroke
				(width 0.1524)
				(type default)
			)
			(layer "F.SilkS")
		)
		(fp_line
			(start -0.7874 0.4064)
			(end -0.7874 -0.4064)
			(stroke
				(width 0.1524)
				(type default)
			)
			(layer "F.SilkS")
		)
		(fp_line
			(start 0.7874 -0.4064)
			(end 0.7874 0.4064)
			(stroke
				(width 0.1524)
				(type default)
			)
			(layer "F.SilkS")
		)
		(fp_line
			(start 0.7874 0.4064)
			(end -0.7874 0.4064)
			(stroke
				(width 0.1524)
				(type default)
			)
			(layer "F.SilkS")
		)
		(fp_line
			(start -0.67945 -0.305054)
			(end -0.12065 -0.305054)
			(stroke
				(width 0.1)
				(type default)
			)
			(layer "F.Fab")
		)
		(fp_line
			(start -0.67945 0.3048)
			(end -0.67945 -0.305054)
			(stroke
				(width 0.1)
				(type default)
			)
			(layer "F.Fab")
		)
		(fp_line
			(start -0.12065 -0.305054)
			(end -0.12065 -0.2794)
			(stroke
				(width 0.1)
				(type default)
			)
			(layer "F.Fab")
		)
		(fp_line
			(start -0.12065 -0.2794)
			(end 0.12065 -0.2794)
			(stroke
				(width 0.1)
				(type default)
			)
			(layer "F.Fab")
		)
		(fp_line
			(start -0.12065 0.2794)
			(end -0.12065 0.3048)
			(stroke
				(width 0.1)
				(type default)
			)
			(layer "F.Fab")
		)
		(fp_line
			(start -0.12065 0.3048)
			(end -0.67945 0.3048)
			(stroke
				(width 0.1)
				(type default)
			)
			(layer "F.Fab")
		)
		(fp_line
			(start 0.120396 0.2794)
			(end -0.12065 0.2794)
			(stroke
				(width 0.1)
				(type default)
			)
			(layer "F.Fab")
		)
		(fp_line
			(start 0.120396 0.3048)
			(end 0.120396 0.2794)
			(stroke
				(width 0.1)
				(type default)
			)
			(layer "F.Fab")
		)
		(fp_line
			(start 0.12065 -0.3048)
			(end 0.67945 -0.3048)
			(stroke
				(width 0.1)
				(type default)
			)
			(layer "F.Fab")
		)
		(fp_line
			(start 0.12065 -0.2794)
			(end 0.12065 -0.3048)
			(stroke
				(width 0.1)
				(type default)
			)
			(layer "F.Fab")
		)
		(fp_line
			(start 0.67945 -0.3048)
			(end 0.67945 0.3048)
			(stroke
				(width 0.1)
				(type default)
			)
			(layer "F.Fab")
		)
		(fp_line
			(start 0.67945 0.3048)
			(end 0.120396 0.3048)
			(stroke
				(width 0.1)
				(type default)
			)
			(layer "F.Fab")
		)
		(pad "1" smd circle
			(at -0.40005 0)
			(size 0 0)
			(layers "F.Cu" "F.Mask" "F.Paste")
			(net "P3V3_AUX")
		)
		(pad "2" smd circle
			(at 0.40005 0)
			(size 0 0)
			(layers "F.Cu" "F.Mask" "F.Paste")
			(net "P52V_FAN_0_BUFF_EN")
		)
	)
	(footprint ""
		(layer "F.Cu")
		(at 36.322 -116.008912)
		(property "Reference" "D278"
			(at 2.23774 -0.669798 0)
			(unlocked yes)
			(layer "F.SilkS")
			(effects
				(font
					(size 0.7874 0.5842)
					(thickness 0.1524)
				)
				(justify left)
			)
		)
		(property "Value" ""
			(at 0 0 0)
			(layer "F.Fab")
			(effects
				(font
					(size 1.27 1.27)
				)
			)
		)
		(duplicate_pad_numbers_are_jumpers no)
		(fp_line
			(start -0.854964 -0.450088)
			(end -0.854964 0.450088)
			(stroke
				(width 0.1524)
				(type default)
			)
			(layer "F.SilkS")
		)
		(fp_line
			(start -0.854964 0.450088)
			(end 0.925068 0.450088)
			(stroke
				(width 0.1524)
				(type default)
			)
			(layer "F.SilkS")
		)
		(fp_line
			(start 0.845058 0.4064)
			(end 0.845058 -0.381)
			(stroke
				(width 0.1524)
				(type default)
			)
			(layer "F.SilkS")
		)
		(fp_line
			(start 0.870458 -0.2794)
			(end 0.845058 0.4064)
			(stroke
				(width 0.1524)
				(type default)
			)
			(layer "F.SilkS")
		)
		(fp_line
			(start 0.94488 -0.450088)
			(end -0.854964 -0.450088)
			(stroke
				(width 0.1524)
				(type default)
			)
			(layer "F.SilkS")
		)
		(fp_line
			(start 0.94488 0.450088)
			(end 0.94488 -0.450088)
			(stroke
				(width 0.1524)
				(type default)
			)
			(layer "F.SilkS")
		)
		(fp_line
			(start -0.54991 -0.350012)
			(end -0.54991 0.350012)
			(stroke
				(width 0.1)
				(type default)
			)
			(layer "F.Fab")
		)
		(fp_line
			(start -0.54991 0.350012)
			(end 0.54991 0.350012)
			(stroke
				(width 0.1)
				(type default)
			)
			(layer "F.Fab")
		)
		(fp_line
			(start 0.54991 -0.350012)
			(end -0.54991 -0.350012)
			(stroke
				(width 0.1)
				(type default)
			)
			(layer "F.Fab")
		)
		(fp_line
			(start 0.54991 0.350012)
			(end 0.54991 -0.350012)
			(stroke
				(width 0.1)
				(type default)
			)
			(layer "F.Fab")
		)
		(fp_text user "+"
			(at -0.635 0.407162 180)
			(unlocked yes)
			(layer "F.SilkS")
			(effects
				(font
					(size 1.905 1.4224)
					(thickness 0.1524)
				)
				(justify left)
			)
		)
		(fp_text user "-"
			(at 2.159 0.407162 180)
			(unlocked yes)
			(layer "F.SilkS")
			(effects
				(font
					(size 1.905 1.4224)
					(thickness 0.1524)
				)
				(justify left)
			)
		)
		(fp_text user "+"
			(at -0.808228 0.239014 180)
			(unlocked yes)
			(layer "F.Fab")
			(effects
				(font
					(size 1.905 1.4224)
					(thickness 0.1524)
				)
				(justify left)
			)
		)
		(fp_text user "-"
			(at 2.48539 0.239014 180)
			(unlocked yes)
			(layer "F.Fab")
			(effects
				(font
					(size 1.905 1.4224)
					(thickness 0.1524)
				)
				(justify left)
			)
		)
		(pad "A" smd rect
			(at -0.424942 0)
			(size 0.5588 0.6096)
			(layers "F.Cu" "F.Mask" "F.Paste")
			(net "GND")
		)
		(pad "C" smd rect
			(at 0.424942 0 180)
			(size 0.5588 0.6096)
			(layers "F.Cu" "F.Mask" "F.Paste")
			(net "FAN_2_TACH_IL_D")
		)
	)
	(footprint ""
		(layer "F.Cu")
		(at 14.234922 -14.310868 180)
		(property "Reference" "R5128"
			(at 0 0 180)
			(layer "F.SilkS")
			(hide yes)
			(effects
				(font
					(size 1.27 1.27)
				)
			)
		)
		(property "Value" ""
			(at 0 0 180)
			(layer "F.Fab")
			(effects
				(font
					(size 1.27 1.27)
				)
			)
		)
		(duplicate_pad_numbers_are_jumpers no)
		(fp_line
			(start 0.7874 0.4064)
			(end -0.7874 0.4064)
			(stroke
				(width 0.1524)
				(type default)
			)
			(layer "F.SilkS")
		)
		(fp_line
			(start 0.7874 -0.4064)
			(end 0.7874 0.4064)
			(stroke
				(width 0.1524)
				(type default)
			)
			(layer "F.SilkS")
		)
		(fp_line
			(start -0.7874 0.4064)
			(end -0.7874 -0.4064)
			(stroke
				(width 0.1524)
				(type default)
			)
			(layer "F.SilkS")
		)
		(fp_line
			(start -0.7874 -0.4064)
			(end 0.7874 -0.4064)
			(stroke
				(width 0.1524)
				(type default)
			)
			(layer "F.SilkS")
		)
		(fp_line
			(start 0.67945 0.3048)
			(end 0.120396 0.3048)
			(stroke
				(width 0.1)
				(type default)
			)
			(layer "F.Fab")
		)
		(fp_line
			(start 0.67945 -0.3048)
			(end 0.67945 0.3048)
			(stroke
				(width 0.1)
				(type default)
			)
			(layer "F.Fab")
		)
		(fp_line
			(start 0.12065 -0.2794)
			(end 0.12065 -0.3048)
			(stroke
				(width 0.1)
				(type default)
			)
			(layer "F.Fab")
		)
		(fp_line
			(start 0.12065 -0.3048)
			(end 0.67945 -0.3048)
			(stroke
				(width 0.1)
				(type default)
			)
			(layer "F.Fab")
		)
		(fp_line
			(start 0.120396 0.3048)
			(end 0.120396 0.2794)
			(stroke
				(width 0.1)
				(type default)
			)
			(layer "F.Fab")
		)
		(fp_line
			(start 0.120396 0.2794)
			(end -0.12065 0.2794)
			(stroke
				(width 0.1)
				(type default)
			)
			(layer "F.Fab")
		)
		(fp_line
			(start -0.12065 0.3048)
			(end -0.67945 0.3048)
			(stroke
				(width 0.1)
				(type default)
			)
			(layer "F.Fab")
		)
		(fp_line
			(start -0.12065 0.2794)
			(end -0.12065 0.3048)
			(stroke
				(width 0.1)
				(type default)
			)
			(layer "F.Fab")
		)
		(fp_line
			(start -0.12065 -0.2794)
			(end 0.12065 -0.2794)
			(stroke
				(width 0.1)
				(type default)
			)
			(layer "F.Fab")
		)
		(fp_line
			(start -0.12065 -0.305054)
			(end -0.12065 -0.2794)
			(stroke
				(width 0.1)
				(type default)
			)
			(layer "F.Fab")
		)
		(fp_line
			(start -0.67945 0.3048)
			(end -0.67945 -0.305054)
			(stroke
				(width 0.1)
				(type default)
			)
			(layer "F.Fab")
		)
		(fp_line
			(start -0.67945 -0.305054)
			(end -0.12065 -0.305054)
			(stroke
				(width 0.1)
				(type default)
			)
			(layer "F.Fab")
		)
		(pad "1" smd circle
			(at -0.40005 0 180)
			(size 0 0)
			(layers "F.Cu" "F.Mask" "F.Paste")
			(net "FAN_4_PWM_OL")
		)
		(pad "2" smd circle
			(at 0.40005 0 180)
			(size 0 0)
			(layers "F.Cu" "F.Mask" "F.Paste")
			(net "FAN_4_PWM_OL_R")
		)
	)
	(footprint ""
		(layer "F.Cu")
		(at 18.415 -186.563)
		(property "Reference" "R313"
			(at 0 0 0)
			(layer "F.SilkS")
			(hide yes)
			(effects
				(font
					(size 1.27 1.27)
				)
			)
		)
		(property "Value" ""
			(at 0 0 0)
			(layer "F.Fab")
			(effects
				(font
					(size 1.27 1.27)
				)
			)
		)
		(duplicate_pad_numbers_are_jumpers no)
		(fp_line
			(start -0.7874 -0.4064)
			(end 0.7874 -0.4064)
			(stroke
				(width 0.1524)
				(type default)
			)
			(layer "F.SilkS")
		)
		(fp_line
			(start -0.7874 0.4064)
			(end -0.7874 -0.4064)
			(stroke
				(width 0.1524)
				(type default)
			)
			(layer "F.SilkS")
		)
		(fp_line
			(start 0.7874 -0.4064)
			(end 0.7874 0.4064)
			(stroke
				(width 0.1524)
				(type default)
			)
			(layer "F.SilkS")
		)
		(fp_line
			(start 0.7874 0.4064)
			(end -0.7874 0.4064)
			(stroke
				(width 0.1524)
				(type default)
			)
			(layer "F.SilkS")
		)
		(fp_line
			(start -0.67945 -0.305054)
			(end -0.12065 -0.305054)
			(stroke
				(width 0.1)
				(type default)
			)
			(layer "F.Fab")
		)
		(fp_line
			(start -0.67945 0.3048)
			(end -0.67945 -0.305054)
			(stroke
				(width 0.1)
				(type default)
			)
			(layer "F.Fab")
		)
		(fp_line
			(start -0.12065 -0.305054)
			(end -0.12065 -0.2794)
			(stroke
				(width 0.1)
				(type default)
			)
			(layer "F.Fab")
		)
		(fp_line
			(start -0.12065 -0.2794)
			(end 0.12065 -0.2794)
			(stroke
				(width 0.1)
				(type default)
			)
			(layer "F.Fab")
		)
		(fp_line
			(start -0.12065 0.2794)
			(end -0.12065 0.3048)
			(stroke
				(width 0.1)
				(type default)
			)
			(layer "F.Fab")
		)
		(fp_line
			(start -0.12065 0.3048)
			(end -0.67945 0.3048)
			(stroke
				(width 0.1)
				(type default)
			)
			(layer "F.Fab")
		)
		(fp_line
			(start 0.120396 0.2794)
			(end -0.12065 0.2794)
			(stroke
				(width 0.1)
				(type default)
			)
			(layer "F.Fab")
		)
		(fp_line
			(start 0.120396 0.3048)
			(end 0.120396 0.2794)
			(stroke
				(width 0.1)
				(type default)
			)
			(layer "F.Fab")
		)
		(fp_line
			(start 0.12065 -0.3048)
			(end 0.67945 -0.3048)
			(stroke
				(width 0.1)
				(type default)
			)
			(layer "F.Fab")
		)
		(fp_line
			(start 0.12065 -0.2794)
			(end 0.12065 -0.3048)
			(stroke
				(width 0.1)
				(type default)
			)
			(layer "F.Fab")
		)
		(fp_line
			(start 0.67945 -0.3048)
			(end 0.67945 0.3048)
			(stroke
				(width 0.1)
				(type default)
			)
			(layer "F.Fab")
		)
		(fp_line
			(start 0.67945 0.3048)
			(end 0.120396 0.3048)
			(stroke
				(width 0.1)
				(type default)
			)
			(layer "F.Fab")
		)
		(pad "1" smd circle
			(at -0.40005 0)
			(size 0 0)
			(layers "F.Cu" "F.Mask" "F.Paste")
			(net "SMB_FRU_DAT")
		)
		(pad "2" smd circle
			(at 0.40005 0)
			(size 0 0)
			(layers "F.Cu" "F.Mask" "F.Paste")
			(net "SMB_PDBV_FAN_SDA")
		)
	)
	(footprint ""
		(layer "F.Cu")
		(at 31.623 -143.891 -90)
		(property "Reference" "R4791"
			(at 0 0 270)
			(layer "F.SilkS")
			(hide yes)
			(effects
				(font
					(size 1.27 1.27)
				)
			)
		)
		(property "Value" ""
			(at 0 0 270)
			(layer "F.Fab")
			(effects
				(font
					(size 1.27 1.27)
				)
			)
		)
		(duplicate_pad_numbers_are_jumpers no)
		(fp_line
			(start -0.7874 0.4064)
			(end -0.7874 -0.4064)
			(stroke
				(width 0.1524)
				(type default)
			)
			(layer "F.SilkS")
		)
		(fp_line
			(start 0.7874 0.4064)
			(end -0.7874 0.4064)
			(stroke
				(width 0.1524)
				(type default)
			)
			(layer "F.SilkS")
		)
		(fp_line
			(start -0.7874 -0.4064)
			(end 0.7874 -0.4064)
			(stroke
				(width 0.1524)
				(type default)
			)
			(layer "F.SilkS")
		)
		(fp_line
			(start 0.7874 -0.4064)
			(end 0.7874 0.4064)
			(stroke
				(width 0.1524)
				(type default)
			)
			(layer "F.SilkS")
		)
		(fp_line
			(start -0.67945 0.3048)
			(end -0.67945 -0.305054)
			(stroke
				(width 0.1)
				(type default)
			)
			(layer "F.Fab")
		)
		(fp_line
			(start -0.12065 0.3048)
			(end -0.67945 0.3048)
			(stroke
				(width 0.1)
				(type default)
			)
			(layer "F.Fab")
		)
		(fp_line
			(start 0.120396 0.3048)
			(end 0.120396 0.2794)
			(stroke
				(width 0.1)
				(type default)
			)
			(layer "F.Fab")
		)
		(fp_line
			(start 0.67945 0.3048)
			(end 0.120396 0.3048)
			(stroke
				(width 0.1)
				(type default)
			)
			(layer "F.Fab")
		)
		(fp_line
			(start -0.12065 0.2794)
			(end -0.12065 0.3048)
			(stroke
				(width 0.1)
				(type default)
			)
			(layer "F.Fab")
		)
		(fp_line
			(start 0.120396 0.2794)
			(end -0.12065 0.2794)
			(stroke
				(width 0.1)
				(type default)
			)
			(layer "F.Fab")
		)
		(fp_line
			(start -0.12065 -0.2794)
			(end 0.12065 -0.2794)
			(stroke
				(width 0.1)
				(type default)
			)
			(layer "F.Fab")
		)
		(fp_line
			(start 0.12065 -0.2794)
			(end 0.12065 -0.3048)
			(stroke
				(width 0.1)
				(type default)
			)
			(layer "F.Fab")
		)
		(fp_line
			(start 0.12065 -0.3048)
			(end 0.67945 -0.3048)
			(stroke
				(width 0.1)
				(type default)
			)
			(layer "F.Fab")
		)
		(fp_line
			(start 0.67945 -0.3048)
			(end 0.67945 0.3048)
			(stroke
				(width 0.1)
				(type default)
			)
			(layer "F.Fab")
		)
		(fp_line
			(start -0.67945 -0.305054)
			(end -0.12065 -0.305054)
			(stroke
				(width 0.1)
				(type default)
			)
			(layer "F.Fab")
		)
		(fp_line
			(start -0.12065 -0.305054)
			(end -0.12065 -0.2794)
			(stroke
				(width 0.1)
				(type default)
			)
			(layer "F.Fab")
		)
		(pad "1" smd circle
			(at -0.40005 0 270)
			(size 0 0)
			(layers "F.Cu" "F.Mask" "F.Paste")
			(net "SMB_FAN2_R_SCL")
		)
		(pad "2" smd circle
			(at 0.40005 0 270)
			(size 0 0)
			(layers "F.Cu" "F.Mask" "F.Paste")
			(net "SMB_FAN2_SCL")
		)
	)
	(footprint ""
		(layer "F.Cu")
		(at 14.859 -132.334)
		(property "Reference" "R5617"
			(at 0 0 0)
			(layer "F.SilkS")
			(hide yes)
			(effects
				(font
					(size 1.27 1.27)
				)
			)
		)
		(property "Value" ""
			(at 0 0 0)
			(layer "F.Fab")
			(effects
				(font
					(size 1.27 1.27)
				)
			)
		)
		(duplicate_pad_numbers_are_jumpers no)
		(fp_line
			(start -0.7874 -0.4064)
			(end 0.7874 -0.4064)
			(stroke
				(width 0.1524)
				(type default)
			)
			(layer "F.SilkS")
		)
		(fp_line
			(start -0.7874 0.4064)
			(end -0.7874 -0.4064)
			(stroke
				(width 0.1524)
				(type default)
			)
			(layer "F.SilkS")
		)
		(fp_line
			(start 0.7874 -0.4064)
			(end 0.7874 0.4064)
			(stroke
				(width 0.1524)
				(type default)
			)
			(layer "F.SilkS")
		)
		(fp_line
			(start 0.7874 0.4064)
			(end -0.7874 0.4064)
			(stroke
				(width 0.1524)
				(type default)
			)
			(layer "F.SilkS")
		)
		(fp_line
			(start -0.67945 -0.305054)
			(end -0.12065 -0.305054)
			(stroke
				(width 0.1)
				(type default)
			)
			(layer "F.Fab")
		)
		(fp_line
			(start -0.67945 0.3048)
			(end -0.67945 -0.305054)
			(stroke
				(width 0.1)
				(type default)
			)
			(layer "F.Fab")
		)
		(fp_line
			(start -0.12065 -0.305054)
			(end -0.12065 -0.2794)
			(stroke
				(width 0.1)
				(type default)
			)
			(layer "F.Fab")
		)
		(fp_line
			(start -0.12065 -0.2794)
			(end 0.12065 -0.2794)
			(stroke
				(width 0.1)
				(type default)
			)
			(layer "F.Fab")
		)
		(fp_line
			(start -0.12065 0.2794)
			(end -0.12065 0.3048)
			(stroke
				(width 0.1)
				(type default)
			)
			(layer "F.Fab")
		)
		(fp_line
			(start -0.12065 0.3048)
			(end -0.67945 0.3048)
			(stroke
				(width 0.1)
				(type default)
			)
			(layer "F.Fab")
		)
		(fp_line
			(start 0.120396 0.2794)
			(end -0.12065 0.2794)
			(stroke
				(width 0.1)
				(type default)
			)
			(layer "F.Fab")
		)
		(fp_line
			(start 0.120396 0.3048)
			(end 0.120396 0.2794)
			(stroke
				(width 0.1)
				(type default)
			)
			(layer "F.Fab")
		)
		(fp_line
			(start 0.12065 -0.3048)
			(end 0.67945 -0.3048)
			(stroke
				(width 0.1)
				(type default)
			)
			(layer "F.Fab")
		)
		(fp_line
			(start 0.12065 -0.2794)
			(end 0.12065 -0.3048)
			(stroke
				(width 0.1)
				(type default)
			)
			(layer "F.Fab")
		)
		(fp_line
			(start 0.67945 -0.3048)
			(end 0.67945 0.3048)
			(stroke
				(width 0.1)
				(type default)
			)
			(layer "F.Fab")
		)
		(fp_line
			(start 0.67945 0.3048)
			(end 0.120396 0.3048)
			(stroke
				(width 0.1)
				(type default)
			)
			(layer "F.Fab")
		)
		(pad "1" smd rect
			(at -0.40005 0 180)
			(size 0.4572 0.508)
			(layers "F.Cu" "F.Mask" "F.Paste")
			(net "FAN_7_TACH_IL")
		)
		(pad "2" smd rect
			(at 0.40005 0 180)
			(size 0.4572 0.508)
			(layers "F.Cu" "F.Mask" "F.Paste")
			(net "FAN_7_TACH_IL_R1")
		)
	)
	(footprint ""
		(layer "F.Cu")
		(at 19.558 -22.479 -90)
		(property "Reference" "R4992"
			(at 0 0 270)
			(layer "F.SilkS")
			(hide yes)
			(effects
				(font
					(size 1.27 1.27)
				)
			)
		)
		(property "Value" ""
			(at 0 0 270)
			(layer "F.Fab")
			(effects
				(font
					(size 1.27 1.27)
				)
			)
		)
		(duplicate_pad_numbers_are_jumpers no)
		(fp_line
			(start -0.7874 0.4064)
			(end -0.7874 -0.4064)
			(stroke
				(width 0.1524)
				(type default)
			)
			(layer "F.SilkS")
		)
		(fp_line
			(start 0.7874 0.4064)
			(end -0.7874 0.4064)
			(stroke
				(width 0.1524)
				(type default)
			)
			(layer "F.SilkS")
		)
		(fp_line
			(start -0.7874 -0.4064)
			(end 0.7874 -0.4064)
			(stroke
				(width 0.1524)
				(type default)
			)
			(layer "F.SilkS")
		)
		(fp_line
			(start 0.7874 -0.4064)
			(end 0.7874 0.4064)
			(stroke
				(width 0.1524)
				(type default)
			)
			(layer "F.SilkS")
		)
		(fp_line
			(start -0.67945 0.3048)
			(end -0.67945 -0.305054)
			(stroke
				(width 0.1)
				(type default)
			)
			(layer "F.Fab")
		)
		(fp_line
			(start -0.12065 0.3048)
			(end -0.67945 0.3048)
			(stroke
				(width 0.1)
				(type default)
			)
			(layer "F.Fab")
		)
		(fp_line
			(start 0.120396 0.3048)
			(end 0.120396 0.2794)
			(stroke
				(width 0.1)
				(type default)
			)
			(layer "F.Fab")
		)
		(fp_line
			(start 0.67945 0.3048)
			(end 0.120396 0.3048)
			(stroke
				(width 0.1)
				(type default)
			)
			(layer "F.Fab")
		)
		(fp_line
			(start -0.12065 0.2794)
			(end -0.12065 0.3048)
			(stroke
				(width 0.1)
				(type default)
			)
			(layer "F.Fab")
		)
		(fp_line
			(start 0.120396 0.2794)
			(end -0.12065 0.2794)
			(stroke
				(width 0.1)
				(type default)
			)
			(layer "F.Fab")
		)
		(fp_line
			(start -0.12065 -0.2794)
			(end 0.12065 -0.2794)
			(stroke
				(width 0.1)
				(type default)
			)
			(layer "F.Fab")
		)
		(fp_line
			(start 0.12065 -0.2794)
			(end 0.12065 -0.3048)
			(stroke
				(width 0.1)
				(type default)
			)
			(layer "F.Fab")
		)
		(fp_line
			(start 0.12065 -0.3048)
			(end 0.67945 -0.3048)
			(stroke
				(width 0.1)
				(type default)
			)
			(layer "F.Fab")
		)
		(fp_line
			(start 0.67945 -0.3048)
			(end 0.67945 0.3048)
			(stroke
				(width 0.1)
				(type default)
			)
			(layer "F.Fab")
		)
		(fp_line
			(start -0.67945 -0.305054)
			(end -0.12065 -0.305054)
			(stroke
				(width 0.1)
				(type default)
			)
			(layer "F.Fab")
		)
		(fp_line
			(start -0.12065 -0.305054)
			(end -0.12065 -0.2794)
			(stroke
				(width 0.1)
				(type default)
			)
			(layer "F.Fab")
		)
		(pad "1" smd circle
			(at -0.40005 0 270)
			(size 0 0)
			(layers "F.Cu" "F.Mask" "F.Paste")
			(net "P3V3_AUX")
		)
		(pad "2" smd circle
			(at 0.40005 0 270)
			(size 0 0)
			(layers "F.Cu" "F.Mask" "F.Paste")
			(net "FAN_4_FAIL_R_LED")
		)
	)
	(footprint ""
		(layer "F.Cu")
		(at 40.767 -74.168)
		(property "Reference" "PR39"
			(at 0 0 0)
			(layer "F.SilkS")
			(hide yes)
			(effects
				(font
					(size 1.27 1.27)
				)
			)
		)
		(property "Value" ""
			(at 0 0 0)
			(layer "F.Fab")
			(effects
				(font
					(size 1.27 1.27)
				)
			)
		)
		(duplicate_pad_numbers_are_jumpers no)
		(fp_line
			(start -0.7874 -0.4064)
			(end 0.7874 -0.4064)
			(stroke
				(width 0.1524)
				(type default)
			)
			(layer "F.SilkS")
		)
		(fp_line
			(start -0.7874 0.4064)
			(end -0.7874 -0.4064)
			(stroke
				(width 0.1524)
				(type default)
			)
			(layer "F.SilkS")
		)
		(fp_line
			(start 0.7874 -0.4064)
			(end 0.7874 0.4064)
			(stroke
				(width 0.1524)
				(type default)
			)
			(layer "F.SilkS")
		)
		(fp_line
			(start 0.7874 0.4064)
			(end -0.7874 0.4064)
			(stroke
				(width 0.1524)
				(type default)
			)
			(layer "F.SilkS")
		)
		(fp_line
			(start -0.67945 -0.305054)
			(end -0.12065 -0.305054)
			(stroke
				(width 0.1)
				(type default)
			)
			(layer "F.Fab")
		)
		(fp_line
			(start -0.67945 0.3048)
			(end -0.67945 -0.305054)
			(stroke
				(width 0.1)
				(type default)
			)
			(layer "F.Fab")
		)
		(fp_line
			(start -0.12065 -0.305054)
			(end -0.12065 -0.2794)
			(stroke
				(width 0.1)
				(type default)
			)
			(layer "F.Fab")
		)
		(fp_line
			(start -0.12065 -0.2794)
			(end 0.12065 -0.2794)
			(stroke
				(width 0.1)
				(type default)
			)
			(layer "F.Fab")
		)
		(fp_line
			(start -0.12065 0.2794)
			(end -0.12065 0.3048)
			(stroke
				(width 0.1)
				(type default)
			)
			(layer "F.Fab")
		)
		(fp_line
			(start -0.12065 0.3048)
			(end -0.67945 0.3048)
			(stroke
				(width 0.1)
				(type default)
			)
			(layer "F.Fab")
		)
		(fp_line
			(start 0.120396 0.2794)
			(end -0.12065 0.2794)
			(stroke
				(width 0.1)
				(type default)
			)
			(layer "F.Fab")
		)
		(fp_line
			(start 0.120396 0.3048)
			(end 0.120396 0.2794)
			(stroke
				(width 0.1)
				(type default)
			)
			(layer "F.Fab")
		)
		(fp_line
			(start 0.12065 -0.3048)
			(end 0.67945 -0.3048)
			(stroke
				(width 0.1)
				(type default)
			)
			(layer "F.Fab")
		)
		(fp_line
			(start 0.12065 -0.2794)
			(end 0.12065 -0.3048)
			(stroke
				(width 0.1)
				(type default)
			)
			(layer "F.Fab")
		)
		(fp_line
			(start 0.67945 -0.3048)
			(end 0.67945 0.3048)
			(stroke
				(width 0.1)
				(type default)
			)
			(layer "F.Fab")
		)
		(fp_line
			(start 0.67945 0.3048)
			(end 0.120396 0.3048)
			(stroke
				(width 0.1)
				(type default)
			)
			(layer "F.Fab")
		)
		(pad "1" smd circle
			(at -0.40005 0)
			(size 0 0)
			(layers "F.Cu" "F.Mask" "F.Paste")
			(net "FAN_2_MODE")
		)
		(pad "2" smd circle
			(at 0.40005 0)
			(size 0 0)
			(layers "F.Cu" "F.Mask" "F.Paste")
			(net "GND")
		)
	)
	(footprint ""
		(layer "F.Cu")
		(at 45.593 -31.623 180)
		(property "Reference" "R5696"
			(at 0 0 180)
			(layer "F.SilkS")
			(hide yes)
			(effects
				(font
					(size 1.27 1.27)
				)
			)
		)
		(property "Value" ""
			(at 0 0 180)
			(layer "F.Fab")
			(effects
				(font
					(size 1.27 1.27)
				)
			)
		)
		(duplicate_pad_numbers_are_jumpers no)
		(fp_line
			(start 0.7874 0.4064)
			(end -0.7874 0.4064)
			(stroke
				(width 0.1524)
				(type default)
			)
			(layer "F.SilkS")
		)
		(fp_line
			(start 0.7874 -0.4064)
			(end 0.7874 0.4064)
			(stroke
				(width 0.1524)
				(type default)
			)
			(layer "F.SilkS")
		)
		(fp_line
			(start -0.7874 0.4064)
			(end -0.7874 -0.4064)
			(stroke
				(width 0.1524)
				(type default)
			)
			(layer "F.SilkS")
		)
		(fp_line
			(start -0.7874 -0.4064)
			(end 0.7874 -0.4064)
			(stroke
				(width 0.1524)
				(type default)
			)
			(layer "F.SilkS")
		)
		(fp_line
			(start 0.67945 0.3048)
			(end 0.120396 0.3048)
			(stroke
				(width 0.1)
				(type default)
			)
			(layer "F.Fab")
		)
		(fp_line
			(start 0.67945 -0.3048)
			(end 0.67945 0.3048)
			(stroke
				(width 0.1)
				(type default)
			)
			(layer "F.Fab")
		)
		(fp_line
			(start 0.12065 -0.2794)
			(end 0.12065 -0.3048)
			(stroke
				(width 0.1)
				(type default)
			)
			(layer "F.Fab")
		)
		(fp_line
			(start 0.12065 -0.3048)
			(end 0.67945 -0.3048)
			(stroke
				(width 0.1)
				(type default)
			)
			(layer "F.Fab")
		)
		(fp_line
			(start 0.120396 0.3048)
			(end 0.120396 0.2794)
			(stroke
				(width 0.1)
				(type default)
			)
			(layer "F.Fab")
		)
		(fp_line
			(start 0.120396 0.2794)
			(end -0.12065 0.2794)
			(stroke
				(width 0.1)
				(type default)
			)
			(layer "F.Fab")
		)
		(fp_line
			(start -0.12065 0.3048)
			(end -0.67945 0.3048)
			(stroke
				(width 0.1)
				(type default)
			)
			(layer "F.Fab")
		)
		(fp_line
			(start -0.12065 0.2794)
			(end -0.12065 0.3048)
			(stroke
				(width 0.1)
				(type default)
			)
			(layer "F.Fab")
		)
		(fp_line
			(start -0.12065 -0.2794)
			(end 0.12065 -0.2794)
			(stroke
				(width 0.1)
				(type default)
			)
			(layer "F.Fab")
		)
		(fp_line
			(start -0.12065 -0.305054)
			(end -0.12065 -0.2794)
			(stroke
				(width 0.1)
				(type default)
			)
			(layer "F.Fab")
		)
		(fp_line
			(start -0.67945 0.3048)
			(end -0.67945 -0.305054)
			(stroke
				(width 0.1)
				(type default)
			)
			(layer "F.Fab")
		)
		(fp_line
			(start -0.67945 -0.305054)
			(end -0.12065 -0.305054)
			(stroke
				(width 0.1)
				(type default)
			)
			(layer "F.Fab")
		)
		(pad "1" smd rect
			(at -0.40005 0)
			(size 0.4572 0.508)
			(layers "F.Cu" "F.Mask" "F.Paste")
			(net "P12V_LED_R_FAN3")
		)
		(pad "2" smd rect
			(at 0.40005 0)
			(size 0.4572 0.508)
			(layers "F.Cu" "F.Mask" "F.Paste")
			(net "P12V_LED_R1_FAN3")
		)
	)
	(footprint ""
		(layer "F.Cu")
		(at 18.034 -136.017 -90)
		(property "Reference" "R4950"
			(at 0 0 270)
			(layer "F.SilkS")
			(hide yes)
			(effects
				(font
					(size 1.27 1.27)
				)
			)
		)
		(property "Value" ""
			(at 0 0 270)
			(layer "F.Fab")
			(effects
				(font
					(size 1.27 1.27)
				)
			)
		)
		(duplicate_pad_numbers_are_jumpers no)
		(fp_line
			(start -0.7874 0.4064)
			(end -0.7874 -0.4064)
			(stroke
				(width 0.1524)
				(type default)
			)
			(layer "F.SilkS")
		)
		(fp_line
			(start 0.7874 0.4064)
			(end -0.7874 0.4064)
			(stroke
				(width 0.1524)
				(type default)
			)
			(layer "F.SilkS")
		)
		(fp_line
			(start -0.7874 -0.4064)
			(end 0.7874 -0.4064)
			(stroke
				(width 0.1524)
				(type default)
			)
			(layer "F.SilkS")
		)
		(fp_line
			(start 0.7874 -0.4064)
			(end 0.7874 0.4064)
			(stroke
				(width 0.1524)
				(type default)
			)
			(layer "F.SilkS")
		)
		(fp_line
			(start -0.67945 0.3048)
			(end -0.67945 -0.305054)
			(stroke
				(width 0.1)
				(type default)
			)
			(layer "F.Fab")
		)
		(fp_line
			(start -0.12065 0.3048)
			(end -0.67945 0.3048)
			(stroke
				(width 0.1)
				(type default)
			)
			(layer "F.Fab")
		)
		(fp_line
			(start 0.120396 0.3048)
			(end 0.120396 0.2794)
			(stroke
				(width 0.1)
				(type default)
			)
			(layer "F.Fab")
		)
		(fp_line
			(start 0.67945 0.3048)
			(end 0.120396 0.3048)
			(stroke
				(width 0.1)
				(type default)
			)
			(layer "F.Fab")
		)
		(fp_line
			(start -0.12065 0.2794)
			(end -0.12065 0.3048)
			(stroke
				(width 0.1)
				(type default)
			)
			(layer "F.Fab")
		)
		(fp_line
			(start 0.120396 0.2794)
			(end -0.12065 0.2794)
			(stroke
				(width 0.1)
				(type default)
			)
			(layer "F.Fab")
		)
		(fp_line
			(start -0.12065 -0.2794)
			(end 0.12065 -0.2794)
			(stroke
				(width 0.1)
				(type default)
			)
			(layer "F.Fab")
		)
		(fp_line
			(start 0.12065 -0.2794)
			(end 0.12065 -0.3048)
			(stroke
				(width 0.1)
				(type default)
			)
			(layer "F.Fab")
		)
		(fp_line
			(start 0.12065 -0.3048)
			(end 0.67945 -0.3048)
			(stroke
				(width 0.1)
				(type default)
			)
			(layer "F.Fab")
		)
		(fp_line
			(start 0.67945 -0.3048)
			(end 0.67945 0.3048)
			(stroke
				(width 0.1)
				(type default)
			)
			(layer "F.Fab")
		)
		(fp_line
			(start -0.67945 -0.305054)
			(end -0.12065 -0.305054)
			(stroke
				(width 0.1)
				(type default)
			)
			(layer "F.Fab")
		)
		(fp_line
			(start -0.12065 -0.305054)
			(end -0.12065 -0.2794)
			(stroke
				(width 0.1)
				(type default)
			)
			(layer "F.Fab")
		)
		(pad "1" smd circle
			(at -0.40005 0 270)
			(size 0 0)
			(layers "F.Cu" "F.Mask" "F.Paste")
			(net "GND")
		)
		(pad "2" smd circle
			(at 0.40005 0 270)
			(size 0 0)
			(layers "F.Cu" "F.Mask" "F.Paste")
			(net "MAX31790_U330_WD_START")
		)
	)
	(footprint ""
		(layer "F.Cu")
		(at 43.561 -165.481 180)
		(property "Reference" "R5112"
			(at 0 0 180)
			(layer "F.SilkS")
			(hide yes)
			(effects
				(font
					(size 1.27 1.27)
				)
			)
		)
		(property "Value" ""
			(at 0 0 180)
			(layer "F.Fab")
			(effects
				(font
					(size 1.27 1.27)
				)
			)
		)
		(duplicate_pad_numbers_are_jumpers no)
		(fp_line
			(start 0.7874 0.4064)
			(end -0.7874 0.4064)
			(stroke
				(width 0.1524)
				(type default)
			)
			(layer "F.SilkS")
		)
		(fp_line
			(start 0.7874 -0.4064)
			(end 0.7874 0.4064)
			(stroke
				(width 0.1524)
				(type default)
			)
			(layer "F.SilkS")
		)
		(fp_line
			(start -0.7874 0.4064)
			(end -0.7874 -0.4064)
			(stroke
				(width 0.1524)
				(type default)
			)
			(layer "F.SilkS")
		)
		(fp_line
			(start -0.7874 -0.4064)
			(end 0.7874 -0.4064)
			(stroke
				(width 0.1524)
				(type default)
			)
			(layer "F.SilkS")
		)
		(fp_line
			(start 0.67945 0.3048)
			(end 0.120396 0.3048)
			(stroke
				(width 0.1)
				(type default)
			)
			(layer "F.Fab")
		)
		(fp_line
			(start 0.67945 -0.3048)
			(end 0.67945 0.3048)
			(stroke
				(width 0.1)
				(type default)
			)
			(layer "F.Fab")
		)
		(fp_line
			(start 0.12065 -0.2794)
			(end 0.12065 -0.3048)
			(stroke
				(width 0.1)
				(type default)
			)
			(layer "F.Fab")
		)
		(fp_line
			(start 0.12065 -0.3048)
			(end 0.67945 -0.3048)
			(stroke
				(width 0.1)
				(type default)
			)
			(layer "F.Fab")
		)
		(fp_line
			(start 0.120396 0.3048)
			(end 0.120396 0.2794)
			(stroke
				(width 0.1)
				(type default)
			)
			(layer "F.Fab")
		)
		(fp_line
			(start 0.120396 0.2794)
			(end -0.12065 0.2794)
			(stroke
				(width 0.1)
				(type default)
			)
			(layer "F.Fab")
		)
		(fp_line
			(start -0.12065 0.3048)
			(end -0.67945 0.3048)
			(stroke
				(width 0.1)
				(type default)
			)
			(layer "F.Fab")
		)
		(fp_line
			(start -0.12065 0.2794)
			(end -0.12065 0.3048)
			(stroke
				(width 0.1)
				(type default)
			)
			(layer "F.Fab")
		)
		(fp_line
			(start -0.12065 -0.2794)
			(end 0.12065 -0.2794)
			(stroke
				(width 0.1)
				(type default)
			)
			(layer "F.Fab")
		)
		(fp_line
			(start -0.12065 -0.305054)
			(end -0.12065 -0.2794)
			(stroke
				(width 0.1)
				(type default)
			)
			(layer "F.Fab")
		)
		(fp_line
			(start -0.67945 0.3048)
			(end -0.67945 -0.305054)
			(stroke
				(width 0.1)
				(type default)
			)
			(layer "F.Fab")
		)
		(fp_line
			(start -0.67945 -0.305054)
			(end -0.12065 -0.305054)
			(stroke
				(width 0.1)
				(type default)
			)
			(layer "F.Fab")
		)
		(pad "1" smd circle
			(at -0.40005 0 180)
			(size 0 0)
			(layers "F.Cu" "F.Mask" "F.Paste")
			(net "P3V3_AUX")
		)
		(pad "2" smd circle
			(at 0.40005 0 180)
			(size 0 0)
			(layers "F.Cu" "F.Mask" "F.Paste")
			(net "PCA9552_MB1_A0")
		)
	)
	(footprint ""
		(layer "F.Cu")
		(at 35.306 -64.897 -90)
		(property "Reference" "PR22"
			(at 0 0 270)
			(layer "F.SilkS")
			(hide yes)
			(effects
				(font
					(size 1.27 1.27)
				)
			)
		)
		(property "Value" ""
			(at 0 0 270)
			(layer "F.Fab")
			(effects
				(font
					(size 1.27 1.27)
				)
			)
		)
		(duplicate_pad_numbers_are_jumpers no)
		(fp_line
			(start -0.7874 0.4064)
			(end -0.7874 -0.4064)
			(stroke
				(width 0.1524)
				(type default)
			)
			(layer "F.SilkS")
		)
		(fp_line
			(start 0.7874 0.4064)
			(end -0.7874 0.4064)
			(stroke
				(width 0.1524)
				(type default)
			)
			(layer "F.SilkS")
		)
		(fp_line
			(start -0.7874 -0.4064)
			(end 0.7874 -0.4064)
			(stroke
				(width 0.1524)
				(type default)
			)
			(layer "F.SilkS")
		)
		(fp_line
			(start 0.7874 -0.4064)
			(end 0.7874 0.4064)
			(stroke
				(width 0.1524)
				(type default)
			)
			(layer "F.SilkS")
		)
		(fp_line
			(start -0.67945 0.3048)
			(end -0.67945 -0.305054)
			(stroke
				(width 0.1)
				(type default)
			)
			(layer "F.Fab")
		)
		(fp_line
			(start -0.12065 0.3048)
			(end -0.67945 0.3048)
			(stroke
				(width 0.1)
				(type default)
			)
			(layer "F.Fab")
		)
		(fp_line
			(start 0.120396 0.3048)
			(end 0.120396 0.2794)
			(stroke
				(width 0.1)
				(type default)
			)
			(layer "F.Fab")
		)
		(fp_line
			(start 0.67945 0.3048)
			(end 0.120396 0.3048)
			(stroke
				(width 0.1)
				(type default)
			)
			(layer "F.Fab")
		)
		(fp_line
			(start -0.12065 0.2794)
			(end -0.12065 0.3048)
			(stroke
				(width 0.1)
				(type default)
			)
			(layer "F.Fab")
		)
		(fp_line
			(start 0.120396 0.2794)
			(end -0.12065 0.2794)
			(stroke
				(width 0.1)
				(type default)
			)
			(layer "F.Fab")
		)
		(fp_line
			(start -0.12065 -0.2794)
			(end 0.12065 -0.2794)
			(stroke
				(width 0.1)
				(type default)
			)
			(layer "F.Fab")
		)
		(fp_line
			(start 0.12065 -0.2794)
			(end 0.12065 -0.3048)
			(stroke
				(width 0.1)
				(type default)
			)
			(layer "F.Fab")
		)
		(fp_line
			(start 0.12065 -0.3048)
			(end 0.67945 -0.3048)
			(stroke
				(width 0.1)
				(type default)
			)
			(layer "F.Fab")
		)
		(fp_line
			(start 0.67945 -0.3048)
			(end 0.67945 0.3048)
			(stroke
				(width 0.1)
				(type default)
			)
			(layer "F.Fab")
		)
		(fp_line
			(start -0.67945 -0.305054)
			(end -0.12065 -0.305054)
			(stroke
				(width 0.1)
				(type default)
			)
			(layer "F.Fab")
		)
		(fp_line
			(start -0.12065 -0.305054)
			(end -0.12065 -0.2794)
			(stroke
				(width 0.1)
				(type default)
			)
			(layer "F.Fab")
		)
		(pad "1" smd rect
			(at -0.40005 0 90)
			(size 0.4572 0.508)
			(layers "F.Cu" "F.Mask" "F.Paste")
			(net "FAN_3_FAULT_R")
		)
		(pad "2" smd rect
			(at 0.40005 0 90)
			(size 0.4572 0.508)
			(layers "F.Cu" "F.Mask" "F.Paste")
			(net "FAN_3_FAULT")
		)
	)
	(footprint ""
		(layer "F.Cu")
		(at 28.956 -170.561 180)
		(property "Reference" "R5111"
			(at 0 0 180)
			(layer "F.SilkS")
			(hide yes)
			(effects
				(font
					(size 1.27 1.27)
				)
			)
		)
		(property "Value" ""
			(at 0 0 180)
			(layer "F.Fab")
			(effects
				(font
					(size 1.27 1.27)
				)
			)
		)
		(duplicate_pad_numbers_are_jumpers no)
		(fp_line
			(start 0.7874 0.4064)
			(end -0.7874 0.4064)
			(stroke
				(width 0.1524)
				(type default)
			)
			(layer "F.SilkS")
		)
		(fp_line
			(start 0.7874 -0.4064)
			(end 0.7874 0.4064)
			(stroke
				(width 0.1524)
				(type default)
			)
			(layer "F.SilkS")
		)
		(fp_line
			(start -0.7874 0.4064)
			(end -0.7874 -0.4064)
			(stroke
				(width 0.1524)
				(type default)
			)
			(layer "F.SilkS")
		)
		(fp_line
			(start -0.7874 -0.4064)
			(end 0.7874 -0.4064)
			(stroke
				(width 0.1524)
				(type default)
			)
			(layer "F.SilkS")
		)
		(fp_line
			(start 0.67945 0.3048)
			(end 0.120396 0.3048)
			(stroke
				(width 0.1)
				(type default)
			)
			(layer "F.Fab")
		)
		(fp_line
			(start 0.67945 -0.3048)
			(end 0.67945 0.3048)
			(stroke
				(width 0.1)
				(type default)
			)
			(layer "F.Fab")
		)
		(fp_line
			(start 0.12065 -0.2794)
			(end 0.12065 -0.3048)
			(stroke
				(width 0.1)
				(type default)
			)
			(layer "F.Fab")
		)
		(fp_line
			(start 0.12065 -0.3048)
			(end 0.67945 -0.3048)
			(stroke
				(width 0.1)
				(type default)
			)
			(layer "F.Fab")
		)
		(fp_line
			(start 0.120396 0.3048)
			(end 0.120396 0.2794)
			(stroke
				(width 0.1)
				(type default)
			)
			(layer "F.Fab")
		)
		(fp_line
			(start 0.120396 0.2794)
			(end -0.12065 0.2794)
			(stroke
				(width 0.1)
				(type default)
			)
			(layer "F.Fab")
		)
		(fp_line
			(start -0.12065 0.3048)
			(end -0.67945 0.3048)
			(stroke
				(width 0.1)
				(type default)
			)
			(layer "F.Fab")
		)
		(fp_line
			(start -0.12065 0.2794)
			(end -0.12065 0.3048)
			(stroke
				(width 0.1)
				(type default)
			)
			(layer "F.Fab")
		)
		(fp_line
			(start -0.12065 -0.2794)
			(end 0.12065 -0.2794)
			(stroke
				(width 0.1)
				(type default)
			)
			(layer "F.Fab")
		)
		(fp_line
			(start -0.12065 -0.305054)
			(end -0.12065 -0.2794)
			(stroke
				(width 0.1)
				(type default)
			)
			(layer "F.Fab")
		)
		(fp_line
			(start -0.67945 0.3048)
			(end -0.67945 -0.305054)
			(stroke
				(width 0.1)
				(type default)
			)
			(layer "F.Fab")
		)
		(fp_line
			(start -0.67945 -0.305054)
			(end -0.12065 -0.305054)
			(stroke
				(width 0.1)
				(type default)
			)
			(layer "F.Fab")
		)
		(pad "1" smd circle
			(at -0.40005 0 180)
			(size 0 0)
			(layers "F.Cu" "F.Mask" "F.Paste")
			(net "FAN_7_FAIL_LED")
		)
		(pad "2" smd circle
			(at 0.40005 0 180)
			(size 0 0)
			(layers "F.Cu" "F.Mask" "F.Paste")
			(net "FAN_7_FAIL_R_LED")
		)
	)
	(footprint ""
		(layer "F.Cu")
		(at 25.654 -25.654 180)
		(property "Reference" "U67"
			(at 1.05664 1.80467 0)
			(unlocked yes)
			(layer "F.SilkS")
			(effects
				(font
					(size 0.7874 0.5842)
					(thickness 0.1524)
				)
				(justify left)
			)
		)
		(property "Value" ""
			(at 0 0 180)
			(layer "F.Fab")
			(effects
				(font
					(size 1.27 1.27)
				)
			)
		)
		(duplicate_pad_numbers_are_jumpers no)
		(fp_line
			(start 1.538478 1.150874)
			(end 1.538478 -1.150874)
			(stroke
				(width 0.1524)
				(type default)
			)
			(layer "F.SilkS")
		)
		(fp_line
			(start 1.538478 -1.150874)
			(end -1.538478 -1.150874)
			(stroke
				(width 0.1524)
				(type default)
			)
			(layer "F.SilkS")
		)
		(fp_line
			(start -1.538478 1.150874)
			(end 1.538478 1.150874)
			(stroke
				(width 0.1524)
				(type default)
			)
			(layer "F.SilkS")
		)
		(fp_line
			(start -1.538478 -1.150874)
			(end -1.538478 1.150874)
			(stroke
				(width 0.1524)
				(type default)
			)
			(layer "F.SilkS")
		)
		(fp_line
			(start 0.674878 1.100074)
			(end 0.674878 -1.100074)
			(stroke
				(width 0.1)
				(type default)
			)
			(layer "F.Fab")
		)
		(fp_line
			(start 0.674878 -1.100074)
			(end -0.674878 -1.100074)
			(stroke
				(width 0.1)
				(type default)
			)
			(layer "F.Fab")
		)
		(fp_line
			(start -0.674878 1.100074)
			(end 0.674878 1.100074)
			(stroke
				(width 0.1)
				(type default)
			)
			(layer "F.Fab")
		)
		(fp_line
			(start -0.674878 -1.100074)
			(end -0.674878 1.100074)
			(stroke
				(width 0.1)
				(type default)
			)
			(layer "F.Fab")
		)
		(pad "1" smd rect
			(at -0.94996 -0.649986 270)
			(size 0.7112 0.9144)
			(layers "F.Cu" "F.Mask" "F.Paste")
			(net "FAN_3_PWM_IL")
		)
		(pad "2" smd rect
			(at -0.94996 0.649986 270)
			(size 0.7112 0.9144)
			(layers "F.Cu" "F.Mask" "F.Paste")
			(net "FAN_3_PWM_OL")
		)
		(pad "3" smd rect
			(at 0.94996 0 270)
			(size 0.7112 0.9144)
			(layers "F.Cu" "F.Mask" "F.Paste")
			(net "FAN_3_PWM_BUF")
		)
	)
	(footprint ""
		(layer "F.Cu")
		(at 15.621 -173.99)
		(property "Reference" "C1948"
			(at 0 0 0)
			(layer "F.SilkS")
			(hide yes)
			(effects
				(font
					(size 1.27 1.27)
				)
			)
		)
		(property "Value" ""
			(at 0 0 0)
			(layer "F.Fab")
			(effects
				(font
					(size 1.27 1.27)
				)
			)
		)
		(duplicate_pad_numbers_are_jumpers no)
		(fp_line
			(start -0.7874 -0.4064)
			(end 0.7874 -0.4064)
			(stroke
				(width 0.1524)
				(type default)
			)
			(layer "F.SilkS")
		)
		(fp_line
			(start -0.7874 0.4064)
			(end -0.7874 -0.4064)
			(stroke
				(width 0.1524)
				(type default)
			)
			(layer "F.SilkS")
		)
		(fp_line
			(start 0.7874 -0.4064)
			(end 0.7874 0.4064)
			(stroke
				(width 0.1524)
				(type default)
			)
			(layer "F.SilkS")
		)
		(fp_line
			(start 0.7874 0.4064)
			(end -0.7874 0.4064)
			(stroke
				(width 0.1524)
				(type default)
			)
			(layer "F.SilkS")
		)
		(fp_line
			(start -0.67945 -0.305054)
			(end -0.12065 -0.305054)
			(stroke
				(width 0.1)
				(type default)
			)
			(layer "F.Fab")
		)
		(fp_line
			(start -0.67945 0.3048)
			(end -0.67945 -0.305054)
			(stroke
				(width 0.1)
				(type default)
			)
			(layer "F.Fab")
		)
		(fp_line
			(start -0.12065 -0.305054)
			(end -0.12065 -0.2794)
			(stroke
				(width 0.1)
				(type default)
			)
			(layer "F.Fab")
		)
		(fp_line
			(start -0.12065 -0.2794)
			(end 0.12065 -0.2794)
			(stroke
				(width 0.1)
				(type default)
			)
			(layer "F.Fab")
		)
		(fp_line
			(start -0.12065 0.2794)
			(end -0.12065 0.3048)
			(stroke
				(width 0.1)
				(type default)
			)
			(layer "F.Fab")
		)
		(fp_line
			(start -0.12065 0.3048)
			(end -0.67945 0.3048)
			(stroke
				(width 0.1)
				(type default)
			)
			(layer "F.Fab")
		)
		(fp_line
			(start 0.120396 0.2794)
			(end -0.12065 0.2794)
			(stroke
				(width 0.1)
				(type default)
			)
			(layer "F.Fab")
		)
		(fp_line
			(start 0.120396 0.3048)
			(end 0.120396 0.2794)
			(stroke
				(width 0.1)
				(type default)
			)
			(layer "F.Fab")
		)
		(fp_line
			(start 0.12065 -0.3048)
			(end 0.67945 -0.3048)
			(stroke
				(width 0.1)
				(type default)
			)
			(layer "F.Fab")
		)
		(fp_line
			(start 0.12065 -0.2794)
			(end 0.12065 -0.3048)
			(stroke
				(width 0.1)
				(type default)
			)
			(layer "F.Fab")
		)
		(fp_line
			(start 0.67945 -0.3048)
			(end 0.67945 0.3048)
			(stroke
				(width 0.1)
				(type default)
			)
			(layer "F.Fab")
		)
		(fp_line
			(start 0.67945 0.3048)
			(end 0.120396 0.3048)
			(stroke
				(width 0.1)
				(type default)
			)
			(layer "F.Fab")
		)
		(pad "1" smd circle
			(at -0.40005 0)
			(size 0 0)
			(layers "F.Cu" "F.Mask" "F.Paste")
			(net "FAN_7_PRESENT_N")
		)
		(pad "2" smd circle
			(at 0.40005 0)
			(size 0 0)
			(layers "F.Cu" "F.Mask" "F.Paste")
			(net "GND")
		)
	)
	(footprint ""
		(layer "F.Cu")
		(at 21.717 -119.126 90)
		(property "Reference" "C2088"
			(at 0 0 90)
			(layer "F.SilkS")
			(hide yes)
			(effects
				(font
					(size 1.27 1.27)
				)
			)
		)
		(property "Value" ""
			(at 0 0 90)
			(layer "F.Fab")
			(effects
				(font
					(size 1.27 1.27)
				)
			)
		)
		(duplicate_pad_numbers_are_jumpers no)
		(fp_line
			(start 0.7874 -0.4064)
			(end 0.7874 0.4064)
			(stroke
				(width 0.1524)
				(type default)
			)
			(layer "F.SilkS")
		)
		(fp_line
			(start -0.7874 -0.4064)
			(end 0.7874 -0.4064)
			(stroke
				(width 0.1524)
				(type default)
			)
			(layer "F.SilkS")
		)
		(fp_line
			(start 0.7874 0.4064)
			(end -0.7874 0.4064)
			(stroke
				(width 0.1524)
				(type default)
			)
			(layer "F.SilkS")
		)
		(fp_line
			(start -0.7874 0.4064)
			(end -0.7874 -0.4064)
			(stroke
				(width 0.1524)
				(type default)
			)
			(layer "F.SilkS")
		)
		(fp_line
			(start -0.12065 -0.305054)
			(end -0.12065 -0.2794)
			(stroke
				(width 0.1)
				(type default)
			)
			(layer "F.Fab")
		)
		(fp_line
			(start -0.67945 -0.305054)
			(end -0.12065 -0.305054)
			(stroke
				(width 0.1)
				(type default)
			)
			(layer "F.Fab")
		)
		(fp_line
			(start 0.67945 -0.3048)
			(end 0.67945 0.3048)
			(stroke
				(width 0.1)
				(type default)
			)
			(layer "F.Fab")
		)
		(fp_line
			(start 0.12065 -0.3048)
			(end 0.67945 -0.3048)
			(stroke
				(width 0.1)
				(type default)
			)
			(layer "F.Fab")
		)
		(fp_line
			(start 0.12065 -0.2794)
			(end 0.12065 -0.3048)
			(stroke
				(width 0.1)
				(type default)
			)
			(layer "F.Fab")
		)
		(fp_line
			(start -0.12065 -0.2794)
			(end 0.12065 -0.2794)
			(stroke
				(width 0.1)
				(type default)
			)
			(layer "F.Fab")
		)
		(fp_line
			(start 0.120396 0.2794)
			(end -0.12065 0.2794)
			(stroke
				(width 0.1)
				(type default)
			)
			(layer "F.Fab")
		)
		(fp_line
			(start -0.12065 0.2794)
			(end -0.12065 0.3048)
			(stroke
				(width 0.1)
				(type default)
			)
			(layer "F.Fab")
		)
		(fp_line
			(start 0.67945 0.3048)
			(end 0.120396 0.3048)
			(stroke
				(width 0.1)
				(type default)
			)
			(layer "F.Fab")
		)
		(fp_line
			(start 0.120396 0.3048)
			(end 0.120396 0.2794)
			(stroke
				(width 0.1)
				(type default)
			)
			(layer "F.Fab")
		)
		(fp_line
			(start -0.12065 0.3048)
			(end -0.67945 0.3048)
			(stroke
				(width 0.1)
				(type default)
			)
			(layer "F.Fab")
		)
		(fp_line
			(start -0.67945 0.3048)
			(end -0.67945 -0.305054)
			(stroke
				(width 0.1)
				(type default)
			)
			(layer "F.Fab")
		)
		(pad "1" smd circle
			(at -0.40005 0 90)
			(size 0 0)
			(layers "F.Cu" "F.Mask" "F.Paste")
			(net "P3V3_AUX")
		)
		(pad "2" smd circle
			(at 0.40005 0 90)
			(size 0 0)
			(layers "F.Cu" "F.Mask" "F.Paste")
			(net "GND")
		)
	)
	(footprint ""
		(layer "F.Cu")
		(at 37.465 -251.206)
		(property "Reference" "PR27"
			(at 0 0 0)
			(layer "F.SilkS")
			(hide yes)
			(effects
				(font
					(size 1.27 1.27)
				)
			)
		)
		(property "Value" ""
			(at 0 0 0)
			(layer "F.Fab")
			(effects
				(font
					(size 1.27 1.27)
				)
			)
		)
		(duplicate_pad_numbers_are_jumpers no)
		(fp_line
			(start -0.7874 -0.4064)
			(end 0.7874 -0.4064)
			(stroke
				(width 0.1524)
				(type default)
			)
			(layer "F.SilkS")
		)
		(fp_line
			(start -0.7874 0.4064)
			(end -0.7874 -0.4064)
			(stroke
				(width 0.1524)
				(type default)
			)
			(layer "F.SilkS")
		)
		(fp_line
			(start 0.7874 -0.4064)
			(end 0.7874 0.4064)
			(stroke
				(width 0.1524)
				(type default)
			)
			(layer "F.SilkS")
		)
		(fp_line
			(start 0.7874 0.4064)
			(end -0.7874 0.4064)
			(stroke
				(width 0.1524)
				(type default)
			)
			(layer "F.SilkS")
		)
		(fp_line
			(start -0.67945 -0.305054)
			(end -0.12065 -0.305054)
			(stroke
				(width 0.1)
				(type default)
			)
			(layer "F.Fab")
		)
		(fp_line
			(start -0.67945 0.3048)
			(end -0.67945 -0.305054)
			(stroke
				(width 0.1)
				(type default)
			)
			(layer "F.Fab")
		)
		(fp_line
			(start -0.12065 -0.305054)
			(end -0.12065 -0.2794)
			(stroke
				(width 0.1)
				(type default)
			)
			(layer "F.Fab")
		)
		(fp_line
			(start -0.12065 -0.2794)
			(end 0.12065 -0.2794)
			(stroke
				(width 0.1)
				(type default)
			)
			(layer "F.Fab")
		)
		(fp_line
			(start -0.12065 0.2794)
			(end -0.12065 0.3048)
			(stroke
				(width 0.1)
				(type default)
			)
			(layer "F.Fab")
		)
		(fp_line
			(start -0.12065 0.3048)
			(end -0.67945 0.3048)
			(stroke
				(width 0.1)
				(type default)
			)
			(layer "F.Fab")
		)
		(fp_line
			(start 0.120396 0.2794)
			(end -0.12065 0.2794)
			(stroke
				(width 0.1)
				(type default)
			)
			(layer "F.Fab")
		)
		(fp_line
			(start 0.120396 0.3048)
			(end 0.120396 0.2794)
			(stroke
				(width 0.1)
				(type default)
			)
			(layer "F.Fab")
		)
		(fp_line
			(start 0.12065 -0.3048)
			(end 0.67945 -0.3048)
			(stroke
				(width 0.1)
				(type default)
			)
			(layer "F.Fab")
		)
		(fp_line
			(start 0.12065 -0.2794)
			(end 0.12065 -0.3048)
			(stroke
				(width 0.1)
				(type default)
			)
			(layer "F.Fab")
		)
		(fp_line
			(start 0.67945 -0.3048)
			(end 0.67945 0.3048)
			(stroke
				(width 0.1)
				(type default)
			)
			(layer "F.Fab")
		)
		(fp_line
			(start 0.67945 0.3048)
			(end 0.120396 0.3048)
			(stroke
				(width 0.1)
				(type default)
			)
			(layer "F.Fab")
		)
		(pad "1" smd circle
			(at -0.40005 0)
			(size 0 0)
			(layers "F.Cu" "F.Mask" "F.Paste")
			(net "FAN_1_FAULT_R")
		)
		(pad "2" smd circle
			(at 0.40005 0)
			(size 0 0)
			(layers "F.Cu" "F.Mask" "F.Paste")
			(net "FAN_1_P3V_R")
		)
	)
	(footprint ""
		(layer "F.Cu")
		(at 36.322 -103.435912)
		(property "Reference" "D139"
			(at 2.54 0.465582 0)
			(unlocked yes)
			(layer "F.SilkS")
			(effects
				(font
					(size 0.7874 0.5842)
					(thickness 0.1524)
				)
				(justify left)
			)
		)
		(property "Value" ""
			(at 0 0 0)
			(layer "F.Fab")
			(effects
				(font
					(size 1.27 1.27)
				)
			)
		)
		(duplicate_pad_numbers_are_jumpers no)
		(fp_line
			(start -1.651 -0.7112)
			(end 2.032 -0.7112)
			(stroke
				(width 0.1524)
				(type default)
			)
			(layer "F.SilkS")
		)
		(fp_line
			(start -1.651 0.7112)
			(end -1.651 -0.7112)
			(stroke
				(width 0.1524)
				(type default)
			)
			(layer "F.SilkS")
		)
		(fp_line
			(start -0.299974 -0.500126)
			(end -0.299974 0.500126)
			(stroke
				(width 0.1524)
				(type default)
			)
			(layer "F.SilkS")
		)
		(fp_line
			(start -0.299974 0.500126)
			(end 0.199898 0)
			(stroke
				(width 0.1524)
				(type default)
			)
			(layer "F.SilkS")
		)
		(fp_line
			(start 0.199898 0)
			(end -0.299974 -0.500126)
			(stroke
				(width 0.1524)
				(type default)
			)
			(layer "F.SilkS")
		)
		(fp_line
			(start 0.299974 -0.500126)
			(end 0.299974 0.500126)
			(stroke
				(width 0.1524)
				(type default)
			)
			(layer "F.SilkS")
		)
		(fp_line
			(start 1.651 -0.6858)
			(end 1.651 0.6858)
			(stroke
				(width 0.1524)
				(type default)
			)
			(layer "F.SilkS")
		)
		(fp_line
			(start 1.778 0.6858)
			(end 1.778 -0.6858)
			(stroke
				(width 0.1524)
				(type default)
			)
			(layer "F.SilkS")
		)
		(fp_line
			(start 1.905 -0.6858)
			(end 1.905 0.6858)
			(stroke
				(width 0.1524)
				(type default)
			)
			(layer "F.SilkS")
		)
		(fp_line
			(start 2.032 -0.7112)
			(end 2.032 0.7112)
			(stroke
				(width 0.1524)
				(type default)
			)
			(layer "F.SilkS")
		)
		(fp_line
			(start 2.032 0.7112)
			(end -1.651 0.7112)
			(stroke
				(width 0.1524)
				(type default)
			)
			(layer "F.SilkS")
		)
		(fp_line
			(start -1.35001 -0.225044)
			(end -0.899922 -0.225044)
			(stroke
				(width 0.1)
				(type default)
			)
			(layer "F.Fab")
		)
		(fp_line
			(start -1.35001 0.175006)
			(end -1.35001 -0.225044)
			(stroke
				(width 0.1)
				(type default)
			)
			(layer "F.Fab")
		)
		(fp_line
			(start -0.899922 -0.700024)
			(end 0.899922 -0.700024)
			(stroke
				(width 0.1)
				(type default)
			)
			(layer "F.Fab")
		)
		(fp_line
			(start -0.899922 -0.225044)
			(end -0.899922 -0.700024)
			(stroke
				(width 0.1)
				(type default)
			)
			(layer "F.Fab")
		)
		(fp_line
			(start -0.899922 0.175006)
			(end -1.35001 0.175006)
			(stroke
				(width 0.1)
				(type default)
			)
			(layer "F.Fab")
		)
		(fp_line
			(start -0.899922 0.700024)
			(end -0.899922 0.175006)
			(stroke
				(width 0.1)
				(type default)
			)
			(layer "F.Fab")
		)
		(fp_line
			(start -0.299974 -0.500126)
			(end -0.299974 0.500126)
			(stroke
				(width 0.1)
				(type default)
			)
			(layer "F.Fab")
		)
		(fp_line
			(start -0.299974 0.500126)
			(end 0.199898 0)
			(stroke
				(width 0.1)
				(type default)
			)
			(layer "F.Fab")
		)
		(fp_line
			(start 0.199898 0)
			(end -0.299974 -0.500126)
			(stroke
				(width 0.1)
				(type default)
			)
			(layer "F.Fab")
		)
		(fp_line
			(start 0.299974 -0.500126)
			(end 0.299974 0.500126)
			(stroke
				(width 0.1)
				(type default)
			)
			(layer "F.Fab")
		)
		(fp_line
			(start 0.899922 -0.700024)
			(end 0.899922 -0.225044)
			(stroke
				(width 0.1)
				(type default)
			)
			(layer "F.Fab")
		)
		(fp_line
			(start 0.899922 -0.225044)
			(end 1.35001 -0.225044)
			(stroke
				(width 0.1)
				(type default)
			)
			(layer "F.Fab")
		)
		(fp_line
			(start 0.899922 0.175006)
			(end 0.899922 0.700024)
			(stroke
				(width 0.1)
				(type default)
			)
			(layer "F.Fab")
		)
		(fp_line
			(start 0.899922 0.700024)
			(end -0.899922 0.700024)
			(stroke
				(width 0.1)
				(type default)
			)
			(layer "F.Fab")
		)
		(fp_line
			(start 1.35001 -0.225044)
			(end 1.35001 0.175006)
			(stroke
				(width 0.1)
				(type default)
			)
			(layer "F.Fab")
		)
		(fp_line
			(start 1.35001 0.175006)
			(end 0.899922 0.175006)
			(stroke
				(width 0.1)
				(type default)
			)
			(layer "F.Fab")
		)
		(fp_text user "+"
			(at -2.159 1.105662 0)
			(unlocked yes)
			(layer "F.SilkS")
			(effects
				(font
					(size 1.905 1.4224)
					(thickness 0.1524)
				)
				(justify left)
			)
		)
		(fp_text user "-"
			(at 0.889 0.978662 0)
			(unlocked yes)
			(layer "F.SilkS")
			(effects
				(font
					(size 1.905 1.4224)
					(thickness 0.1524)
				)
				(justify left)
			)
		)
		(fp_text user "+"
			(at -2.794 -0.19685 0)
			(unlocked yes)
			(layer "F.Fab")
			(effects
				(font
					(size 1.905 1.4224)
					(thickness 0.1524)
				)
				(justify left)
			)
		)
		(fp_text user "-"
			(at 1.8288 -0.24765 0)
			(unlocked yes)
			(layer "F.Fab")
			(effects
				(font
					(size 1.905 1.4224)
					(thickness 0.1524)
				)
				(justify left)
			)
		)
		(pad "1" smd rect
			(at -1.0922 0 180)
			(size 0.8128 0.8636)
			(layers "F.Cu" "F.Mask" "F.Paste")
			(net "FAN_2_TACH_OL_R")
		)
		(pad "2" smd rect
			(at 1.0922 0)
			(size 0.8128 0.8636)
			(layers "F.Cu" "F.Mask" "F.Paste")
			(net "FAN_2_TACH_OL_D")
		)
	)
	(footprint ""
		(layer "F.Cu")
		(at 5.461 -189.992)
		(property "Reference" "R312"
			(at 0 0 0)
			(layer "F.SilkS")
			(hide yes)
			(effects
				(font
					(size 1.27 1.27)
				)
			)
		)
		(property "Value" ""
			(at 0 0 0)
			(layer "F.Fab")
			(effects
				(font
					(size 1.27 1.27)
				)
			)
		)
		(duplicate_pad_numbers_are_jumpers no)
		(fp_line
			(start -0.7874 -0.4064)
			(end 0.7874 -0.4064)
			(stroke
				(width 0.1524)
				(type default)
			)
			(layer "F.SilkS")
		)
		(fp_line
			(start -0.7874 0.4064)
			(end -0.7874 -0.4064)
			(stroke
				(width 0.1524)
				(type default)
			)
			(layer "F.SilkS")
		)
		(fp_line
			(start 0.7874 -0.4064)
			(end 0.7874 0.4064)
			(stroke
				(width 0.1524)
				(type default)
			)
			(layer "F.SilkS")
		)
		(fp_line
			(start 0.7874 0.4064)
			(end -0.7874 0.4064)
			(stroke
				(width 0.1524)
				(type default)
			)
			(layer "F.SilkS")
		)
		(fp_line
			(start -0.67945 -0.305054)
			(end -0.12065 -0.305054)
			(stroke
				(width 0.1)
				(type default)
			)
			(layer "F.Fab")
		)
		(fp_line
			(start -0.67945 0.3048)
			(end -0.67945 -0.305054)
			(stroke
				(width 0.1)
				(type default)
			)
			(layer "F.Fab")
		)
		(fp_line
			(start -0.12065 -0.305054)
			(end -0.12065 -0.2794)
			(stroke
				(width 0.1)
				(type default)
			)
			(layer "F.Fab")
		)
		(fp_line
			(start -0.12065 -0.2794)
			(end 0.12065 -0.2794)
			(stroke
				(width 0.1)
				(type default)
			)
			(layer "F.Fab")
		)
		(fp_line
			(start -0.12065 0.2794)
			(end -0.12065 0.3048)
			(stroke
				(width 0.1)
				(type default)
			)
			(layer "F.Fab")
		)
		(fp_line
			(start -0.12065 0.3048)
			(end -0.67945 0.3048)
			(stroke
				(width 0.1)
				(type default)
			)
			(layer "F.Fab")
		)
		(fp_line
			(start 0.120396 0.2794)
			(end -0.12065 0.2794)
			(stroke
				(width 0.1)
				(type default)
			)
			(layer "F.Fab")
		)
		(fp_line
			(start 0.120396 0.3048)
			(end 0.120396 0.2794)
			(stroke
				(width 0.1)
				(type default)
			)
			(layer "F.Fab")
		)
		(fp_line
			(start 0.12065 -0.3048)
			(end 0.67945 -0.3048)
			(stroke
				(width 0.1)
				(type default)
			)
			(layer "F.Fab")
		)
		(fp_line
			(start 0.12065 -0.2794)
			(end 0.12065 -0.3048)
			(stroke
				(width 0.1)
				(type default)
			)
			(layer "F.Fab")
		)
		(fp_line
			(start 0.67945 -0.3048)
			(end 0.67945 0.3048)
			(stroke
				(width 0.1)
				(type default)
			)
			(layer "F.Fab")
		)
		(fp_line
			(start 0.67945 0.3048)
			(end 0.120396 0.3048)
			(stroke
				(width 0.1)
				(type default)
			)
			(layer "F.Fab")
		)
		(pad "1" smd circle
			(at -0.40005 0)
			(size 0 0)
			(layers "F.Cu" "F.Mask" "F.Paste")
			(net "P3V3_AUX")
		)
		(pad "2" smd circle
			(at 0.40005 0)
			(size 0 0)
			(layers "F.Cu" "F.Mask" "F.Paste")
			(net "FRU_ADDR0")
		)
	)
	(footprint ""
		(layer "F.Cu")
		(at 16.520922 -291.5031)
		(property "Reference" "C2057"
			(at 0 0 0)
			(layer "F.SilkS")
			(hide yes)
			(effects
				(font
					(size 1.27 1.27)
				)
			)
		)
		(property "Value" ""
			(at 0 0 0)
			(layer "F.Fab")
			(effects
				(font
					(size 1.27 1.27)
				)
			)
		)
		(duplicate_pad_numbers_are_jumpers no)
		(fp_line
			(start -0.7874 -0.4064)
			(end 0.7874 -0.4064)
			(stroke
				(width 0.1524)
				(type default)
			)
			(layer "F.SilkS")
		)
		(fp_line
			(start -0.7874 0.4064)
			(end -0.7874 -0.4064)
			(stroke
				(width 0.1524)
				(type default)
			)
			(layer "F.SilkS")
		)
		(fp_line
			(start 0.7874 -0.4064)
			(end 0.7874 0.4064)
			(stroke
				(width 0.1524)
				(type default)
			)
			(layer "F.SilkS")
		)
		(fp_line
			(start 0.7874 0.4064)
			(end -0.7874 0.4064)
			(stroke
				(width 0.1524)
				(type default)
			)
			(layer "F.SilkS")
		)
		(fp_line
			(start -0.67945 -0.305054)
			(end -0.12065 -0.305054)
			(stroke
				(width 0.1)
				(type default)
			)
			(layer "F.Fab")
		)
		(fp_line
			(start -0.67945 0.3048)
			(end -0.67945 -0.305054)
			(stroke
				(width 0.1)
				(type default)
			)
			(layer "F.Fab")
		)
		(fp_line
			(start -0.12065 -0.305054)
			(end -0.12065 -0.2794)
			(stroke
				(width 0.1)
				(type default)
			)
			(layer "F.Fab")
		)
		(fp_line
			(start -0.12065 -0.2794)
			(end 0.12065 -0.2794)
			(stroke
				(width 0.1)
				(type default)
			)
			(layer "F.Fab")
		)
		(fp_line
			(start -0.12065 0.2794)
			(end -0.12065 0.3048)
			(stroke
				(width 0.1)
				(type default)
			)
			(layer "F.Fab")
		)
		(fp_line
			(start -0.12065 0.3048)
			(end -0.67945 0.3048)
			(stroke
				(width 0.1)
				(type default)
			)
			(layer "F.Fab")
		)
		(fp_line
			(start 0.120396 0.2794)
			(end -0.12065 0.2794)
			(stroke
				(width 0.1)
				(type default)
			)
			(layer "F.Fab")
		)
		(fp_line
			(start 0.120396 0.3048)
			(end 0.120396 0.2794)
			(stroke
				(width 0.1)
				(type default)
			)
			(layer "F.Fab")
		)
		(fp_line
			(start 0.12065 -0.3048)
			(end 0.67945 -0.3048)
			(stroke
				(width 0.1)
				(type default)
			)
			(layer "F.Fab")
		)
		(fp_line
			(start 0.12065 -0.2794)
			(end 0.12065 -0.3048)
			(stroke
				(width 0.1)
				(type default)
			)
			(layer "F.Fab")
		)
		(fp_line
			(start 0.67945 -0.3048)
			(end 0.67945 0.3048)
			(stroke
				(width 0.1)
				(type default)
			)
			(layer "F.Fab")
		)
		(fp_line
			(start 0.67945 0.3048)
			(end 0.120396 0.3048)
			(stroke
				(width 0.1)
				(type default)
			)
			(layer "F.Fab")
		)
		(pad "1" smd circle
			(at -0.40005 0)
			(size 0 0)
			(layers "F.Cu" "F.Mask" "F.Paste")
			(net "FAN_7_PWM_IL_R")
		)
		(pad "2" smd circle
			(at 0.40005 0)
			(size 0 0)
			(layers "F.Cu" "F.Mask" "F.Paste")
			(net "GND")
		)
	)
	(footprint ""
		(layer "F.Cu")
		(at 36.83 -110.363 90)
		(property "Reference" "R5410"
			(at 0 0 90)
			(layer "F.SilkS")
			(hide yes)
			(effects
				(font
					(size 1.27 1.27)
				)
			)
		)
		(property "Value" ""
			(at 0 0 90)
			(layer "F.Fab")
			(effects
				(font
					(size 1.27 1.27)
				)
			)
		)
		(duplicate_pad_numbers_are_jumpers no)
		(fp_line
			(start 0.7874 -0.4064)
			(end 0.7874 0.4064)
			(stroke
				(width 0.1524)
				(type default)
			)
			(layer "F.SilkS")
		)
		(fp_line
			(start -0.7874 -0.4064)
			(end 0.7874 -0.4064)
			(stroke
				(width 0.1524)
				(type default)
			)
			(layer "F.SilkS")
		)
		(fp_line
			(start 0.7874 0.4064)
			(end -0.7874 0.4064)
			(stroke
				(width 0.1524)
				(type default)
			)
			(layer "F.SilkS")
		)
		(fp_line
			(start -0.7874 0.4064)
			(end -0.7874 -0.4064)
			(stroke
				(width 0.1524)
				(type default)
			)
			(layer "F.SilkS")
		)
		(fp_line
			(start -0.12065 -0.305054)
			(end -0.12065 -0.2794)
			(stroke
				(width 0.1)
				(type default)
			)
			(layer "F.Fab")
		)
		(fp_line
			(start -0.67945 -0.305054)
			(end -0.12065 -0.305054)
			(stroke
				(width 0.1)
				(type default)
			)
			(layer "F.Fab")
		)
		(fp_line
			(start 0.67945 -0.3048)
			(end 0.67945 0.3048)
			(stroke
				(width 0.1)
				(type default)
			)
			(layer "F.Fab")
		)
		(fp_line
			(start 0.12065 -0.3048)
			(end 0.67945 -0.3048)
			(stroke
				(width 0.1)
				(type default)
			)
			(layer "F.Fab")
		)
		(fp_line
			(start 0.12065 -0.2794)
			(end 0.12065 -0.3048)
			(stroke
				(width 0.1)
				(type default)
			)
			(layer "F.Fab")
		)
		(fp_line
			(start -0.12065 -0.2794)
			(end 0.12065 -0.2794)
			(stroke
				(width 0.1)
				(type default)
			)
			(layer "F.Fab")
		)
		(fp_line
			(start 0.120396 0.2794)
			(end -0.12065 0.2794)
			(stroke
				(width 0.1)
				(type default)
			)
			(layer "F.Fab")
		)
		(fp_line
			(start -0.12065 0.2794)
			(end -0.12065 0.3048)
			(stroke
				(width 0.1)
				(type default)
			)
			(layer "F.Fab")
		)
		(fp_line
			(start 0.67945 0.3048)
			(end 0.120396 0.3048)
			(stroke
				(width 0.1)
				(type default)
			)
			(layer "F.Fab")
		)
		(fp_line
			(start 0.120396 0.3048)
			(end 0.120396 0.2794)
			(stroke
				(width 0.1)
				(type default)
			)
			(layer "F.Fab")
		)
		(fp_line
			(start -0.12065 0.3048)
			(end -0.67945 0.3048)
			(stroke
				(width 0.1)
				(type default)
			)
			(layer "F.Fab")
		)
		(fp_line
			(start -0.67945 0.3048)
			(end -0.67945 -0.305054)
			(stroke
				(width 0.1)
				(type default)
			)
			(layer "F.Fab")
		)
		(pad "1" smd rect
			(at -0.40005 0 270)
			(size 0.4572 0.508)
			(layers "F.Cu" "F.Mask" "F.Paste")
			(net "FAN_2_FAIL_LED_R_N")
		)
		(pad "2" smd rect
			(at 0.40005 0 270)
			(size 0.4572 0.508)
			(layers "F.Cu" "F.Mask" "F.Paste")
			(net "FAN_2_FAIL_R_LED_N")
		)
	)
	(footprint ""
		(layer "F.Cu")
		(at 32.893 -207.01)
		(property "Reference" "D274"
			(at -1.397 1.29667 0)
			(unlocked yes)
			(layer "F.SilkS")
			(effects
				(font
					(size 0.7874 0.5842)
					(thickness 0.1524)
				)
				(justify left)
			)
		)
		(property "Value" ""
			(at 0 0 0)
			(layer "F.Fab")
			(effects
				(font
					(size 1.27 1.27)
				)
			)
		)
		(duplicate_pad_numbers_are_jumpers no)
		(fp_line
			(start -0.854964 -0.450088)
			(end -0.854964 0.450088)
			(stroke
				(width 0.1524)
				(type default)
			)
			(layer "F.SilkS")
		)
		(fp_line
			(start -0.854964 0.450088)
			(end 0.925068 0.450088)
			(stroke
				(width 0.1524)
				(type default)
			)
			(layer "F.SilkS")
		)
		(fp_line
			(start 0.845058 0.4064)
			(end 0.845058 -0.381)
			(stroke
				(width 0.1524)
				(type default)
			)
			(layer "F.SilkS")
		)
		(fp_line
			(start 0.870458 -0.2794)
			(end 0.845058 0.4064)
			(stroke
				(width 0.1524)
				(type default)
			)
			(layer "F.SilkS")
		)
		(fp_line
			(start 0.94488 -0.450088)
			(end -0.854964 -0.450088)
			(stroke
				(width 0.1524)
				(type default)
			)
			(layer "F.SilkS")
		)
		(fp_line
			(start 0.94488 0.450088)
			(end 0.94488 -0.450088)
			(stroke
				(width 0.1524)
				(type default)
			)
			(layer "F.SilkS")
		)
		(fp_line
			(start -0.54991 -0.350012)
			(end -0.54991 0.350012)
			(stroke
				(width 0.1)
				(type default)
			)
			(layer "F.Fab")
		)
		(fp_line
			(start -0.54991 0.350012)
			(end 0.54991 0.350012)
			(stroke
				(width 0.1)
				(type default)
			)
			(layer "F.Fab")
		)
		(fp_line
			(start 0.54991 -0.350012)
			(end -0.54991 -0.350012)
			(stroke
				(width 0.1)
				(type default)
			)
			(layer "F.Fab")
		)
		(fp_line
			(start 0.54991 0.350012)
			(end 0.54991 -0.350012)
			(stroke
				(width 0.1)
				(type default)
			)
			(layer "F.Fab")
		)
		(fp_text user "+"
			(at -1.016 0.22225 180)
			(unlocked yes)
			(layer "F.SilkS")
			(effects
				(font
					(size 1.905 1.4224)
					(thickness 0.1524)
				)
				(justify left)
			)
		)
		(fp_text user "-"
			(at 1.651 -0.43815 180)
			(unlocked yes)
			(layer "F.SilkS")
			(effects
				(font
					(size 1.905 1.4224)
					(thickness 0.1524)
				)
				(justify left)
			)
		)
		(fp_text user "+"
			(at -0.808228 0.239014 180)
			(unlocked yes)
			(layer "F.Fab")
			(effects
				(font
					(size 1.905 1.4224)
					(thickness 0.1524)
				)
				(justify left)
			)
		)
		(fp_text user "-"
			(at 2.48539 0.239014 180)
			(unlocked yes)
			(layer "F.Fab")
			(effects
				(font
					(size 1.905 1.4224)
					(thickness 0.1524)
				)
				(justify left)
			)
		)
		(pad "A" smd rect
			(at -0.424942 0)
			(size 0.5588 0.6096)
			(layers "F.Cu" "F.Mask" "F.Paste")
			(net "GND")
		)
		(pad "C" smd rect
			(at 0.424942 0 180)
			(size 0.5588 0.6096)
			(layers "F.Cu" "F.Mask" "F.Paste")
			(net "FAN_1_PWM_IL_R")
		)
	)
	(footprint ""
		(layer "F.Cu")
		(at 13.335 -162.814 180)
		(property "Reference" "R5507"
			(at 0 0 180)
			(layer "F.SilkS")
			(hide yes)
			(effects
				(font
					(size 1.27 1.27)
				)
			)
		)
		(property "Value" ""
			(at 0 0 180)
			(layer "F.Fab")
			(effects
				(font
					(size 1.27 1.27)
				)
			)
		)
		(duplicate_pad_numbers_are_jumpers no)
		(fp_line
			(start 0.7874 0.4064)
			(end -0.7874 0.4064)
			(stroke
				(width 0.1524)
				(type default)
			)
			(layer "F.SilkS")
		)
		(fp_line
			(start 0.7874 -0.4064)
			(end 0.7874 0.4064)
			(stroke
				(width 0.1524)
				(type default)
			)
			(layer "F.SilkS")
		)
		(fp_line
			(start -0.7874 0.4064)
			(end -0.7874 -0.4064)
			(stroke
				(width 0.1524)
				(type default)
			)
			(layer "F.SilkS")
		)
		(fp_line
			(start -0.7874 -0.4064)
			(end 0.7874 -0.4064)
			(stroke
				(width 0.1524)
				(type default)
			)
			(layer "F.SilkS")
		)
		(fp_line
			(start 0.67945 0.3048)
			(end 0.120396 0.3048)
			(stroke
				(width 0.1)
				(type default)
			)
			(layer "F.Fab")
		)
		(fp_line
			(start 0.67945 -0.3048)
			(end 0.67945 0.3048)
			(stroke
				(width 0.1)
				(type default)
			)
			(layer "F.Fab")
		)
		(fp_line
			(start 0.12065 -0.2794)
			(end 0.12065 -0.3048)
			(stroke
				(width 0.1)
				(type default)
			)
			(layer "F.Fab")
		)
		(fp_line
			(start 0.12065 -0.3048)
			(end 0.67945 -0.3048)
			(stroke
				(width 0.1)
				(type default)
			)
			(layer "F.Fab")
		)
		(fp_line
			(start 0.120396 0.3048)
			(end 0.120396 0.2794)
			(stroke
				(width 0.1)
				(type default)
			)
			(layer "F.Fab")
		)
		(fp_line
			(start 0.120396 0.2794)
			(end -0.12065 0.2794)
			(stroke
				(width 0.1)
				(type default)
			)
			(layer "F.Fab")
		)
		(fp_line
			(start -0.12065 0.3048)
			(end -0.67945 0.3048)
			(stroke
				(width 0.1)
				(type default)
			)
			(layer "F.Fab")
		)
		(fp_line
			(start -0.12065 0.2794)
			(end -0.12065 0.3048)
			(stroke
				(width 0.1)
				(type default)
			)
			(layer "F.Fab")
		)
		(fp_line
			(start -0.12065 -0.2794)
			(end 0.12065 -0.2794)
			(stroke
				(width 0.1)
				(type default)
			)
			(layer "F.Fab")
		)
		(fp_line
			(start -0.12065 -0.305054)
			(end -0.12065 -0.2794)
			(stroke
				(width 0.1)
				(type default)
			)
			(layer "F.Fab")
		)
		(fp_line
			(start -0.67945 0.3048)
			(end -0.67945 -0.305054)
			(stroke
				(width 0.1)
				(type default)
			)
			(layer "F.Fab")
		)
		(fp_line
			(start -0.67945 -0.305054)
			(end -0.12065 -0.305054)
			(stroke
				(width 0.1)
				(type default)
			)
			(layer "F.Fab")
		)
		(pad "1" smd circle
			(at -0.40005 0 180)
			(size 0 0)
			(layers "F.Cu" "F.Mask" "F.Paste")
			(net "P3V3_AUX")
		)
		(pad "2" smd circle
			(at 0.40005 0 180)
			(size 0 0)
			(layers "F.Cu" "F.Mask" "F.Paste")
			(net "FAN_0_PRESENT_N")
		)
	)
	(footprint ""
		(layer "F.Cu")
		(at 37.846 -136.398 180)
		(property "Reference" "R5598"
			(at 0 0 180)
			(layer "F.SilkS")
			(hide yes)
			(effects
				(font
					(size 1.27 1.27)
				)
			)
		)
		(property "Value" ""
			(at 0 0 180)
			(layer "F.Fab")
			(effects
				(font
					(size 1.27 1.27)
				)
			)
		)
		(duplicate_pad_numbers_are_jumpers no)
		(fp_line
			(start 0.7874 0.4064)
			(end -0.7874 0.4064)
			(stroke
				(width 0.1524)
				(type default)
			)
			(layer "F.SilkS")
		)
		(fp_line
			(start 0.7874 -0.4064)
			(end 0.7874 0.4064)
			(stroke
				(width 0.1524)
				(type default)
			)
			(layer "F.SilkS")
		)
		(fp_line
			(start -0.7874 0.4064)
			(end -0.7874 -0.4064)
			(stroke
				(width 0.1524)
				(type default)
			)
			(layer "F.SilkS")
		)
		(fp_line
			(start -0.7874 -0.4064)
			(end 0.7874 -0.4064)
			(stroke
				(width 0.1524)
				(type default)
			)
			(layer "F.SilkS")
		)
		(fp_line
			(start 0.67945 0.3048)
			(end 0.120396 0.3048)
			(stroke
				(width 0.1)
				(type default)
			)
			(layer "F.Fab")
		)
		(fp_line
			(start 0.67945 -0.3048)
			(end 0.67945 0.3048)
			(stroke
				(width 0.1)
				(type default)
			)
			(layer "F.Fab")
		)
		(fp_line
			(start 0.12065 -0.2794)
			(end 0.12065 -0.3048)
			(stroke
				(width 0.1)
				(type default)
			)
			(layer "F.Fab")
		)
		(fp_line
			(start 0.12065 -0.3048)
			(end 0.67945 -0.3048)
			(stroke
				(width 0.1)
				(type default)
			)
			(layer "F.Fab")
		)
		(fp_line
			(start 0.120396 0.3048)
			(end 0.120396 0.2794)
			(stroke
				(width 0.1)
				(type default)
			)
			(layer "F.Fab")
		)
		(fp_line
			(start 0.120396 0.2794)
			(end -0.12065 0.2794)
			(stroke
				(width 0.1)
				(type default)
			)
			(layer "F.Fab")
		)
		(fp_line
			(start -0.12065 0.3048)
			(end -0.67945 0.3048)
			(stroke
				(width 0.1)
				(type default)
			)
			(layer "F.Fab")
		)
		(fp_line
			(start -0.12065 0.2794)
			(end -0.12065 0.3048)
			(stroke
				(width 0.1)
				(type default)
			)
			(layer "F.Fab")
		)
		(fp_line
			(start -0.12065 -0.2794)
			(end 0.12065 -0.2794)
			(stroke
				(width 0.1)
				(type default)
			)
			(layer "F.Fab")
		)
		(fp_line
			(start -0.12065 -0.305054)
			(end -0.12065 -0.2794)
			(stroke
				(width 0.1)
				(type default)
			)
			(layer "F.Fab")
		)
		(fp_line
			(start -0.67945 0.3048)
			(end -0.67945 -0.305054)
			(stroke
				(width 0.1)
				(type default)
			)
			(layer "F.Fab")
		)
		(fp_line
			(start -0.67945 -0.305054)
			(end -0.12065 -0.305054)
			(stroke
				(width 0.1)
				(type default)
			)
			(layer "F.Fab")
		)
		(pad "1" smd rect
			(at -0.40005 0)
			(size 0.4572 0.508)
			(layers "F.Cu" "F.Mask" "F.Paste")
			(net "FAN_0_TACH_IL")
		)
		(pad "2" smd rect
			(at 0.40005 0)
			(size 0.4572 0.508)
			(layers "F.Cu" "F.Mask" "F.Paste")
			(net "FAN_0_TACH_IL_R1")
		)
	)
	(footprint ""
		(layer "F.Cu")
		(at 34.417 -143.891 -90)
		(property "Reference" "R4792"
			(at 0 0 270)
			(layer "F.SilkS")
			(hide yes)
			(effects
				(font
					(size 1.27 1.27)
				)
			)
		)
		(property "Value" ""
			(at 0 0 270)
			(layer "F.Fab")
			(effects
				(font
					(size 1.27 1.27)
				)
			)
		)
		(duplicate_pad_numbers_are_jumpers no)
		(fp_line
			(start -0.7874 0.4064)
			(end -0.7874 -0.4064)
			(stroke
				(width 0.1524)
				(type default)
			)
			(layer "F.SilkS")
		)
		(fp_line
			(start 0.7874 0.4064)
			(end -0.7874 0.4064)
			(stroke
				(width 0.1524)
				(type default)
			)
			(layer "F.SilkS")
		)
		(fp_line
			(start -0.7874 -0.4064)
			(end 0.7874 -0.4064)
			(stroke
				(width 0.1524)
				(type default)
			)
			(layer "F.SilkS")
		)
		(fp_line
			(start 0.7874 -0.4064)
			(end 0.7874 0.4064)
			(stroke
				(width 0.1524)
				(type default)
			)
			(layer "F.SilkS")
		)
		(fp_line
			(start -0.67945 0.3048)
			(end -0.67945 -0.305054)
			(stroke
				(width 0.1)
				(type default)
			)
			(layer "F.Fab")
		)
		(fp_line
			(start -0.12065 0.3048)
			(end -0.67945 0.3048)
			(stroke
				(width 0.1)
				(type default)
			)
			(layer "F.Fab")
		)
		(fp_line
			(start 0.120396 0.3048)
			(end 0.120396 0.2794)
			(stroke
				(width 0.1)
				(type default)
			)
			(layer "F.Fab")
		)
		(fp_line
			(start 0.67945 0.3048)
			(end 0.120396 0.3048)
			(stroke
				(width 0.1)
				(type default)
			)
			(layer "F.Fab")
		)
		(fp_line
			(start -0.12065 0.2794)
			(end -0.12065 0.3048)
			(stroke
				(width 0.1)
				(type default)
			)
			(layer "F.Fab")
		)
		(fp_line
			(start 0.120396 0.2794)
			(end -0.12065 0.2794)
			(stroke
				(width 0.1)
				(type default)
			)
			(layer "F.Fab")
		)
		(fp_line
			(start -0.12065 -0.2794)
			(end 0.12065 -0.2794)
			(stroke
				(width 0.1)
				(type default)
			)
			(layer "F.Fab")
		)
		(fp_line
			(start 0.12065 -0.2794)
			(end 0.12065 -0.3048)
			(stroke
				(width 0.1)
				(type default)
			)
			(layer "F.Fab")
		)
		(fp_line
			(start 0.12065 -0.3048)
			(end 0.67945 -0.3048)
			(stroke
				(width 0.1)
				(type default)
			)
			(layer "F.Fab")
		)
		(fp_line
			(start 0.67945 -0.3048)
			(end 0.67945 0.3048)
			(stroke
				(width 0.1)
				(type default)
			)
			(layer "F.Fab")
		)
		(fp_line
			(start -0.67945 -0.305054)
			(end -0.12065 -0.305054)
			(stroke
				(width 0.1)
				(type default)
			)
			(layer "F.Fab")
		)
		(fp_line
			(start -0.12065 -0.305054)
			(end -0.12065 -0.2794)
			(stroke
				(width 0.1)
				(type default)
			)
			(layer "F.Fab")
		)
		(pad "1" smd circle
			(at -0.40005 0 270)
			(size 0 0)
			(layers "F.Cu" "F.Mask" "F.Paste")
			(net "SMB_FAN3_R_SCL")
		)
		(pad "2" smd circle
			(at 0.40005 0 270)
			(size 0 0)
			(layers "F.Cu" "F.Mask" "F.Paste")
			(net "SMB_FAN3_SCL")
		)
	)
	(footprint ""
		(layer "F.Cu")
		(at 37.846 -124.968 180)
		(property "Reference" "R5607"
			(at 0 0 180)
			(layer "F.SilkS")
			(hide yes)
			(effects
				(font
					(size 1.27 1.27)
				)
			)
		)
		(property "Value" ""
			(at 0 0 180)
			(layer "F.Fab")
			(effects
				(font
					(size 1.27 1.27)
				)
			)
		)
		(duplicate_pad_numbers_are_jumpers no)
		(fp_line
			(start 0.7874 0.4064)
			(end -0.7874 0.4064)
			(stroke
				(width 0.1524)
				(type default)
			)
			(layer "F.SilkS")
		)
		(fp_line
			(start 0.7874 -0.4064)
			(end 0.7874 0.4064)
			(stroke
				(width 0.1524)
				(type default)
			)
			(layer "F.SilkS")
		)
		(fp_line
			(start -0.7874 0.4064)
			(end -0.7874 -0.4064)
			(stroke
				(width 0.1524)
				(type default)
			)
			(layer "F.SilkS")
		)
		(fp_line
			(start -0.7874 -0.4064)
			(end 0.7874 -0.4064)
			(stroke
				(width 0.1524)
				(type default)
			)
			(layer "F.SilkS")
		)
		(fp_line
			(start 0.67945 0.3048)
			(end 0.120396 0.3048)
			(stroke
				(width 0.1)
				(type default)
			)
			(layer "F.Fab")
		)
		(fp_line
			(start 0.67945 -0.3048)
			(end 0.67945 0.3048)
			(stroke
				(width 0.1)
				(type default)
			)
			(layer "F.Fab")
		)
		(fp_line
			(start 0.12065 -0.2794)
			(end 0.12065 -0.3048)
			(stroke
				(width 0.1)
				(type default)
			)
			(layer "F.Fab")
		)
		(fp_line
			(start 0.12065 -0.3048)
			(end 0.67945 -0.3048)
			(stroke
				(width 0.1)
				(type default)
			)
			(layer "F.Fab")
		)
		(fp_line
			(start 0.120396 0.3048)
			(end 0.120396 0.2794)
			(stroke
				(width 0.1)
				(type default)
			)
			(layer "F.Fab")
		)
		(fp_line
			(start 0.120396 0.2794)
			(end -0.12065 0.2794)
			(stroke
				(width 0.1)
				(type default)
			)
			(layer "F.Fab")
		)
		(fp_line
			(start -0.12065 0.3048)
			(end -0.67945 0.3048)
			(stroke
				(width 0.1)
				(type default)
			)
			(layer "F.Fab")
		)
		(fp_line
			(start -0.12065 0.2794)
			(end -0.12065 0.3048)
			(stroke
				(width 0.1)
				(type default)
			)
			(layer "F.Fab")
		)
		(fp_line
			(start -0.12065 -0.2794)
			(end 0.12065 -0.2794)
			(stroke
				(width 0.1)
				(type default)
			)
			(layer "F.Fab")
		)
		(fp_line
			(start -0.12065 -0.305054)
			(end -0.12065 -0.2794)
			(stroke
				(width 0.1)
				(type default)
			)
			(layer "F.Fab")
		)
		(fp_line
			(start -0.67945 0.3048)
			(end -0.67945 -0.305054)
			(stroke
				(width 0.1)
				(type default)
			)
			(layer "F.Fab")
		)
		(fp_line
			(start -0.67945 -0.305054)
			(end -0.12065 -0.305054)
			(stroke
				(width 0.1)
				(type default)
			)
			(layer "F.Fab")
		)
		(pad "1" smd rect
			(at -0.40005 0)
			(size 0.4572 0.508)
			(layers "F.Cu" "F.Mask" "F.Paste")
			(net "FAN_3_PWM")
		)
		(pad "2" smd rect
			(at 0.40005 0)
			(size 0.4572 0.508)
			(layers "F.Cu" "F.Mask" "F.Paste")
			(net "FAN_3_PWM_R1")
		)
	)
	(footprint ""
		(layer "F.Cu")
		(at 22.479 -206.248 90)
		(property "Reference" "R344"
			(at 0 0 90)
			(layer "F.SilkS")
			(hide yes)
			(effects
				(font
					(size 1.27 1.27)
				)
			)
		)
		(property "Value" ""
			(at 0 0 90)
			(layer "F.Fab")
			(effects
				(font
					(size 1.27 1.27)
				)
			)
		)
		(duplicate_pad_numbers_are_jumpers no)
		(fp_line
			(start 0.7874 -0.4064)
			(end 0.7874 0.4064)
			(stroke
				(width 0.1524)
				(type default)
			)
			(layer "F.SilkS")
		)
		(fp_line
			(start -0.7874 -0.4064)
			(end 0.7874 -0.4064)
			(stroke
				(width 0.1524)
				(type default)
			)
			(layer "F.SilkS")
		)
		(fp_line
			(start 0.7874 0.4064)
			(end -0.7874 0.4064)
			(stroke
				(width 0.1524)
				(type default)
			)
			(layer "F.SilkS")
		)
		(fp_line
			(start -0.7874 0.4064)
			(end -0.7874 -0.4064)
			(stroke
				(width 0.1524)
				(type default)
			)
			(layer "F.SilkS")
		)
		(fp_line
			(start -0.12065 -0.305054)
			(end -0.12065 -0.2794)
			(stroke
				(width 0.1)
				(type default)
			)
			(layer "F.Fab")
		)
		(fp_line
			(start -0.67945 -0.305054)
			(end -0.12065 -0.305054)
			(stroke
				(width 0.1)
				(type default)
			)
			(layer "F.Fab")
		)
		(fp_line
			(start 0.67945 -0.3048)
			(end 0.67945 0.3048)
			(stroke
				(width 0.1)
				(type default)
			)
			(layer "F.Fab")
		)
		(fp_line
			(start 0.12065 -0.3048)
			(end 0.67945 -0.3048)
			(stroke
				(width 0.1)
				(type default)
			)
			(layer "F.Fab")
		)
		(fp_line
			(start 0.12065 -0.2794)
			(end 0.12065 -0.3048)
			(stroke
				(width 0.1)
				(type default)
			)
			(layer "F.Fab")
		)
		(fp_line
			(start -0.12065 -0.2794)
			(end 0.12065 -0.2794)
			(stroke
				(width 0.1)
				(type default)
			)
			(layer "F.Fab")
		)
		(fp_line
			(start 0.120396 0.2794)
			(end -0.12065 0.2794)
			(stroke
				(width 0.1)
				(type default)
			)
			(layer "F.Fab")
		)
		(fp_line
			(start -0.12065 0.2794)
			(end -0.12065 0.3048)
			(stroke
				(width 0.1)
				(type default)
			)
			(layer "F.Fab")
		)
		(fp_line
			(start 0.67945 0.3048)
			(end 0.120396 0.3048)
			(stroke
				(width 0.1)
				(type default)
			)
			(layer "F.Fab")
		)
		(fp_line
			(start 0.120396 0.3048)
			(end 0.120396 0.2794)
			(stroke
				(width 0.1)
				(type default)
			)
			(layer "F.Fab")
		)
		(fp_line
			(start -0.12065 0.3048)
			(end -0.67945 0.3048)
			(stroke
				(width 0.1)
				(type default)
			)
			(layer "F.Fab")
		)
		(fp_line
			(start -0.67945 0.3048)
			(end -0.67945 -0.305054)
			(stroke
				(width 0.1)
				(type default)
			)
			(layer "F.Fab")
		)
		(pad "1" smd circle
			(at -0.40005 0 90)
			(size 0 0)
			(layers "F.Cu" "F.Mask" "F.Paste")
			(net "P3V3_AUX")
		)
		(pad "2" smd circle
			(at 0.40005 0 90)
			(size 0 0)
			(layers "F.Cu" "F.Mask" "F.Paste")
			(net "FAN_1_PWM")
		)
	)
	(footprint ""
		(layer "F.Cu")
		(at 32.512 -117.094)
		(property "Reference" "R5328"
			(at 0 0 0)
			(layer "F.SilkS")
			(hide yes)
			(effects
				(font
					(size 1.27 1.27)
				)
			)
		)
		(property "Value" ""
			(at 0 0 0)
			(layer "F.Fab")
			(effects
				(font
					(size 1.27 1.27)
				)
			)
		)
		(duplicate_pad_numbers_are_jumpers no)
		(fp_line
			(start -1.2954 -0.5842)
			(end 1.2954 -0.5842)
			(stroke
				(width 0.1524)
				(type default)
			)
			(layer "F.SilkS")
		)
		(fp_line
			(start -1.2954 0.5842)
			(end -1.2954 -0.5842)
			(stroke
				(width 0.1524)
				(type default)
			)
			(layer "F.SilkS")
		)
		(fp_line
			(start 1.2954 -0.5842)
			(end 1.2954 0.5842)
			(stroke
				(width 0.1524)
				(type default)
			)
			(layer "F.SilkS")
		)
		(fp_line
			(start 1.2954 0.5842)
			(end -1.2954 0.5842)
			(stroke
				(width 0.1524)
				(type default)
			)
			(layer "F.SilkS")
		)
		(fp_line
			(start -1.1938 -0.406654)
			(end -0.8636 -0.406654)
			(stroke
				(width 0.1)
				(type default)
			)
			(layer "F.Fab")
		)
		(fp_line
			(start -1.1938 0.4064)
			(end -1.1938 -0.406654)
			(stroke
				(width 0.1)
				(type default)
			)
			(layer "F.Fab")
		)
		(fp_line
			(start -0.8636 -0.4572)
			(end 0.8636 -0.4572)
			(stroke
				(width 0.1)
				(type default)
			)
			(layer "F.Fab")
		)
		(fp_line
			(start -0.8636 -0.406654)
			(end -0.8636 -0.4572)
			(stroke
				(width 0.1)
				(type default)
			)
			(layer "F.Fab")
		)
		(fp_line
			(start -0.8636 0.4064)
			(end -1.1938 0.4064)
			(stroke
				(width 0.1)
				(type default)
			)
			(layer "F.Fab")
		)
		(fp_line
			(start -0.8636 0.4318)
			(end -0.8636 0.4064)
			(stroke
				(width 0.1)
				(type default)
			)
			(layer "F.Fab")
		)
		(fp_line
			(start -0.8636 0.4572)
			(end -0.8636 0.4318)
			(stroke
				(width 0.1)
				(type default)
			)
			(layer "F.Fab")
		)
		(fp_line
			(start 0.8636 -0.4572)
			(end 0.8636 -0.406654)
			(stroke
				(width 0.1)
				(type default)
			)
			(layer "F.Fab")
		)
		(fp_line
			(start 0.8636 -0.406654)
			(end 1.1938 -0.406654)
			(stroke
				(width 0.1)
				(type default)
			)
			(layer "F.Fab")
		)
		(fp_line
			(start 0.8636 0.4064)
			(end 0.8636 0.4572)
			(stroke
				(width 0.1)
				(type default)
			)
			(layer "F.Fab")
		)
		(fp_line
			(start 0.8636 0.4572)
			(end -0.8636 0.4572)
			(stroke
				(width 0.1)
				(type default)
			)
			(layer "F.Fab")
		)
		(fp_line
			(start 1.1938 -0.406654)
			(end 1.1938 0.4064)
			(stroke
				(width 0.1)
				(type default)
			)
			(layer "F.Fab")
		)
		(fp_line
			(start 1.1938 0.4064)
			(end 0.8636 0.4064)
			(stroke
				(width 0.1)
				(type default)
			)
			(layer "F.Fab")
		)
		(pad "1" smd rect
			(at -0.7366 0 270)
			(size 0.7112 0.8128)
			(layers "F.Cu" "F.Mask" "F.Paste")
			(net "P52V_FAN_2")
		)
		(pad "2" smd rect
			(at 0.7366 0 270)
			(size 0.7112 0.8128)
			(layers "F.Cu" "F.Mask" "F.Paste")
			(net "FAN_2_TACH_IL_R")
		)
	)
	(footprint ""
		(layer "F.Cu")
		(at 39.878 -98.806)
		(property "Reference" "U407"
			(at -1.2446 -1.72593 0)
			(unlocked yes)
			(layer "F.SilkS")
			(effects
				(font
					(size 0.7874 0.5842)
					(thickness 0.1524)
				)
				(justify left)
			)
		)
		(property "Value" ""
			(at 0 0 0)
			(layer "F.Fab")
			(effects
				(font
					(size 1.27 1.27)
				)
			)
		)
		(duplicate_pad_numbers_are_jumpers no)
		(fp_line
			(start -1.335278 -1.100074)
			(end -1.335278 1.100074)
			(stroke
				(width 0.1524)
				(type default)
			)
			(layer "F.SilkS")
		)
		(fp_line
			(start -1.335278 1.100074)
			(end 1.335278 1.100074)
			(stroke
				(width 0.1524)
				(type default)
			)
			(layer "F.SilkS")
		)
		(fp_line
			(start 1.335278 -1.100074)
			(end -1.335278 -1.100074)
			(stroke
				(width 0.1524)
				(type default)
			)
			(layer "F.SilkS")
		)
		(fp_line
			(start 1.335278 1.100074)
			(end 1.335278 -1.100074)
			(stroke
				(width 0.1524)
				(type default)
			)
			(layer "F.SilkS")
		)
		(fp_line
			(start -0.674878 -1.100074)
			(end -0.674878 1.100074)
			(stroke
				(width 0.1)
				(type default)
			)
			(layer "F.Fab")
		)
		(fp_line
			(start -0.674878 1.100074)
			(end 0.674878 1.100074)
			(stroke
				(width 0.1)
				(type default)
			)
			(layer "F.Fab")
		)
		(fp_line
			(start 0.674878 -1.100074)
			(end -0.674878 -1.100074)
			(stroke
				(width 0.1)
				(type default)
			)
			(layer "F.Fab")
		)
		(fp_line
			(start 0.674878 1.100074)
			(end 0.674878 -1.100074)
			(stroke
				(width 0.1)
				(type default)
			)
			(layer "F.Fab")
		)
		(pad "D" smd rect
			(at 0.8001 0 270)
			(size 0.6096 0.8128)
			(layers "F.Cu" "F.Mask" "F.Paste")
			(net "U407_D1")
		)
		(pad "G" smd rect
			(at -0.8001 -0.649986 270)
			(size 0.6096 0.8128)
			(layers "F.Cu" "F.Mask" "F.Paste")
			(net "FAN_2_PRESENT")
		)
		(pad "S" smd rect
			(at -0.8001 0.649986 270)
			(size 0.6096 0.8128)
			(layers "F.Cu" "F.Mask" "F.Paste")
			(net "GND")
		)
	)
	(footprint ""
		(layer "F.Cu")
		(at 37.338 -113.595912)
		(property "Reference" "R5222"
			(at 0 0 0)
			(layer "F.SilkS")
			(hide yes)
			(effects
				(font
					(size 1.27 1.27)
				)
			)
		)
		(property "Value" ""
			(at 0 0 0)
			(layer "F.Fab")
			(effects
				(font
					(size 1.27 1.27)
				)
			)
		)
		(duplicate_pad_numbers_are_jumpers no)
		(fp_line
			(start -0.7874 -0.4064)
			(end 0.7874 -0.4064)
			(stroke
				(width 0.1524)
				(type default)
			)
			(layer "F.SilkS")
		)
		(fp_line
			(start -0.7874 0.4064)
			(end -0.7874 -0.4064)
			(stroke
				(width 0.1524)
				(type default)
			)
			(layer "F.SilkS")
		)
		(fp_line
			(start 0.7874 -0.4064)
			(end 0.7874 0.4064)
			(stroke
				(width 0.1524)
				(type default)
			)
			(layer "F.SilkS")
		)
		(fp_line
			(start 0.7874 0.4064)
			(end -0.7874 0.4064)
			(stroke
				(width 0.1524)
				(type default)
			)
			(layer "F.SilkS")
		)
		(fp_line
			(start -0.67945 -0.305054)
			(end -0.12065 -0.305054)
			(stroke
				(width 0.1)
				(type default)
			)
			(layer "F.Fab")
		)
		(fp_line
			(start -0.67945 0.3048)
			(end -0.67945 -0.305054)
			(stroke
				(width 0.1)
				(type default)
			)
			(layer "F.Fab")
		)
		(fp_line
			(start -0.12065 -0.305054)
			(end -0.12065 -0.2794)
			(stroke
				(width 0.1)
				(type default)
			)
			(layer "F.Fab")
		)
		(fp_line
			(start -0.12065 -0.2794)
			(end 0.12065 -0.2794)
			(stroke
				(width 0.1)
				(type default)
			)
			(layer "F.Fab")
		)
		(fp_line
			(start -0.12065 0.2794)
			(end -0.12065 0.3048)
			(stroke
				(width 0.1)
				(type default)
			)
			(layer "F.Fab")
		)
		(fp_line
			(start -0.12065 0.3048)
			(end -0.67945 0.3048)
			(stroke
				(width 0.1)
				(type default)
			)
			(layer "F.Fab")
		)
		(fp_line
			(start 0.120396 0.2794)
			(end -0.12065 0.2794)
			(stroke
				(width 0.1)
				(type default)
			)
			(layer "F.Fab")
		)
		(fp_line
			(start 0.120396 0.3048)
			(end 0.120396 0.2794)
			(stroke
				(width 0.1)
				(type default)
			)
			(layer "F.Fab")
		)
		(fp_line
			(start 0.12065 -0.3048)
			(end 0.67945 -0.3048)
			(stroke
				(width 0.1)
				(type default)
			)
			(layer "F.Fab")
		)
		(fp_line
			(start 0.12065 -0.2794)
			(end 0.12065 -0.3048)
			(stroke
				(width 0.1)
				(type default)
			)
			(layer "F.Fab")
		)
		(fp_line
			(start 0.67945 -0.3048)
			(end 0.67945 0.3048)
			(stroke
				(width 0.1)
				(type default)
			)
			(layer "F.Fab")
		)
		(fp_line
			(start 0.67945 0.3048)
			(end 0.120396 0.3048)
			(stroke
				(width 0.1)
				(type default)
			)
			(layer "F.Fab")
		)
		(pad "1" smd circle
			(at -0.40005 0)
			(size 0 0)
			(layers "F.Cu" "F.Mask" "F.Paste")
			(net "SMB_FAN2_SCL")
		)
		(pad "2" smd circle
			(at 0.40005 0)
			(size 0 0)
			(layers "F.Cu" "F.Mask" "F.Paste")
			(net "SMB_FAN2_SCL_R")
		)
	)
	(footprint ""
		(layer "F.Cu")
		(at 11.572494 -255.143 180)
		(property "Reference" "R5425"
			(at 0 0 180)
			(layer "F.SilkS")
			(hide yes)
			(effects
				(font
					(size 1.27 1.27)
				)
			)
		)
		(property "Value" ""
			(at 0 0 180)
			(layer "F.Fab")
			(effects
				(font
					(size 1.27 1.27)
				)
			)
		)
		(duplicate_pad_numbers_are_jumpers no)
		(fp_line
			(start 0.7874 0.4064)
			(end -0.7874 0.4064)
			(stroke
				(width 0.1524)
				(type default)
			)
			(layer "F.SilkS")
		)
		(fp_line
			(start 0.7874 -0.4064)
			(end 0.7874 0.4064)
			(stroke
				(width 0.1524)
				(type default)
			)
			(layer "F.SilkS")
		)
		(fp_line
			(start -0.7874 0.4064)
			(end -0.7874 -0.4064)
			(stroke
				(width 0.1524)
				(type default)
			)
			(layer "F.SilkS")
		)
		(fp_line
			(start -0.7874 -0.4064)
			(end 0.7874 -0.4064)
			(stroke
				(width 0.1524)
				(type default)
			)
			(layer "F.SilkS")
		)
		(fp_line
			(start 0.67945 0.3048)
			(end 0.120396 0.3048)
			(stroke
				(width 0.1)
				(type default)
			)
			(layer "F.Fab")
		)
		(fp_line
			(start 0.67945 -0.3048)
			(end 0.67945 0.3048)
			(stroke
				(width 0.1)
				(type default)
			)
			(layer "F.Fab")
		)
		(fp_line
			(start 0.12065 -0.2794)
			(end 0.12065 -0.3048)
			(stroke
				(width 0.1)
				(type default)
			)
			(layer "F.Fab")
		)
		(fp_line
			(start 0.12065 -0.3048)
			(end 0.67945 -0.3048)
			(stroke
				(width 0.1)
				(type default)
			)
			(layer "F.Fab")
		)
		(fp_line
			(start 0.120396 0.3048)
			(end 0.120396 0.2794)
			(stroke
				(width 0.1)
				(type default)
			)
			(layer "F.Fab")
		)
		(fp_line
			(start 0.120396 0.2794)
			(end -0.12065 0.2794)
			(stroke
				(width 0.1)
				(type default)
			)
			(layer "F.Fab")
		)
		(fp_line
			(start -0.12065 0.3048)
			(end -0.67945 0.3048)
			(stroke
				(width 0.1)
				(type default)
			)
			(layer "F.Fab")
		)
		(fp_line
			(start -0.12065 0.2794)
			(end -0.12065 0.3048)
			(stroke
				(width 0.1)
				(type default)
			)
			(layer "F.Fab")
		)
		(fp_line
			(start -0.12065 -0.2794)
			(end 0.12065 -0.2794)
			(stroke
				(width 0.1)
				(type default)
			)
			(layer "F.Fab")
		)
		(fp_line
			(start -0.12065 -0.305054)
			(end -0.12065 -0.2794)
			(stroke
				(width 0.1)
				(type default)
			)
			(layer "F.Fab")
		)
		(fp_line
			(start -0.67945 0.3048)
			(end -0.67945 -0.305054)
			(stroke
				(width 0.1)
				(type default)
			)
			(layer "F.Fab")
		)
		(fp_line
			(start -0.67945 -0.305054)
			(end -0.12065 -0.305054)
			(stroke
				(width 0.1)
				(type default)
			)
			(layer "F.Fab")
		)
		(pad "1" smd circle
			(at -0.40005 0 180)
			(size 0 0)
			(layers "F.Cu" "F.Mask" "F.Paste")
			(net "FAN_7_ON")
		)
		(pad "2" smd circle
			(at 0.40005 0 180)
			(size 0 0)
			(layers "F.Cu" "F.Mask" "F.Paste")
			(net "P52V_FAN_7_EN")
		)
	)
	(footprint ""
		(layer "F.Cu")
		(at 14.0589 -133.604 180)
		(property "Reference" "R5594"
			(at 0 0 180)
			(layer "F.SilkS")
			(hide yes)
			(effects
				(font
					(size 1.27 1.27)
				)
			)
		)
		(property "Value" ""
			(at 0 0 180)
			(layer "F.Fab")
			(effects
				(font
					(size 1.27 1.27)
				)
			)
		)
		(duplicate_pad_numbers_are_jumpers no)
		(fp_line
			(start 0.7874 0.4064)
			(end -0.7874 0.4064)
			(stroke
				(width 0.1524)
				(type default)
			)
			(layer "F.SilkS")
		)
		(fp_line
			(start 0.7874 -0.4064)
			(end 0.7874 0.4064)
			(stroke
				(width 0.1524)
				(type default)
			)
			(layer "F.SilkS")
		)
		(fp_line
			(start -0.7874 0.4064)
			(end -0.7874 -0.4064)
			(stroke
				(width 0.1524)
				(type default)
			)
			(layer "F.SilkS")
		)
		(fp_line
			(start -0.7874 -0.4064)
			(end 0.7874 -0.4064)
			(stroke
				(width 0.1524)
				(type default)
			)
			(layer "F.SilkS")
		)
		(fp_line
			(start 0.67945 0.3048)
			(end 0.120396 0.3048)
			(stroke
				(width 0.1)
				(type default)
			)
			(layer "F.Fab")
		)
		(fp_line
			(start 0.67945 -0.3048)
			(end 0.67945 0.3048)
			(stroke
				(width 0.1)
				(type default)
			)
			(layer "F.Fab")
		)
		(fp_line
			(start 0.12065 -0.2794)
			(end 0.12065 -0.3048)
			(stroke
				(width 0.1)
				(type default)
			)
			(layer "F.Fab")
		)
		(fp_line
			(start 0.12065 -0.3048)
			(end 0.67945 -0.3048)
			(stroke
				(width 0.1)
				(type default)
			)
			(layer "F.Fab")
		)
		(fp_line
			(start 0.120396 0.3048)
			(end 0.120396 0.2794)
			(stroke
				(width 0.1)
				(type default)
			)
			(layer "F.Fab")
		)
		(fp_line
			(start 0.120396 0.2794)
			(end -0.12065 0.2794)
			(stroke
				(width 0.1)
				(type default)
			)
			(layer "F.Fab")
		)
		(fp_line
			(start -0.12065 0.3048)
			(end -0.67945 0.3048)
			(stroke
				(width 0.1)
				(type default)
			)
			(layer "F.Fab")
		)
		(fp_line
			(start -0.12065 0.2794)
			(end -0.12065 0.3048)
			(stroke
				(width 0.1)
				(type default)
			)
			(layer "F.Fab")
		)
		(fp_line
			(start -0.12065 -0.2794)
			(end 0.12065 -0.2794)
			(stroke
				(width 0.1)
				(type default)
			)
			(layer "F.Fab")
		)
		(fp_line
			(start -0.12065 -0.305054)
			(end -0.12065 -0.2794)
			(stroke
				(width 0.1)
				(type default)
			)
			(layer "F.Fab")
		)
		(fp_line
			(start -0.67945 0.3048)
			(end -0.67945 -0.305054)
			(stroke
				(width 0.1)
				(type default)
			)
			(layer "F.Fab")
		)
		(fp_line
			(start -0.67945 -0.305054)
			(end -0.12065 -0.305054)
			(stroke
				(width 0.1)
				(type default)
			)
			(layer "F.Fab")
		)
		(pad "1" smd rect
			(at -0.40005 0)
			(size 0.4572 0.508)
			(layers "F.Cu" "F.Mask" "F.Paste")
			(net "FAN_6_TACH_OL")
		)
		(pad "2" smd rect
			(at 0.40005 0)
			(size 0.4572 0.508)
			(layers "F.Cu" "F.Mask" "F.Paste")
			(net "FAN_6_TACH_OL_R2")
		)
	)
	(footprint ""
		(layer "F.Cu")
		(at 37.338 -291.1856)
		(property "Reference" "R5400"
			(at 0 0 0)
			(layer "F.SilkS")
			(hide yes)
			(effects
				(font
					(size 1.27 1.27)
				)
			)
		)
		(property "Value" ""
			(at 0 0 0)
			(layer "F.Fab")
			(effects
				(font
					(size 1.27 1.27)
				)
			)
		)
		(duplicate_pad_numbers_are_jumpers no)
		(fp_line
			(start -0.7874 -0.4064)
			(end 0.7874 -0.4064)
			(stroke
				(width 0.1524)
				(type default)
			)
			(layer "F.SilkS")
		)
		(fp_line
			(start -0.7874 0.4064)
			(end -0.7874 -0.4064)
			(stroke
				(width 0.1524)
				(type default)
			)
			(layer "F.SilkS")
		)
		(fp_line
			(start 0.7874 -0.4064)
			(end 0.7874 0.4064)
			(stroke
				(width 0.1524)
				(type default)
			)
			(layer "F.SilkS")
		)
		(fp_line
			(start 0.7874 0.4064)
			(end -0.7874 0.4064)
			(stroke
				(width 0.1524)
				(type default)
			)
			(layer "F.SilkS")
		)
		(fp_line
			(start -0.67945 -0.305054)
			(end -0.12065 -0.305054)
			(stroke
				(width 0.1)
				(type default)
			)
			(layer "F.Fab")
		)
		(fp_line
			(start -0.67945 0.3048)
			(end -0.67945 -0.305054)
			(stroke
				(width 0.1)
				(type default)
			)
			(layer "F.Fab")
		)
		(fp_line
			(start -0.12065 -0.305054)
			(end -0.12065 -0.2794)
			(stroke
				(width 0.1)
				(type default)
			)
			(layer "F.Fab")
		)
		(fp_line
			(start -0.12065 -0.2794)
			(end 0.12065 -0.2794)
			(stroke
				(width 0.1)
				(type default)
			)
			(layer "F.Fab")
		)
		(fp_line
			(start -0.12065 0.2794)
			(end -0.12065 0.3048)
			(stroke
				(width 0.1)
				(type default)
			)
			(layer "F.Fab")
		)
		(fp_line
			(start -0.12065 0.3048)
			(end -0.67945 0.3048)
			(stroke
				(width 0.1)
				(type default)
			)
			(layer "F.Fab")
		)
		(fp_line
			(start 0.120396 0.2794)
			(end -0.12065 0.2794)
			(stroke
				(width 0.1)
				(type default)
			)
			(layer "F.Fab")
		)
		(fp_line
			(start 0.120396 0.3048)
			(end 0.120396 0.2794)
			(stroke
				(width 0.1)
				(type default)
			)
			(layer "F.Fab")
		)
		(fp_line
			(start 0.12065 -0.3048)
			(end 0.67945 -0.3048)
			(stroke
				(width 0.1)
				(type default)
			)
			(layer "F.Fab")
		)
		(fp_line
			(start 0.12065 -0.2794)
			(end 0.12065 -0.3048)
			(stroke
				(width 0.1)
				(type default)
			)
			(layer "F.Fab")
		)
		(fp_line
			(start 0.67945 -0.3048)
			(end 0.67945 0.3048)
			(stroke
				(width 0.1)
				(type default)
			)
			(layer "F.Fab")
		)
		(fp_line
			(start 0.67945 0.3048)
			(end 0.120396 0.3048)
			(stroke
				(width 0.1)
				(type default)
			)
			(layer "F.Fab")
		)
		(pad "1" smd rect
			(at -0.40005 0 180)
			(size 0.4572 0.508)
			(layers "F.Cu" "F.Mask" "F.Paste")
			(net "FAN_0_OK_LED_R_N")
		)
		(pad "2" smd rect
			(at 0.40005 0 180)
			(size 0.4572 0.508)
			(layers "F.Cu" "F.Mask" "F.Paste")
			(net "FAN_0_OK_R_LED_N")
		)
	)
	(footprint ""
		(layer "F.Cu")
		(at 5.715 -65.278 -90)
		(property "Reference" "PR48"
			(at 0 0 270)
			(layer "F.SilkS")
			(hide yes)
			(effects
				(font
					(size 1.27 1.27)
				)
			)
		)
		(property "Value" ""
			(at 0 0 270)
			(layer "F.Fab")
			(effects
				(font
					(size 1.27 1.27)
				)
			)
		)
		(duplicate_pad_numbers_are_jumpers no)
		(fp_line
			(start -0.7874 0.4064)
			(end -0.7874 -0.4064)
			(stroke
				(width 0.1524)
				(type default)
			)
			(layer "F.SilkS")
		)
		(fp_line
			(start 0.7874 0.4064)
			(end -0.7874 0.4064)
			(stroke
				(width 0.1524)
				(type default)
			)
			(layer "F.SilkS")
		)
		(fp_line
			(start -0.7874 -0.4064)
			(end 0.7874 -0.4064)
			(stroke
				(width 0.1524)
				(type default)
			)
			(layer "F.SilkS")
		)
		(fp_line
			(start 0.7874 -0.4064)
			(end 0.7874 0.4064)
			(stroke
				(width 0.1524)
				(type default)
			)
			(layer "F.SilkS")
		)
		(fp_line
			(start -0.67945 0.3048)
			(end -0.67945 -0.305054)
			(stroke
				(width 0.1)
				(type default)
			)
			(layer "F.Fab")
		)
		(fp_line
			(start -0.12065 0.3048)
			(end -0.67945 0.3048)
			(stroke
				(width 0.1)
				(type default)
			)
			(layer "F.Fab")
		)
		(fp_line
			(start 0.120396 0.3048)
			(end 0.120396 0.2794)
			(stroke
				(width 0.1)
				(type default)
			)
			(layer "F.Fab")
		)
		(fp_line
			(start 0.67945 0.3048)
			(end 0.120396 0.3048)
			(stroke
				(width 0.1)
				(type default)
			)
			(layer "F.Fab")
		)
		(fp_line
			(start -0.12065 0.2794)
			(end -0.12065 0.3048)
			(stroke
				(width 0.1)
				(type default)
			)
			(layer "F.Fab")
		)
		(fp_line
			(start 0.120396 0.2794)
			(end -0.12065 0.2794)
			(stroke
				(width 0.1)
				(type default)
			)
			(layer "F.Fab")
		)
		(fp_line
			(start -0.12065 -0.2794)
			(end 0.12065 -0.2794)
			(stroke
				(width 0.1)
				(type default)
			)
			(layer "F.Fab")
		)
		(fp_line
			(start 0.12065 -0.2794)
			(end 0.12065 -0.3048)
			(stroke
				(width 0.1)
				(type default)
			)
			(layer "F.Fab")
		)
		(fp_line
			(start 0.12065 -0.3048)
			(end 0.67945 -0.3048)
			(stroke
				(width 0.1)
				(type default)
			)
			(layer "F.Fab")
		)
		(fp_line
			(start 0.67945 -0.3048)
			(end 0.67945 0.3048)
			(stroke
				(width 0.1)
				(type default)
			)
			(layer "F.Fab")
		)
		(fp_line
			(start -0.67945 -0.305054)
			(end -0.12065 -0.305054)
			(stroke
				(width 0.1)
				(type default)
			)
			(layer "F.Fab")
		)
		(fp_line
			(start -0.12065 -0.305054)
			(end -0.12065 -0.2794)
			(stroke
				(width 0.1)
				(type default)
			)
			(layer "F.Fab")
		)
		(pad "1" smd rect
			(at -0.40005 0 90)
			(size 0.4572 0.508)
			(layers "F.Cu" "F.Mask" "F.Paste")
			(net "FAN_4_FAULT_R")
		)
		(pad "2" smd rect
			(at 0.40005 0 90)
			(size 0.4572 0.508)
			(layers "F.Cu" "F.Mask" "F.Paste")
			(net "FAN_4_FAULT")
		)
	)
	(footprint ""
		(layer "F.Cu")
		(at 19.939 -154.94 -90)
		(property "Reference" "C1933"
			(at 0 0 270)
			(layer "F.SilkS")
			(hide yes)
			(effects
				(font
					(size 1.27 1.27)
				)
			)
		)
		(property "Value" ""
			(at 0 0 270)
			(layer "F.Fab")
			(effects
				(font
					(size 1.27 1.27)
				)
			)
		)
		(duplicate_pad_numbers_are_jumpers no)
		(fp_line
			(start -0.7874 0.4064)
			(end -0.7874 -0.4064)
			(stroke
				(width 0.1524)
				(type default)
			)
			(layer "F.SilkS")
		)
		(fp_line
			(start 0.7874 0.4064)
			(end -0.7874 0.4064)
			(stroke
				(width 0.1524)
				(type default)
			)
			(layer "F.SilkS")
		)
		(fp_line
			(start -0.7874 -0.4064)
			(end 0.7874 -0.4064)
			(stroke
				(width 0.1524)
				(type default)
			)
			(layer "F.SilkS")
		)
		(fp_line
			(start 0.7874 -0.4064)
			(end 0.7874 0.4064)
			(stroke
				(width 0.1524)
				(type default)
			)
			(layer "F.SilkS")
		)
		(fp_line
			(start -0.67945 0.3048)
			(end -0.67945 -0.305054)
			(stroke
				(width 0.1)
				(type default)
			)
			(layer "F.Fab")
		)
		(fp_line
			(start -0.12065 0.3048)
			(end -0.67945 0.3048)
			(stroke
				(width 0.1)
				(type default)
			)
			(layer "F.Fab")
		)
		(fp_line
			(start 0.120396 0.3048)
			(end 0.120396 0.2794)
			(stroke
				(width 0.1)
				(type default)
			)
			(layer "F.Fab")
		)
		(fp_line
			(start 0.67945 0.3048)
			(end 0.120396 0.3048)
			(stroke
				(width 0.1)
				(type default)
			)
			(layer "F.Fab")
		)
		(fp_line
			(start -0.12065 0.2794)
			(end -0.12065 0.3048)
			(stroke
				(width 0.1)
				(type default)
			)
			(layer "F.Fab")
		)
		(fp_line
			(start 0.120396 0.2794)
			(end -0.12065 0.2794)
			(stroke
				(width 0.1)
				(type default)
			)
			(layer "F.Fab")
		)
		(fp_line
			(start -0.12065 -0.2794)
			(end 0.12065 -0.2794)
			(stroke
				(width 0.1)
				(type default)
			)
			(layer "F.Fab")
		)
		(fp_line
			(start 0.12065 -0.2794)
			(end 0.12065 -0.3048)
			(stroke
				(width 0.1)
				(type default)
			)
			(layer "F.Fab")
		)
		(fp_line
			(start 0.12065 -0.3048)
			(end 0.67945 -0.3048)
			(stroke
				(width 0.1)
				(type default)
			)
			(layer "F.Fab")
		)
		(fp_line
			(start 0.67945 -0.3048)
			(end 0.67945 0.3048)
			(stroke
				(width 0.1)
				(type default)
			)
			(layer "F.Fab")
		)
		(fp_line
			(start -0.67945 -0.305054)
			(end -0.12065 -0.305054)
			(stroke
				(width 0.1)
				(type default)
			)
			(layer "F.Fab")
		)
		(fp_line
			(start -0.12065 -0.305054)
			(end -0.12065 -0.2794)
			(stroke
				(width 0.1)
				(type default)
			)
			(layer "F.Fab")
		)
		(pad "1" smd circle
			(at -0.40005 0 270)
			(size 0 0)
			(layers "F.Cu" "F.Mask" "F.Paste")
			(net "GND")
		)
		(pad "2" smd circle
			(at 0.40005 0 270)
			(size 0 0)
			(layers "F.Cu" "F.Mask" "F.Paste")
			(net "P3V3_AUX")
		)
	)
	(footprint ""
		(layer "F.Cu")
		(at 46.99 -221.234 90)
		(property "Reference" "C2121"
			(at 0 0 90)
			(layer "F.SilkS")
			(hide yes)
			(effects
				(font
					(size 1.27 1.27)
				)
			)
		)
		(property "Value" ""
			(at 0 0 90)
			(layer "F.Fab")
			(effects
				(font
					(size 1.27 1.27)
				)
			)
		)
		(duplicate_pad_numbers_are_jumpers no)
		(fp_line
			(start 1.2954 -0.5842)
			(end 1.2954 0.5842)
			(stroke
				(width 0.1524)
				(type default)
			)
			(layer "F.SilkS")
		)
		(fp_line
			(start -1.2954 -0.5842)
			(end 1.2954 -0.5842)
			(stroke
				(width 0.1524)
				(type default)
			)
			(layer "F.SilkS")
		)
		(fp_line
			(start 1.2954 0.5842)
			(end -1.2954 0.5842)
			(stroke
				(width 0.1524)
				(type default)
			)
			(layer "F.SilkS")
		)
		(fp_line
			(start -1.2954 0.5842)
			(end -1.2954 -0.5842)
			(stroke
				(width 0.1524)
				(type default)
			)
			(layer "F.SilkS")
		)
		(fp_line
			(start 0.8636 -0.4572)
			(end 0.8636 -0.4064)
			(stroke
				(width 0.1)
				(type default)
			)
			(layer "F.Fab")
		)
		(fp_line
			(start -0.8636 -0.4572)
			(end 0.8636 -0.4572)
			(stroke
				(width 0.1)
				(type default)
			)
			(layer "F.Fab")
		)
		(fp_line
			(start 1.1938 -0.4064)
			(end 1.1938 0.4064)
			(stroke
				(width 0.1)
				(type default)
			)
			(layer "F.Fab")
		)
		(fp_line
			(start 0.8636 -0.4064)
			(end 1.1938 -0.4064)
			(stroke
				(width 0.1)
				(type default)
			)
			(layer "F.Fab")
		)
		(fp_line
			(start -0.8636 -0.4064)
			(end -0.8636 -0.4572)
			(stroke
				(width 0.1)
				(type default)
			)
			(layer "F.Fab")
		)
		(fp_line
			(start -1.1938 -0.4064)
			(end -0.8636 -0.4064)
			(stroke
				(width 0.1)
				(type default)
			)
			(layer "F.Fab")
		)
		(fp_line
			(start 1.1938 0.4064)
			(end 0.8636 0.4064)
			(stroke
				(width 0.1)
				(type default)
			)
			(layer "F.Fab")
		)
		(fp_line
			(start 0.8636 0.4064)
			(end 0.8636 0.4572)
			(stroke
				(width 0.1)
				(type default)
			)
			(layer "F.Fab")
		)
		(fp_line
			(start -0.8636 0.4064)
			(end -1.1938 0.4064)
			(stroke
				(width 0.1)
				(type default)
			)
			(layer "F.Fab")
		)
		(fp_line
			(start -1.1938 0.4064)
			(end -1.1938 -0.4064)
			(stroke
				(width 0.1)
				(type default)
			)
			(layer "F.Fab")
		)
		(fp_line
			(start 0.8636 0.4572)
			(end -0.8636 0.4572)
			(stroke
				(width 0.1)
				(type default)
			)
			(layer "F.Fab")
		)
		(fp_line
			(start -0.8636 0.4572)
			(end -0.8636 0.4064)
			(stroke
				(width 0.1)
				(type default)
			)
			(layer "F.Fab")
		)
		(pad "1" smd rect
			(at -0.7366 0)
			(size 0.7112 0.8128)
			(layers "F.Cu" "F.Mask" "F.Paste")
			(net "U406_D1")
		)
		(pad "2" smd rect
			(at 0.7366 0)
			(size 0.7112 0.8128)
			(layers "F.Cu" "F.Mask" "F.Paste")
			(net "GND")
		)
	)
	(footprint ""
		(layer "F.Cu")
		(at 47.752 -308.61 180)
		(property "Reference" "C2019"
			(at 0 0 180)
			(layer "F.SilkS")
			(hide yes)
			(effects
				(font
					(size 1.27 1.27)
				)
			)
		)
		(property "Value" ""
			(at 0 0 180)
			(layer "F.Fab")
			(effects
				(font
					(size 1.27 1.27)
				)
			)
		)
		(duplicate_pad_numbers_are_jumpers no)
		(fp_line
			(start 0.7874 0.4064)
			(end -0.7874 0.4064)
			(stroke
				(width 0.1524)
				(type default)
			)
			(layer "F.SilkS")
		)
		(fp_line
			(start 0.7874 -0.4064)
			(end 0.7874 0.4064)
			(stroke
				(width 0.1524)
				(type default)
			)
			(layer "F.SilkS")
		)
		(fp_line
			(start -0.7874 0.4064)
			(end -0.7874 -0.4064)
			(stroke
				(width 0.1524)
				(type default)
			)
			(layer "F.SilkS")
		)
		(fp_line
			(start -0.7874 -0.4064)
			(end 0.7874 -0.4064)
			(stroke
				(width 0.1524)
				(type default)
			)
			(layer "F.SilkS")
		)
		(fp_line
			(start 0.6858 0.3048)
			(end 0.1016 0.3048)
			(stroke
				(width 0.1)
				(type default)
			)
			(layer "F.Fab")
		)
		(fp_line
			(start 0.6858 -0.3048)
			(end 0.6858 0.3048)
			(stroke
				(width 0.1)
				(type default)
			)
			(layer "F.Fab")
		)
		(fp_line
			(start 0.1016 0.3048)
			(end 0.1016 0.2794)
			(stroke
				(width 0.1)
				(type default)
			)
			(layer "F.Fab")
		)
		(fp_line
			(start 0.1016 0.2794)
			(end -0.1016 0.2794)
			(stroke
				(width 0.1)
				(type default)
			)
			(layer "F.Fab")
		)
		(fp_line
			(start 0.1016 -0.2794)
			(end 0.1016 -0.3048)
			(stroke
				(width 0.1)
				(type default)
			)
			(layer "F.Fab")
		)
		(fp_line
			(start 0.1016 -0.3048)
			(end 0.6858 -0.3048)
			(stroke
				(width 0.1)
				(type default)
			)
			(layer "F.Fab")
		)
		(fp_line
			(start -0.1016 0.3048)
			(end -0.6858 0.3048)
			(stroke
				(width 0.1)
				(type default)
			)
			(layer "F.Fab")
		)
		(fp_line
			(start -0.1016 0.2794)
			(end -0.1016 0.3048)
			(stroke
				(width 0.1)
				(type default)
			)
			(layer "F.Fab")
		)
		(fp_line
			(start -0.1016 -0.2794)
			(end 0.1016 -0.2794)
			(stroke
				(width 0.1)
				(type default)
			)
			(layer "F.Fab")
		)
		(fp_line
			(start -0.1016 -0.3048)
			(end -0.1016 -0.2794)
			(stroke
				(width 0.1)
				(type default)
			)
			(layer "F.Fab")
		)
		(fp_line
			(start -0.6858 0.3048)
			(end -0.6858 -0.3048)
			(stroke
				(width 0.1)
				(type default)
			)
			(layer "F.Fab")
		)
		(fp_line
			(start -0.6858 -0.3048)
			(end -0.1016 -0.3048)
			(stroke
				(width 0.1)
				(type default)
			)
			(layer "F.Fab")
		)
		(pad "1" smd rect
			(at -0.40005 0)
			(size 0.4572 0.508)
			(layers "F.Cu" "F.Mask" "F.Paste")
			(net "GND")
		)
		(pad "2" smd rect
			(at 0.40005 0)
			(size 0.4572 0.508)
			(layers "F.Cu" "F.Mask" "F.Paste")
			(net "P12V_LED_FAN0")
		)
	)
	(footprint ""
		(layer "F.Cu")
		(at 34.666428 -67.494912 90)
		(property "Reference" "C165"
			(at 0 0 90)
			(layer "F.SilkS")
			(hide yes)
			(effects
				(font
					(size 1.27 1.27)
				)
			)
		)
		(property "Value" ""
			(at 0 0 90)
			(layer "F.Fab")
			(effects
				(font
					(size 1.27 1.27)
				)
			)
		)
		(duplicate_pad_numbers_are_jumpers no)
		(fp_line
			(start 0.7874 -0.4064)
			(end 0.7874 0.4064)
			(stroke
				(width 0.1524)
				(type default)
			)
			(layer "F.SilkS")
		)
		(fp_line
			(start -0.7874 -0.4064)
			(end 0.7874 -0.4064)
			(stroke
				(width 0.1524)
				(type default)
			)
			(layer "F.SilkS")
		)
		(fp_line
			(start 0.7874 0.4064)
			(end -0.7874 0.4064)
			(stroke
				(width 0.1524)
				(type default)
			)
			(layer "F.SilkS")
		)
		(fp_line
			(start -0.7874 0.4064)
			(end -0.7874 -0.4064)
			(stroke
				(width 0.1524)
				(type default)
			)
			(layer "F.SilkS")
		)
		(fp_line
			(start -0.12065 -0.305054)
			(end -0.12065 -0.2794)
			(stroke
				(width 0.1)
				(type default)
			)
			(layer "F.Fab")
		)
		(fp_line
			(start -0.67945 -0.305054)
			(end -0.12065 -0.305054)
			(stroke
				(width 0.1)
				(type default)
			)
			(layer "F.Fab")
		)
		(fp_line
			(start 0.67945 -0.3048)
			(end 0.67945 0.3048)
			(stroke
				(width 0.1)
				(type default)
			)
			(layer "F.Fab")
		)
		(fp_line
			(start 0.12065 -0.3048)
			(end 0.67945 -0.3048)
			(stroke
				(width 0.1)
				(type default)
			)
			(layer "F.Fab")
		)
		(fp_line
			(start 0.12065 -0.2794)
			(end 0.12065 -0.3048)
			(stroke
				(width 0.1)
				(type default)
			)
			(layer "F.Fab")
		)
		(fp_line
			(start -0.12065 -0.2794)
			(end 0.12065 -0.2794)
			(stroke
				(width 0.1)
				(type default)
			)
			(layer "F.Fab")
		)
		(fp_line
			(start 0.120396 0.2794)
			(end -0.12065 0.2794)
			(stroke
				(width 0.1)
				(type default)
			)
			(layer "F.Fab")
		)
		(fp_line
			(start -0.12065 0.2794)
			(end -0.12065 0.3048)
			(stroke
				(width 0.1)
				(type default)
			)
			(layer "F.Fab")
		)
		(fp_line
			(start 0.67945 0.3048)
			(end 0.120396 0.3048)
			(stroke
				(width 0.1)
				(type default)
			)
			(layer "F.Fab")
		)
		(fp_line
			(start 0.120396 0.3048)
			(end 0.120396 0.2794)
			(stroke
				(width 0.1)
				(type default)
			)
			(layer "F.Fab")
		)
		(fp_line
			(start -0.12065 0.3048)
			(end -0.67945 0.3048)
			(stroke
				(width 0.1)
				(type default)
			)
			(layer "F.Fab")
		)
		(fp_line
			(start -0.67945 0.3048)
			(end -0.67945 -0.305054)
			(stroke
				(width 0.1)
				(type default)
			)
			(layer "F.Fab")
		)
		(pad "1" smd circle
			(at -0.40005 0 90)
			(size 0 0)
			(layers "F.Cu" "F.Mask" "F.Paste")
			(net "P3V3_AUX")
		)
		(pad "2" smd circle
			(at 0.40005 0 90)
			(size 0 0)
			(layers "F.Cu" "F.Mask" "F.Paste")
			(net "GND")
		)
	)
	(footprint ""
		(layer "F.Cu")
		(at 28.321 -194.818 90)
		(property "Reference" "R5517"
			(at 0 0 90)
			(layer "F.SilkS")
			(hide yes)
			(effects
				(font
					(size 1.27 1.27)
				)
			)
		)
		(property "Value" ""
			(at 0 0 90)
			(layer "F.Fab")
			(effects
				(font
					(size 1.27 1.27)
				)
			)
		)
		(duplicate_pad_numbers_are_jumpers no)
		(fp_line
			(start 0.7874 -0.4064)
			(end 0.7874 0.4064)
			(stroke
				(width 0.1524)
				(type default)
			)
			(layer "F.SilkS")
		)
		(fp_line
			(start -0.7874 -0.4064)
			(end 0.7874 -0.4064)
			(stroke
				(width 0.1524)
				(type default)
			)
			(layer "F.SilkS")
		)
		(fp_line
			(start 0.7874 0.4064)
			(end -0.7874 0.4064)
			(stroke
				(width 0.1524)
				(type default)
			)
			(layer "F.SilkS")
		)
		(fp_line
			(start -0.7874 0.4064)
			(end -0.7874 -0.4064)
			(stroke
				(width 0.1524)
				(type default)
			)
			(layer "F.SilkS")
		)
		(fp_line
			(start -0.12065 -0.305054)
			(end -0.12065 -0.2794)
			(stroke
				(width 0.1)
				(type default)
			)
			(layer "F.Fab")
		)
		(fp_line
			(start -0.67945 -0.305054)
			(end -0.12065 -0.305054)
			(stroke
				(width 0.1)
				(type default)
			)
			(layer "F.Fab")
		)
		(fp_line
			(start 0.67945 -0.3048)
			(end 0.67945 0.3048)
			(stroke
				(width 0.1)
				(type default)
			)
			(layer "F.Fab")
		)
		(fp_line
			(start 0.12065 -0.3048)
			(end 0.67945 -0.3048)
			(stroke
				(width 0.1)
				(type default)
			)
			(layer "F.Fab")
		)
		(fp_line
			(start 0.12065 -0.2794)
			(end 0.12065 -0.3048)
			(stroke
				(width 0.1)
				(type default)
			)
			(layer "F.Fab")
		)
		(fp_line
			(start -0.12065 -0.2794)
			(end 0.12065 -0.2794)
			(stroke
				(width 0.1)
				(type default)
			)
			(layer "F.Fab")
		)
		(fp_line
			(start 0.120396 0.2794)
			(end -0.12065 0.2794)
			(stroke
				(width 0.1)
				(type default)
			)
			(layer "F.Fab")
		)
		(fp_line
			(start -0.12065 0.2794)
			(end -0.12065 0.3048)
			(stroke
				(width 0.1)
				(type default)
			)
			(layer "F.Fab")
		)
		(fp_line
			(start 0.67945 0.3048)
			(end 0.120396 0.3048)
			(stroke
				(width 0.1)
				(type default)
			)
			(layer "F.Fab")
		)
		(fp_line
			(start 0.120396 0.3048)
			(end 0.120396 0.2794)
			(stroke
				(width 0.1)
				(type default)
			)
			(layer "F.Fab")
		)
		(fp_line
			(start -0.12065 0.3048)
			(end -0.67945 0.3048)
			(stroke
				(width 0.1)
				(type default)
			)
			(layer "F.Fab")
		)
		(fp_line
			(start -0.67945 0.3048)
			(end -0.67945 -0.305054)
			(stroke
				(width 0.1)
				(type default)
			)
			(layer "F.Fab")
		)
		(pad "1" smd circle
			(at -0.40005 0 90)
			(size 0 0)
			(layers "F.Cu" "F.Mask" "F.Paste")
			(net "P3V3_AUX")
		)
		(pad "2" smd circle
			(at 0.40005 0 90)
			(size 0 0)
			(layers "F.Cu" "F.Mask" "F.Paste")
			(net "FAN_6_PWM_BUF")
		)
	)
	(footprint ""
		(layer "F.Cu")
		(at 37.338 -294.767 180)
		(property "Reference" "R5188"
			(at 0 0 180)
			(layer "F.SilkS")
			(hide yes)
			(effects
				(font
					(size 1.27 1.27)
				)
			)
		)
		(property "Value" ""
			(at 0 0 180)
			(layer "F.Fab")
			(effects
				(font
					(size 1.27 1.27)
				)
			)
		)
		(duplicate_pad_numbers_are_jumpers no)
		(fp_line
			(start 0.7874 0.4064)
			(end -0.7874 0.4064)
			(stroke
				(width 0.1524)
				(type default)
			)
			(layer "F.SilkS")
		)
		(fp_line
			(start 0.7874 -0.4064)
			(end 0.7874 0.4064)
			(stroke
				(width 0.1524)
				(type default)
			)
			(layer "F.SilkS")
		)
		(fp_line
			(start -0.7874 0.4064)
			(end -0.7874 -0.4064)
			(stroke
				(width 0.1524)
				(type default)
			)
			(layer "F.SilkS")
		)
		(fp_line
			(start -0.7874 -0.4064)
			(end 0.7874 -0.4064)
			(stroke
				(width 0.1524)
				(type default)
			)
			(layer "F.SilkS")
		)
		(fp_line
			(start 0.67945 0.3048)
			(end 0.120396 0.3048)
			(stroke
				(width 0.1)
				(type default)
			)
			(layer "F.Fab")
		)
		(fp_line
			(start 0.67945 -0.3048)
			(end 0.67945 0.3048)
			(stroke
				(width 0.1)
				(type default)
			)
			(layer "F.Fab")
		)
		(fp_line
			(start 0.12065 -0.2794)
			(end 0.12065 -0.3048)
			(stroke
				(width 0.1)
				(type default)
			)
			(layer "F.Fab")
		)
		(fp_line
			(start 0.12065 -0.3048)
			(end 0.67945 -0.3048)
			(stroke
				(width 0.1)
				(type default)
			)
			(layer "F.Fab")
		)
		(fp_line
			(start 0.120396 0.3048)
			(end 0.120396 0.2794)
			(stroke
				(width 0.1)
				(type default)
			)
			(layer "F.Fab")
		)
		(fp_line
			(start 0.120396 0.2794)
			(end -0.12065 0.2794)
			(stroke
				(width 0.1)
				(type default)
			)
			(layer "F.Fab")
		)
		(fp_line
			(start -0.12065 0.3048)
			(end -0.67945 0.3048)
			(stroke
				(width 0.1)
				(type default)
			)
			(layer "F.Fab")
		)
		(fp_line
			(start -0.12065 0.2794)
			(end -0.12065 0.3048)
			(stroke
				(width 0.1)
				(type default)
			)
			(layer "F.Fab")
		)
		(fp_line
			(start -0.12065 -0.2794)
			(end 0.12065 -0.2794)
			(stroke
				(width 0.1)
				(type default)
			)
			(layer "F.Fab")
		)
		(fp_line
			(start -0.12065 -0.305054)
			(end -0.12065 -0.2794)
			(stroke
				(width 0.1)
				(type default)
			)
			(layer "F.Fab")
		)
		(fp_line
			(start -0.67945 0.3048)
			(end -0.67945 -0.305054)
			(stroke
				(width 0.1)
				(type default)
			)
			(layer "F.Fab")
		)
		(fp_line
			(start -0.67945 -0.305054)
			(end -0.12065 -0.305054)
			(stroke
				(width 0.1)
				(type default)
			)
			(layer "F.Fab")
		)
		(pad "1" smd circle
			(at -0.40005 0 180)
			(size 0 0)
			(layers "F.Cu" "F.Mask" "F.Paste")
			(net "SMB_FAN0_SDA_R")
		)
		(pad "2" smd circle
			(at 0.40005 0 180)
			(size 0 0)
			(layers "F.Cu" "F.Mask" "F.Paste")
			(net "SMB_FAN0_SDA")
		)
	)
	(footprint ""
		(layer "F.Cu")
		(at 37.846 -198.374 -90)
		(property "Reference" "R5692"
			(at 0 0 270)
			(layer "F.SilkS")
			(hide yes)
			(effects
				(font
					(size 1.27 1.27)
				)
			)
		)
		(property "Value" ""
			(at 0 0 270)
			(layer "F.Fab")
			(effects
				(font
					(size 1.27 1.27)
				)
			)
		)
		(duplicate_pad_numbers_are_jumpers no)
		(fp_line
			(start -0.7874 0.4064)
			(end -0.7874 -0.4064)
			(stroke
				(width 0.1524)
				(type default)
			)
			(layer "F.SilkS")
		)
		(fp_line
			(start 0.7874 0.4064)
			(end -0.7874 0.4064)
			(stroke
				(width 0.1524)
				(type default)
			)
			(layer "F.SilkS")
		)
		(fp_line
			(start -0.7874 -0.4064)
			(end 0.7874 -0.4064)
			(stroke
				(width 0.1524)
				(type default)
			)
			(layer "F.SilkS")
		)
		(fp_line
			(start 0.7874 -0.4064)
			(end 0.7874 0.4064)
			(stroke
				(width 0.1524)
				(type default)
			)
			(layer "F.SilkS")
		)
		(fp_line
			(start -0.67945 0.3048)
			(end -0.67945 -0.305054)
			(stroke
				(width 0.1)
				(type default)
			)
			(layer "F.Fab")
		)
		(fp_line
			(start -0.12065 0.3048)
			(end -0.67945 0.3048)
			(stroke
				(width 0.1)
				(type default)
			)
			(layer "F.Fab")
		)
		(fp_line
			(start 0.120396 0.3048)
			(end 0.120396 0.2794)
			(stroke
				(width 0.1)
				(type default)
			)
			(layer "F.Fab")
		)
		(fp_line
			(start 0.67945 0.3048)
			(end 0.120396 0.3048)
			(stroke
				(width 0.1)
				(type default)
			)
			(layer "F.Fab")
		)
		(fp_line
			(start -0.12065 0.2794)
			(end -0.12065 0.3048)
			(stroke
				(width 0.1)
				(type default)
			)
			(layer "F.Fab")
		)
		(fp_line
			(start 0.120396 0.2794)
			(end -0.12065 0.2794)
			(stroke
				(width 0.1)
				(type default)
			)
			(layer "F.Fab")
		)
		(fp_line
			(start -0.12065 -0.2794)
			(end 0.12065 -0.2794)
			(stroke
				(width 0.1)
				(type default)
			)
			(layer "F.Fab")
		)
		(fp_line
			(start 0.12065 -0.2794)
			(end 0.12065 -0.3048)
			(stroke
				(width 0.1)
				(type default)
			)
			(layer "F.Fab")
		)
		(fp_line
			(start 0.12065 -0.3048)
			(end 0.67945 -0.3048)
			(stroke
				(width 0.1)
				(type default)
			)
			(layer "F.Fab")
		)
		(fp_line
			(start 0.67945 -0.3048)
			(end 0.67945 0.3048)
			(stroke
				(width 0.1)
				(type default)
			)
			(layer "F.Fab")
		)
		(fp_line
			(start -0.67945 -0.305054)
			(end -0.12065 -0.305054)
			(stroke
				(width 0.1)
				(type default)
			)
			(layer "F.Fab")
		)
		(fp_line
			(start -0.12065 -0.305054)
			(end -0.12065 -0.2794)
			(stroke
				(width 0.1)
				(type default)
			)
			(layer "F.Fab")
		)
		(pad "1" smd rect
			(at -0.40005 0 90)
			(size 0.4572 0.508)
			(layers "F.Cu" "F.Mask" "F.Paste")
			(net "P12V_LED_R_FAN1")
		)
		(pad "2" smd rect
			(at 0.40005 0 90)
			(size 0.4572 0.508)
			(layers "F.Cu" "F.Mask" "F.Paste")
			(net "P12V_LED_R1_FAN1")
		)
	)
	(footprint ""
		(layer "F.Cu")
		(at 14.351 -298.069 180)
		(property "Reference" "D257"
			(at 4.826 -0.53467 0)
			(unlocked yes)
			(layer "F.SilkS")
			(effects
				(font
					(size 0.7874 0.5842)
					(thickness 0.1524)
				)
				(justify left)
			)
		)
		(property "Value" ""
			(at 0 0 180)
			(layer "F.Fab")
			(effects
				(font
					(size 1.27 1.27)
				)
			)
		)
		(duplicate_pad_numbers_are_jumpers no)
		(fp_line
			(start 0.94488 0.450088)
			(end 0.94488 -0.450088)
			(stroke
				(width 0.1524)
				(type default)
			)
			(layer "F.SilkS")
		)
		(fp_line
			(start 0.94488 -0.450088)
			(end -0.854964 -0.450088)
			(stroke
				(width 0.1524)
				(type default)
			)
			(layer "F.SilkS")
		)
		(fp_line
			(start 0.870458 -0.2794)
			(end 0.845058 0.4064)
			(stroke
				(width 0.1524)
				(type default)
			)
			(layer "F.SilkS")
		)
		(fp_line
			(start 0.845058 0.4064)
			(end 0.845058 -0.381)
			(stroke
				(width 0.1524)
				(type default)
			)
			(layer "F.SilkS")
		)
		(fp_line
			(start -0.854964 0.450088)
			(end 0.925068 0.450088)
			(stroke
				(width 0.1524)
				(type default)
			)
			(layer "F.SilkS")
		)
		(fp_line
			(start -0.854964 -0.450088)
			(end -0.854964 0.450088)
			(stroke
				(width 0.1524)
				(type default)
			)
			(layer "F.SilkS")
		)
		(fp_line
			(start 0.54991 0.350012)
			(end 0.54991 -0.350012)
			(stroke
				(width 0.1)
				(type default)
			)
			(layer "F.Fab")
		)
		(fp_line
			(start 0.54991 -0.350012)
			(end -0.54991 -0.350012)
			(stroke
				(width 0.1)
				(type default)
			)
			(layer "F.Fab")
		)
		(fp_line
			(start -0.54991 0.350012)
			(end 0.54991 0.350012)
			(stroke
				(width 0.1)
				(type default)
			)
			(layer "F.Fab")
		)
		(fp_line
			(start -0.54991 -0.350012)
			(end -0.54991 0.350012)
			(stroke
				(width 0.1)
				(type default)
			)
			(layer "F.Fab")
		)
		(fp_text user "-"
			(at 2.159 -0.28575 0)
			(unlocked yes)
			(layer "F.SilkS")
			(effects
				(font
					(size 1.905 1.4224)
					(thickness 0.1524)
				)
				(justify left)
			)
		)
		(fp_text user "+"
			(at -0.381 0.88265 0)
			(unlocked yes)
			(layer "F.SilkS")
			(effects
				(font
					(size 1.905 1.4224)
					(thickness 0.1524)
				)
				(justify left)
			)
		)
		(fp_text user "-"
			(at 2.48539 0.239014 0)
			(unlocked yes)
			(layer "F.Fab")
			(effects
				(font
					(size 1.905 1.4224)
					(thickness 0.1524)
				)
				(justify left)
			)
		)
		(fp_text user "+"
			(at -0.808228 0.239014 0)
			(unlocked yes)
			(layer "F.Fab")
			(effects
				(font
					(size 1.905 1.4224)
					(thickness 0.1524)
				)
				(justify left)
			)
		)
		(pad "A" smd rect
			(at -0.424942 0 180)
			(size 0.5588 0.6096)
			(layers "F.Cu" "F.Mask" "F.Paste")
			(net "GND")
		)
		(pad "C" smd rect
			(at 0.424942 0)
			(size 0.5588 0.6096)
			(layers "F.Cu" "F.Mask" "F.Paste")
			(net "FAN_7_FAIL_R_LED_N")
		)
	)
	(footprint ""
		(layer "F.Cu")
		(at 14.351 -21.384768)
		(property "Reference" "R5132"
			(at 0 0 0)
			(layer "F.SilkS")
			(hide yes)
			(effects
				(font
					(size 1.27 1.27)
				)
			)
		)
		(property "Value" ""
			(at 0 0 0)
			(layer "F.Fab")
			(effects
				(font
					(size 1.27 1.27)
				)
			)
		)
		(duplicate_pad_numbers_are_jumpers no)
		(fp_line
			(start -0.7874 -0.4064)
			(end 0.7874 -0.4064)
			(stroke
				(width 0.1524)
				(type default)
			)
			(layer "F.SilkS")
		)
		(fp_line
			(start -0.7874 0.4064)
			(end -0.7874 -0.4064)
			(stroke
				(width 0.1524)
				(type default)
			)
			(layer "F.SilkS")
		)
		(fp_line
			(start 0.7874 -0.4064)
			(end 0.7874 0.4064)
			(stroke
				(width 0.1524)
				(type default)
			)
			(layer "F.SilkS")
		)
		(fp_line
			(start 0.7874 0.4064)
			(end -0.7874 0.4064)
			(stroke
				(width 0.1524)
				(type default)
			)
			(layer "F.SilkS")
		)
		(fp_line
			(start -0.67945 -0.305054)
			(end -0.12065 -0.305054)
			(stroke
				(width 0.1)
				(type default)
			)
			(layer "F.Fab")
		)
		(fp_line
			(start -0.67945 0.3048)
			(end -0.67945 -0.305054)
			(stroke
				(width 0.1)
				(type default)
			)
			(layer "F.Fab")
		)
		(fp_line
			(start -0.12065 -0.305054)
			(end -0.12065 -0.2794)
			(stroke
				(width 0.1)
				(type default)
			)
			(layer "F.Fab")
		)
		(fp_line
			(start -0.12065 -0.2794)
			(end 0.12065 -0.2794)
			(stroke
				(width 0.1)
				(type default)
			)
			(layer "F.Fab")
		)
		(fp_line
			(start -0.12065 0.2794)
			(end -0.12065 0.3048)
			(stroke
				(width 0.1)
				(type default)
			)
			(layer "F.Fab")
		)
		(fp_line
			(start -0.12065 0.3048)
			(end -0.67945 0.3048)
			(stroke
				(width 0.1)
				(type default)
			)
			(layer "F.Fab")
		)
		(fp_line
			(start 0.120396 0.2794)
			(end -0.12065 0.2794)
			(stroke
				(width 0.1)
				(type default)
			)
			(layer "F.Fab")
		)
		(fp_line
			(start 0.120396 0.3048)
			(end 0.120396 0.2794)
			(stroke
				(width 0.1)
				(type default)
			)
			(layer "F.Fab")
		)
		(fp_line
			(start 0.12065 -0.3048)
			(end 0.67945 -0.3048)
			(stroke
				(width 0.1)
				(type default)
			)
			(layer "F.Fab")
		)
		(fp_line
			(start 0.12065 -0.2794)
			(end 0.12065 -0.3048)
			(stroke
				(width 0.1)
				(type default)
			)
			(layer "F.Fab")
		)
		(fp_line
			(start 0.67945 -0.3048)
			(end 0.67945 0.3048)
			(stroke
				(width 0.1)
				(type default)
			)
			(layer "F.Fab")
		)
		(fp_line
			(start 0.67945 0.3048)
			(end 0.120396 0.3048)
			(stroke
				(width 0.1)
				(type default)
			)
			(layer "F.Fab")
		)
		(pad "1" smd circle
			(at -0.40005 0)
			(size 0 0)
			(layers "F.Cu" "F.Mask" "F.Paste")
			(net "SMB_FAN4_SDA_R")
		)
		(pad "2" smd circle
			(at 0.40005 0)
			(size 0 0)
			(layers "F.Cu" "F.Mask" "F.Paste")
			(net "SMB_FAN4_SDA")
		)
	)
	(footprint ""
		(layer "F.Cu")
		(at 23.114 -141.605 -90)
		(property "Reference" "R5277"
			(at 0 0 270)
			(layer "F.SilkS")
			(hide yes)
			(effects
				(font
					(size 1.27 1.27)
				)
			)
		)
		(property "Value" ""
			(at 0 0 270)
			(layer "F.Fab")
			(effects
				(font
					(size 1.27 1.27)
				)
			)
		)
		(duplicate_pad_numbers_are_jumpers no)
		(fp_line
			(start -0.7874 0.4064)
			(end -0.7874 -0.4064)
			(stroke
				(width 0.1524)
				(type default)
			)
			(layer "F.SilkS")
		)
		(fp_line
			(start 0.7874 0.4064)
			(end -0.7874 0.4064)
			(stroke
				(width 0.1524)
				(type default)
			)
			(layer "F.SilkS")
		)
		(fp_line
			(start -0.7874 -0.4064)
			(end 0.7874 -0.4064)
			(stroke
				(width 0.1524)
				(type default)
			)
			(layer "F.SilkS")
		)
		(fp_line
			(start 0.7874 -0.4064)
			(end 0.7874 0.4064)
			(stroke
				(width 0.1524)
				(type default)
			)
			(layer "F.SilkS")
		)
		(fp_line
			(start -0.67945 0.3048)
			(end -0.67945 -0.305054)
			(stroke
				(width 0.1)
				(type default)
			)
			(layer "F.Fab")
		)
		(fp_line
			(start -0.12065 0.3048)
			(end -0.67945 0.3048)
			(stroke
				(width 0.1)
				(type default)
			)
			(layer "F.Fab")
		)
		(fp_line
			(start 0.120396 0.3048)
			(end 0.120396 0.2794)
			(stroke
				(width 0.1)
				(type default)
			)
			(layer "F.Fab")
		)
		(fp_line
			(start 0.67945 0.3048)
			(end 0.120396 0.3048)
			(stroke
				(width 0.1)
				(type default)
			)
			(layer "F.Fab")
		)
		(fp_line
			(start -0.12065 0.2794)
			(end -0.12065 0.3048)
			(stroke
				(width 0.1)
				(type default)
			)
			(layer "F.Fab")
		)
		(fp_line
			(start 0.120396 0.2794)
			(end -0.12065 0.2794)
			(stroke
				(width 0.1)
				(type default)
			)
			(layer "F.Fab")
		)
		(fp_line
			(start -0.12065 -0.2794)
			(end 0.12065 -0.2794)
			(stroke
				(width 0.1)
				(type default)
			)
			(layer "F.Fab")
		)
		(fp_line
			(start 0.12065 -0.2794)
			(end 0.12065 -0.3048)
			(stroke
				(width 0.1)
				(type default)
			)
			(layer "F.Fab")
		)
		(fp_line
			(start 0.12065 -0.3048)
			(end 0.67945 -0.3048)
			(stroke
				(width 0.1)
				(type default)
			)
			(layer "F.Fab")
		)
		(fp_line
			(start 0.67945 -0.3048)
			(end 0.67945 0.3048)
			(stroke
				(width 0.1)
				(type default)
			)
			(layer "F.Fab")
		)
		(fp_line
			(start -0.67945 -0.305054)
			(end -0.12065 -0.305054)
			(stroke
				(width 0.1)
				(type default)
			)
			(layer "F.Fab")
		)
		(fp_line
			(start -0.12065 -0.305054)
			(end -0.12065 -0.2794)
			(stroke
				(width 0.1)
				(type default)
			)
			(layer "F.Fab")
		)
		(pad "1" smd circle
			(at -0.40005 0 270)
			(size 0 0)
			(layers "F.Cu" "F.Mask" "F.Paste")
			(net "SMB_FAN0_R_SDA")
		)
		(pad "2" smd circle
			(at 0.40005 0 270)
			(size 0 0)
			(layers "F.Cu" "F.Mask" "F.Paste")
			(net "P3V3_AUX")
		)
	)
	(footprint ""
		(layer "F.Cu")
		(at 33.401 -16.51 180)
		(property "Reference" "R5327"
			(at 0 0 180)
			(layer "F.SilkS")
			(hide yes)
			(effects
				(font
					(size 1.27 1.27)
				)
			)
		)
		(property "Value" ""
			(at 0 0 180)
			(layer "F.Fab")
			(effects
				(font
					(size 1.27 1.27)
				)
			)
		)
		(duplicate_pad_numbers_are_jumpers no)
		(fp_line
			(start 0.7874 0.4064)
			(end -0.7874 0.4064)
			(stroke
				(width 0.1524)
				(type default)
			)
			(layer "F.SilkS")
		)
		(fp_line
			(start 0.7874 -0.4064)
			(end 0.7874 0.4064)
			(stroke
				(width 0.1524)
				(type default)
			)
			(layer "F.SilkS")
		)
		(fp_line
			(start -0.7874 0.4064)
			(end -0.7874 -0.4064)
			(stroke
				(width 0.1524)
				(type default)
			)
			(layer "F.SilkS")
		)
		(fp_line
			(start -0.7874 -0.4064)
			(end 0.7874 -0.4064)
			(stroke
				(width 0.1524)
				(type default)
			)
			(layer "F.SilkS")
		)
		(fp_line
			(start 0.67945 0.3048)
			(end 0.120396 0.3048)
			(stroke
				(width 0.1)
				(type default)
			)
			(layer "F.Fab")
		)
		(fp_line
			(start 0.67945 -0.3048)
			(end 0.67945 0.3048)
			(stroke
				(width 0.1)
				(type default)
			)
			(layer "F.Fab")
		)
		(fp_line
			(start 0.12065 -0.2794)
			(end 0.12065 -0.3048)
			(stroke
				(width 0.1)
				(type default)
			)
			(layer "F.Fab")
		)
		(fp_line
			(start 0.12065 -0.3048)
			(end 0.67945 -0.3048)
			(stroke
				(width 0.1)
				(type default)
			)
			(layer "F.Fab")
		)
		(fp_line
			(start 0.120396 0.3048)
			(end 0.120396 0.2794)
			(stroke
				(width 0.1)
				(type default)
			)
			(layer "F.Fab")
		)
		(fp_line
			(start 0.120396 0.2794)
			(end -0.12065 0.2794)
			(stroke
				(width 0.1)
				(type default)
			)
			(layer "F.Fab")
		)
		(fp_line
			(start -0.12065 0.3048)
			(end -0.67945 0.3048)
			(stroke
				(width 0.1)
				(type default)
			)
			(layer "F.Fab")
		)
		(fp_line
			(start -0.12065 0.2794)
			(end -0.12065 0.3048)
			(stroke
				(width 0.1)
				(type default)
			)
			(layer "F.Fab")
		)
		(fp_line
			(start -0.12065 -0.2794)
			(end 0.12065 -0.2794)
			(stroke
				(width 0.1)
				(type default)
			)
			(layer "F.Fab")
		)
		(fp_line
			(start -0.12065 -0.305054)
			(end -0.12065 -0.2794)
			(stroke
				(width 0.1)
				(type default)
			)
			(layer "F.Fab")
		)
		(fp_line
			(start -0.67945 0.3048)
			(end -0.67945 -0.305054)
			(stroke
				(width 0.1)
				(type default)
			)
			(layer "F.Fab")
		)
		(fp_line
			(start -0.67945 -0.305054)
			(end -0.12065 -0.305054)
			(stroke
				(width 0.1)
				(type default)
			)
			(layer "F.Fab")
		)
		(pad "1" smd rect
			(at -0.40005 0)
			(size 0.4572 0.508)
			(layers "F.Cu" "F.Mask" "F.Paste")
			(net "FAN_3_TACH_OL_R")
		)
		(pad "2" smd rect
			(at 0.40005 0)
			(size 0.4572 0.508)
			(layers "F.Cu" "F.Mask" "F.Paste")
			(net "FAN_3_TACH_OL")
		)
	)
	(footprint ""
		(layer "F.Cu")
		(at 48.26 -133.731 180)
		(property "Reference" "R5558"
			(at 0 0 180)
			(layer "F.SilkS")
			(hide yes)
			(effects
				(font
					(size 1.27 1.27)
				)
			)
		)
		(property "Value" ""
			(at 0 0 180)
			(layer "F.Fab")
			(effects
				(font
					(size 1.27 1.27)
				)
			)
		)
		(duplicate_pad_numbers_are_jumpers no)
		(fp_line
			(start 0.7874 0.4064)
			(end -0.7874 0.4064)
			(stroke
				(width 0.1524)
				(type default)
			)
			(layer "F.SilkS")
		)
		(fp_line
			(start 0.7874 -0.4064)
			(end 0.7874 0.4064)
			(stroke
				(width 0.1524)
				(type default)
			)
			(layer "F.SilkS")
		)
		(fp_line
			(start -0.7874 0.4064)
			(end -0.7874 -0.4064)
			(stroke
				(width 0.1524)
				(type default)
			)
			(layer "F.SilkS")
		)
		(fp_line
			(start -0.7874 -0.4064)
			(end 0.7874 -0.4064)
			(stroke
				(width 0.1524)
				(type default)
			)
			(layer "F.SilkS")
		)
		(fp_line
			(start 0.67945 0.3048)
			(end 0.120396 0.3048)
			(stroke
				(width 0.1)
				(type default)
			)
			(layer "F.Fab")
		)
		(fp_line
			(start 0.67945 -0.3048)
			(end 0.67945 0.3048)
			(stroke
				(width 0.1)
				(type default)
			)
			(layer "F.Fab")
		)
		(fp_line
			(start 0.12065 -0.2794)
			(end 0.12065 -0.3048)
			(stroke
				(width 0.1)
				(type default)
			)
			(layer "F.Fab")
		)
		(fp_line
			(start 0.12065 -0.3048)
			(end 0.67945 -0.3048)
			(stroke
				(width 0.1)
				(type default)
			)
			(layer "F.Fab")
		)
		(fp_line
			(start 0.120396 0.3048)
			(end 0.120396 0.2794)
			(stroke
				(width 0.1)
				(type default)
			)
			(layer "F.Fab")
		)
		(fp_line
			(start 0.120396 0.2794)
			(end -0.12065 0.2794)
			(stroke
				(width 0.1)
				(type default)
			)
			(layer "F.Fab")
		)
		(fp_line
			(start -0.12065 0.3048)
			(end -0.67945 0.3048)
			(stroke
				(width 0.1)
				(type default)
			)
			(layer "F.Fab")
		)
		(fp_line
			(start -0.12065 0.2794)
			(end -0.12065 0.3048)
			(stroke
				(width 0.1)
				(type default)
			)
			(layer "F.Fab")
		)
		(fp_line
			(start -0.12065 -0.2794)
			(end 0.12065 -0.2794)
			(stroke
				(width 0.1)
				(type default)
			)
			(layer "F.Fab")
		)
		(fp_line
			(start -0.12065 -0.305054)
			(end -0.12065 -0.2794)
			(stroke
				(width 0.1)
				(type default)
			)
			(layer "F.Fab")
		)
		(fp_line
			(start -0.67945 0.3048)
			(end -0.67945 -0.305054)
			(stroke
				(width 0.1)
				(type default)
			)
			(layer "F.Fab")
		)
		(fp_line
			(start -0.67945 -0.305054)
			(end -0.12065 -0.305054)
			(stroke
				(width 0.1)
				(type default)
			)
			(layer "F.Fab")
		)
		(pad "1" smd circle
			(at -0.40005 0 180)
			(size 0 0)
			(layers "F.Cu" "F.Mask" "F.Paste")
			(net "SMB_PDBV_FAN_SCL")
		)
		(pad "2" smd circle
			(at 0.40005 0 180)
			(size 0 0)
			(layers "F.Cu" "F.Mask" "F.Paste")
			(net "SMB_PDBV_FAN_R_U403_SCL")
		)
	)
	(footprint ""
		(layer "F.Cu")
		(at 25.527 -180.594 180)
		(property "Reference" "C2080"
			(at 0 0 180)
			(layer "F.SilkS")
			(hide yes)
			(effects
				(font
					(size 1.27 1.27)
				)
			)
		)
		(property "Value" ""
			(at 0 0 180)
			(layer "F.Fab")
			(effects
				(font
					(size 1.27 1.27)
				)
			)
		)
		(duplicate_pad_numbers_are_jumpers no)
		(fp_line
			(start 0.7874 0.4064)
			(end -0.7874 0.4064)
			(stroke
				(width 0.1524)
				(type default)
			)
			(layer "F.SilkS")
		)
		(fp_line
			(start 0.7874 -0.4064)
			(end 0.7874 0.4064)
			(stroke
				(width 0.1524)
				(type default)
			)
			(layer "F.SilkS")
		)
		(fp_line
			(start -0.7874 0.4064)
			(end -0.7874 -0.4064)
			(stroke
				(width 0.1524)
				(type default)
			)
			(layer "F.SilkS")
		)
		(fp_line
			(start -0.7874 -0.4064)
			(end 0.7874 -0.4064)
			(stroke
				(width 0.1524)
				(type default)
			)
			(layer "F.SilkS")
		)
		(fp_line
			(start 0.67945 0.3048)
			(end 0.120396 0.3048)
			(stroke
				(width 0.1)
				(type default)
			)
			(layer "F.Fab")
		)
		(fp_line
			(start 0.67945 -0.3048)
			(end 0.67945 0.3048)
			(stroke
				(width 0.1)
				(type default)
			)
			(layer "F.Fab")
		)
		(fp_line
			(start 0.12065 -0.2794)
			(end 0.12065 -0.3048)
			(stroke
				(width 0.1)
				(type default)
			)
			(layer "F.Fab")
		)
		(fp_line
			(start 0.12065 -0.3048)
			(end 0.67945 -0.3048)
			(stroke
				(width 0.1)
				(type default)
			)
			(layer "F.Fab")
		)
		(fp_line
			(start 0.120396 0.3048)
			(end 0.120396 0.2794)
			(stroke
				(width 0.1)
				(type default)
			)
			(layer "F.Fab")
		)
		(fp_line
			(start 0.120396 0.2794)
			(end -0.12065 0.2794)
			(stroke
				(width 0.1)
				(type default)
			)
			(layer "F.Fab")
		)
		(fp_line
			(start -0.12065 0.3048)
			(end -0.67945 0.3048)
			(stroke
				(width 0.1)
				(type default)
			)
			(layer "F.Fab")
		)
		(fp_line
			(start -0.12065 0.2794)
			(end -0.12065 0.3048)
			(stroke
				(width 0.1)
				(type default)
			)
			(layer "F.Fab")
		)
		(fp_line
			(start -0.12065 -0.2794)
			(end 0.12065 -0.2794)
			(stroke
				(width 0.1)
				(type default)
			)
			(layer "F.Fab")
		)
		(fp_line
			(start -0.12065 -0.305054)
			(end -0.12065 -0.2794)
			(stroke
				(width 0.1)
				(type default)
			)
			(layer "F.Fab")
		)
		(fp_line
			(start -0.67945 0.3048)
			(end -0.67945 -0.305054)
			(stroke
				(width 0.1)
				(type default)
			)
			(layer "F.Fab")
		)
		(fp_line
			(start -0.67945 -0.305054)
			(end -0.12065 -0.305054)
			(stroke
				(width 0.1)
				(type default)
			)
			(layer "F.Fab")
		)
		(pad "1" smd circle
			(at -0.40005 0 180)
			(size 0 0)
			(layers "F.Cu" "F.Mask" "F.Paste")
			(net "P52V_FAN_1_BUFF_EN_R")
		)
		(pad "2" smd circle
			(at 0.40005 0 180)
			(size 0 0)
			(layers "F.Cu" "F.Mask" "F.Paste")
			(net "GND")
		)
	)
	(footprint ""
		(layer "F.Cu")
		(at 19.558 -26.924 -90)
		(property "Reference" "R4990"
			(at 0 0 270)
			(layer "F.SilkS")
			(hide yes)
			(effects
				(font
					(size 1.27 1.27)
				)
			)
		)
		(property "Value" ""
			(at 0 0 270)
			(layer "F.Fab")
			(effects
				(font
					(size 1.27 1.27)
				)
			)
		)
		(duplicate_pad_numbers_are_jumpers no)
		(fp_line
			(start -0.7874 0.4064)
			(end -0.7874 -0.4064)
			(stroke
				(width 0.1524)
				(type default)
			)
			(layer "F.SilkS")
		)
		(fp_line
			(start 0.7874 0.4064)
			(end -0.7874 0.4064)
			(stroke
				(width 0.1524)
				(type default)
			)
			(layer "F.SilkS")
		)
		(fp_line
			(start -0.7874 -0.4064)
			(end 0.7874 -0.4064)
			(stroke
				(width 0.1524)
				(type default)
			)
			(layer "F.SilkS")
		)
		(fp_line
			(start 0.7874 -0.4064)
			(end 0.7874 0.4064)
			(stroke
				(width 0.1524)
				(type default)
			)
			(layer "F.SilkS")
		)
		(fp_line
			(start -0.67945 0.3048)
			(end -0.67945 -0.305054)
			(stroke
				(width 0.1)
				(type default)
			)
			(layer "F.Fab")
		)
		(fp_line
			(start -0.12065 0.3048)
			(end -0.67945 0.3048)
			(stroke
				(width 0.1)
				(type default)
			)
			(layer "F.Fab")
		)
		(fp_line
			(start 0.120396 0.3048)
			(end 0.120396 0.2794)
			(stroke
				(width 0.1)
				(type default)
			)
			(layer "F.Fab")
		)
		(fp_line
			(start 0.67945 0.3048)
			(end 0.120396 0.3048)
			(stroke
				(width 0.1)
				(type default)
			)
			(layer "F.Fab")
		)
		(fp_line
			(start -0.12065 0.2794)
			(end -0.12065 0.3048)
			(stroke
				(width 0.1)
				(type default)
			)
			(layer "F.Fab")
		)
		(fp_line
			(start 0.120396 0.2794)
			(end -0.12065 0.2794)
			(stroke
				(width 0.1)
				(type default)
			)
			(layer "F.Fab")
		)
		(fp_line
			(start -0.12065 -0.2794)
			(end 0.12065 -0.2794)
			(stroke
				(width 0.1)
				(type default)
			)
			(layer "F.Fab")
		)
		(fp_line
			(start 0.12065 -0.2794)
			(end 0.12065 -0.3048)
			(stroke
				(width 0.1)
				(type default)
			)
			(layer "F.Fab")
		)
		(fp_line
			(start 0.12065 -0.3048)
			(end 0.67945 -0.3048)
			(stroke
				(width 0.1)
				(type default)
			)
			(layer "F.Fab")
		)
		(fp_line
			(start 0.67945 -0.3048)
			(end 0.67945 0.3048)
			(stroke
				(width 0.1)
				(type default)
			)
			(layer "F.Fab")
		)
		(fp_line
			(start -0.67945 -0.305054)
			(end -0.12065 -0.305054)
			(stroke
				(width 0.1)
				(type default)
			)
			(layer "F.Fab")
		)
		(fp_line
			(start -0.12065 -0.305054)
			(end -0.12065 -0.2794)
			(stroke
				(width 0.1)
				(type default)
			)
			(layer "F.Fab")
		)
		(pad "1" smd circle
			(at -0.40005 0 270)
			(size 0 0)
			(layers "F.Cu" "F.Mask" "F.Paste")
			(net "P3V3_AUX")
		)
		(pad "2" smd circle
			(at 0.40005 0 270)
			(size 0 0)
			(layers "F.Cu" "F.Mask" "F.Paste")
			(net "FAN_4_OK_R_LED")
		)
	)
	(footprint ""
		(layer "F.Cu")
		(at 18.415 -185.166)
		(property "Reference" "C1502"
			(at 0 0 0)
			(layer "F.SilkS")
			(hide yes)
			(effects
				(font
					(size 1.27 1.27)
				)
			)
		)
		(property "Value" ""
			(at 0 0 0)
			(layer "F.Fab")
			(effects
				(font
					(size 1.27 1.27)
				)
			)
		)
		(duplicate_pad_numbers_are_jumpers no)
		(fp_line
			(start -0.7874 -0.4064)
			(end 0.7874 -0.4064)
			(stroke
				(width 0.1524)
				(type default)
			)
			(layer "F.SilkS")
		)
		(fp_line
			(start -0.7874 0.4064)
			(end -0.7874 -0.4064)
			(stroke
				(width 0.1524)
				(type default)
			)
			(layer "F.SilkS")
		)
		(fp_line
			(start 0.7874 -0.4064)
			(end 0.7874 0.4064)
			(stroke
				(width 0.1524)
				(type default)
			)
			(layer "F.SilkS")
		)
		(fp_line
			(start 0.7874 0.4064)
			(end -0.7874 0.4064)
			(stroke
				(width 0.1524)
				(type default)
			)
			(layer "F.SilkS")
		)
		(fp_line
			(start -0.67945 -0.305054)
			(end -0.12065 -0.305054)
			(stroke
				(width 0.1)
				(type default)
			)
			(layer "F.Fab")
		)
		(fp_line
			(start -0.67945 0.3048)
			(end -0.67945 -0.305054)
			(stroke
				(width 0.1)
				(type default)
			)
			(layer "F.Fab")
		)
		(fp_line
			(start -0.12065 -0.305054)
			(end -0.12065 -0.2794)
			(stroke
				(width 0.1)
				(type default)
			)
			(layer "F.Fab")
		)
		(fp_line
			(start -0.12065 -0.2794)
			(end 0.12065 -0.2794)
			(stroke
				(width 0.1)
				(type default)
			)
			(layer "F.Fab")
		)
		(fp_line
			(start -0.12065 0.2794)
			(end -0.12065 0.3048)
			(stroke
				(width 0.1)
				(type default)
			)
			(layer "F.Fab")
		)
		(fp_line
			(start -0.12065 0.3048)
			(end -0.67945 0.3048)
			(stroke
				(width 0.1)
				(type default)
			)
			(layer "F.Fab")
		)
		(fp_line
			(start 0.120396 0.2794)
			(end -0.12065 0.2794)
			(stroke
				(width 0.1)
				(type default)
			)
			(layer "F.Fab")
		)
		(fp_line
			(start 0.120396 0.3048)
			(end 0.120396 0.2794)
			(stroke
				(width 0.1)
				(type default)
			)
			(layer "F.Fab")
		)
		(fp_line
			(start 0.12065 -0.3048)
			(end 0.67945 -0.3048)
			(stroke
				(width 0.1)
				(type default)
			)
			(layer "F.Fab")
		)
		(fp_line
			(start 0.12065 -0.2794)
			(end 0.12065 -0.3048)
			(stroke
				(width 0.1)
				(type default)
			)
			(layer "F.Fab")
		)
		(fp_line
			(start 0.67945 -0.3048)
			(end 0.67945 0.3048)
			(stroke
				(width 0.1)
				(type default)
			)
			(layer "F.Fab")
		)
		(fp_line
			(start 0.67945 0.3048)
			(end 0.120396 0.3048)
			(stroke
				(width 0.1)
				(type default)
			)
			(layer "F.Fab")
		)
		(pad "1" smd circle
			(at -0.40005 0)
			(size 0 0)
			(layers "F.Cu" "F.Mask" "F.Paste")
			(net "P3V3_AUX")
		)
		(pad "2" smd circle
			(at 0.40005 0)
			(size 0 0)
			(layers "F.Cu" "F.Mask" "F.Paste")
			(net "GND")
		)
	)
	(footprint ""
		(layer "F.Cu")
		(at 48.768 -221.234 90)
		(property "Reference" "C2024"
			(at 0 0 90)
			(layer "F.SilkS")
			(hide yes)
			(effects
				(font
					(size 1.27 1.27)
				)
			)
		)
		(property "Value" ""
			(at 0 0 90)
			(layer "F.Fab")
			(effects
				(font
					(size 1.27 1.27)
				)
			)
		)
		(duplicate_pad_numbers_are_jumpers no)
		(fp_line
			(start 1.524 -0.762)
			(end 1.524 0.762)
			(stroke
				(width 0.1524)
				(type default)
			)
			(layer "F.SilkS")
		)
		(fp_line
			(start -1.524 -0.762)
			(end 1.524 -0.762)
			(stroke
				(width 0.1524)
				(type default)
			)
			(layer "F.SilkS")
		)
		(fp_line
			(start 1.524 0.762)
			(end -1.524 0.762)
			(stroke
				(width 0.1524)
				(type default)
			)
			(layer "F.SilkS")
		)
		(fp_line
			(start -1.524 0.762)
			(end -1.524 -0.762)
			(stroke
				(width 0.1524)
				(type default)
			)
			(layer "F.SilkS")
		)
		(fp_line
			(start 1.1049 -0.724916)
			(end -1.1049 -0.724916)
			(stroke
				(width 0.1)
				(type default)
			)
			(layer "F.Fab")
		)
		(fp_line
			(start -1.1049 -0.724916)
			(end -1.1049 0.724916)
			(stroke
				(width 0.1)
				(type default)
			)
			(layer "F.Fab")
		)
		(fp_line
			(start 1.1049 0.724916)
			(end 1.1049 -0.724916)
			(stroke
				(width 0.1)
				(type default)
			)
			(layer "F.Fab")
		)
		(fp_line
			(start -1.1049 0.724916)
			(end 1.1049 0.724916)
			(stroke
				(width 0.1)
				(type default)
			)
			(layer "F.Fab")
		)
		(pad "1" smd rect
			(at -0.889 0 270)
			(size 1.016 1.27)
			(layers "F.Cu" "F.Mask" "F.Paste")
			(net "P12V_LED_FAN1")
		)
		(pad "2" smd rect
			(at 0.889 0 270)
			(size 1.016 1.27)
			(layers "F.Cu" "F.Mask" "F.Paste")
			(net "GND")
		)
	)
	(footprint ""
		(layer "F.Cu")
		(at 33.401 -143.891 -90)
		(property "Reference" "R4788"
			(at 0 0 270)
			(layer "F.SilkS")
			(hide yes)
			(effects
				(font
					(size 1.27 1.27)
				)
			)
		)
		(property "Value" ""
			(at 0 0 270)
			(layer "F.Fab")
			(effects
				(font
					(size 1.27 1.27)
				)
			)
		)
		(duplicate_pad_numbers_are_jumpers no)
		(fp_line
			(start -0.7874 0.4064)
			(end -0.7874 -0.4064)
			(stroke
				(width 0.1524)
				(type default)
			)
			(layer "F.SilkS")
		)
		(fp_line
			(start 0.7874 0.4064)
			(end -0.7874 0.4064)
			(stroke
				(width 0.1524)
				(type default)
			)
			(layer "F.SilkS")
		)
		(fp_line
			(start -0.7874 -0.4064)
			(end 0.7874 -0.4064)
			(stroke
				(width 0.1524)
				(type default)
			)
			(layer "F.SilkS")
		)
		(fp_line
			(start 0.7874 -0.4064)
			(end 0.7874 0.4064)
			(stroke
				(width 0.1524)
				(type default)
			)
			(layer "F.SilkS")
		)
		(fp_line
			(start -0.67945 0.3048)
			(end -0.67945 -0.305054)
			(stroke
				(width 0.1)
				(type default)
			)
			(layer "F.Fab")
		)
		(fp_line
			(start -0.12065 0.3048)
			(end -0.67945 0.3048)
			(stroke
				(width 0.1)
				(type default)
			)
			(layer "F.Fab")
		)
		(fp_line
			(start 0.120396 0.3048)
			(end 0.120396 0.2794)
			(stroke
				(width 0.1)
				(type default)
			)
			(layer "F.Fab")
		)
		(fp_line
			(start 0.67945 0.3048)
			(end 0.120396 0.3048)
			(stroke
				(width 0.1)
				(type default)
			)
			(layer "F.Fab")
		)
		(fp_line
			(start -0.12065 0.2794)
			(end -0.12065 0.3048)
			(stroke
				(width 0.1)
				(type default)
			)
			(layer "F.Fab")
		)
		(fp_line
			(start 0.120396 0.2794)
			(end -0.12065 0.2794)
			(stroke
				(width 0.1)
				(type default)
			)
			(layer "F.Fab")
		)
		(fp_line
			(start -0.12065 -0.2794)
			(end 0.12065 -0.2794)
			(stroke
				(width 0.1)
				(type default)
			)
			(layer "F.Fab")
		)
		(fp_line
			(start 0.12065 -0.2794)
			(end 0.12065 -0.3048)
			(stroke
				(width 0.1)
				(type default)
			)
			(layer "F.Fab")
		)
		(fp_line
			(start 0.12065 -0.3048)
			(end 0.67945 -0.3048)
			(stroke
				(width 0.1)
				(type default)
			)
			(layer "F.Fab")
		)
		(fp_line
			(start 0.67945 -0.3048)
			(end 0.67945 0.3048)
			(stroke
				(width 0.1)
				(type default)
			)
			(layer "F.Fab")
		)
		(fp_line
			(start -0.67945 -0.305054)
			(end -0.12065 -0.305054)
			(stroke
				(width 0.1)
				(type default)
			)
			(layer "F.Fab")
		)
		(fp_line
			(start -0.12065 -0.305054)
			(end -0.12065 -0.2794)
			(stroke
				(width 0.1)
				(type default)
			)
			(layer "F.Fab")
		)
		(pad "1" smd circle
			(at -0.40005 0 270)
			(size 0 0)
			(layers "F.Cu" "F.Mask" "F.Paste")
			(net "SMB_FAN3_R_SDA")
		)
		(pad "2" smd circle
			(at 0.40005 0 270)
			(size 0 0)
			(layers "F.Cu" "F.Mask" "F.Paste")
			(net "SMB_FAN3_SDA")
		)
	)
	(footprint ""
		(layer "F.Cu")
		(at 22.86 -23.368 180)
		(property "Reference" "R360"
			(at 0 0 180)
			(layer "F.SilkS")
			(hide yes)
			(effects
				(font
					(size 1.27 1.27)
				)
			)
		)
		(property "Value" ""
			(at 0 0 180)
			(layer "F.Fab")
			(effects
				(font
					(size 1.27 1.27)
				)
			)
		)
		(duplicate_pad_numbers_are_jumpers no)
		(fp_line
			(start 0.7874 0.4064)
			(end -0.7874 0.4064)
			(stroke
				(width 0.1524)
				(type default)
			)
			(layer "F.SilkS")
		)
		(fp_line
			(start 0.7874 -0.4064)
			(end 0.7874 0.4064)
			(stroke
				(width 0.1524)
				(type default)
			)
			(layer "F.SilkS")
		)
		(fp_line
			(start -0.7874 0.4064)
			(end -0.7874 -0.4064)
			(stroke
				(width 0.1524)
				(type default)
			)
			(layer "F.SilkS")
		)
		(fp_line
			(start -0.7874 -0.4064)
			(end 0.7874 -0.4064)
			(stroke
				(width 0.1524)
				(type default)
			)
			(layer "F.SilkS")
		)
		(fp_line
			(start 0.67945 0.3048)
			(end 0.120396 0.3048)
			(stroke
				(width 0.1)
				(type default)
			)
			(layer "F.Fab")
		)
		(fp_line
			(start 0.67945 -0.3048)
			(end 0.67945 0.3048)
			(stroke
				(width 0.1)
				(type default)
			)
			(layer "F.Fab")
		)
		(fp_line
			(start 0.12065 -0.2794)
			(end 0.12065 -0.3048)
			(stroke
				(width 0.1)
				(type default)
			)
			(layer "F.Fab")
		)
		(fp_line
			(start 0.12065 -0.3048)
			(end 0.67945 -0.3048)
			(stroke
				(width 0.1)
				(type default)
			)
			(layer "F.Fab")
		)
		(fp_line
			(start 0.120396 0.3048)
			(end 0.120396 0.2794)
			(stroke
				(width 0.1)
				(type default)
			)
			(layer "F.Fab")
		)
		(fp_line
			(start 0.120396 0.2794)
			(end -0.12065 0.2794)
			(stroke
				(width 0.1)
				(type default)
			)
			(layer "F.Fab")
		)
		(fp_line
			(start -0.12065 0.3048)
			(end -0.67945 0.3048)
			(stroke
				(width 0.1)
				(type default)
			)
			(layer "F.Fab")
		)
		(fp_line
			(start -0.12065 0.2794)
			(end -0.12065 0.3048)
			(stroke
				(width 0.1)
				(type default)
			)
			(layer "F.Fab")
		)
		(fp_line
			(start -0.12065 -0.2794)
			(end 0.12065 -0.2794)
			(stroke
				(width 0.1)
				(type default)
			)
			(layer "F.Fab")
		)
		(fp_line
			(start -0.12065 -0.305054)
			(end -0.12065 -0.2794)
			(stroke
				(width 0.1)
				(type default)
			)
			(layer "F.Fab")
		)
		(fp_line
			(start -0.67945 0.3048)
			(end -0.67945 -0.305054)
			(stroke
				(width 0.1)
				(type default)
			)
			(layer "F.Fab")
		)
		(fp_line
			(start -0.67945 -0.305054)
			(end -0.12065 -0.305054)
			(stroke
				(width 0.1)
				(type default)
			)
			(layer "F.Fab")
		)
		(pad "1" smd circle
			(at -0.40005 0 180)
			(size 0 0)
			(layers "F.Cu" "F.Mask" "F.Paste")
			(net "P3V3_AUX")
		)
		(pad "2" smd circle
			(at 0.40005 0 180)
			(size 0 0)
			(layers "F.Cu" "F.Mask" "F.Paste")
			(net "FAN_3_PWM")
		)
	)
	(footprint ""
		(layer "F.Cu")
		(at 6.477 -167.64)
		(property "Reference" "R102"
			(at 0 0 0)
			(layer "F.SilkS")
			(hide yes)
			(effects
				(font
					(size 1.27 1.27)
				)
			)
		)
		(property "Value" ""
			(at 0 0 0)
			(layer "F.Fab")
			(effects
				(font
					(size 1.27 1.27)
				)
			)
		)
		(duplicate_pad_numbers_are_jumpers no)
		(fp_line
			(start -0.7874 -0.4064)
			(end 0.7874 -0.4064)
			(stroke
				(width 0.1524)
				(type default)
			)
			(layer "F.SilkS")
		)
		(fp_line
			(start -0.7874 0.4064)
			(end -0.7874 -0.4064)
			(stroke
				(width 0.1524)
				(type default)
			)
			(layer "F.SilkS")
		)
		(fp_line
			(start 0.7874 -0.4064)
			(end 0.7874 0.4064)
			(stroke
				(width 0.1524)
				(type default)
			)
			(layer "F.SilkS")
		)
		(fp_line
			(start 0.7874 0.4064)
			(end -0.7874 0.4064)
			(stroke
				(width 0.1524)
				(type default)
			)
			(layer "F.SilkS")
		)
		(fp_line
			(start -0.67945 -0.305054)
			(end -0.12065 -0.305054)
			(stroke
				(width 0.1)
				(type default)
			)
			(layer "F.Fab")
		)
		(fp_line
			(start -0.67945 0.3048)
			(end -0.67945 -0.305054)
			(stroke
				(width 0.1)
				(type default)
			)
			(layer "F.Fab")
		)
		(fp_line
			(start -0.12065 -0.305054)
			(end -0.12065 -0.2794)
			(stroke
				(width 0.1)
				(type default)
			)
			(layer "F.Fab")
		)
		(fp_line
			(start -0.12065 -0.2794)
			(end 0.12065 -0.2794)
			(stroke
				(width 0.1)
				(type default)
			)
			(layer "F.Fab")
		)
		(fp_line
			(start -0.12065 0.2794)
			(end -0.12065 0.3048)
			(stroke
				(width 0.1)
				(type default)
			)
			(layer "F.Fab")
		)
		(fp_line
			(start -0.12065 0.3048)
			(end -0.67945 0.3048)
			(stroke
				(width 0.1)
				(type default)
			)
			(layer "F.Fab")
		)
		(fp_line
			(start 0.120396 0.2794)
			(end -0.12065 0.2794)
			(stroke
				(width 0.1)
				(type default)
			)
			(layer "F.Fab")
		)
		(fp_line
			(start 0.120396 0.3048)
			(end 0.120396 0.2794)
			(stroke
				(width 0.1)
				(type default)
			)
			(layer "F.Fab")
		)
		(fp_line
			(start 0.12065 -0.3048)
			(end 0.67945 -0.3048)
			(stroke
				(width 0.1)
				(type default)
			)
			(layer "F.Fab")
		)
		(fp_line
			(start 0.12065 -0.2794)
			(end 0.12065 -0.3048)
			(stroke
				(width 0.1)
				(type default)
			)
			(layer "F.Fab")
		)
		(fp_line
			(start 0.67945 -0.3048)
			(end 0.67945 0.3048)
			(stroke
				(width 0.1)
				(type default)
			)
			(layer "F.Fab")
		)
		(fp_line
			(start 0.67945 0.3048)
			(end 0.120396 0.3048)
			(stroke
				(width 0.1)
				(type default)
			)
			(layer "F.Fab")
		)
		(pad "1" smd circle
			(at -0.40005 0)
			(size 0 0)
			(layers "F.Cu" "F.Mask" "F.Paste")
			(net "P3V3_AUX")
		)
		(pad "2" smd circle
			(at 0.40005 0)
			(size 0 0)
			(layers "F.Cu" "F.Mask" "F.Paste")
			(net "FAN_3_PRSNT_BUF_R_N")
		)
	)
	(footprint ""
		(layer "F.Cu")
		(at 19.177 -32.004 90)
		(property "Reference" "C2017"
			(at 0 0 90)
			(layer "F.SilkS")
			(hide yes)
			(effects
				(font
					(size 1.27 1.27)
				)
			)
		)
		(property "Value" ""
			(at 0 0 90)
			(layer "F.Fab")
			(effects
				(font
					(size 1.27 1.27)
				)
			)
		)
		(duplicate_pad_numbers_are_jumpers no)
		(fp_line
			(start 0.7874 -0.4064)
			(end 0.7874 0.4064)
			(stroke
				(width 0.1524)
				(type default)
			)
			(layer "F.SilkS")
		)
		(fp_line
			(start -0.7874 -0.4064)
			(end 0.7874 -0.4064)
			(stroke
				(width 0.1524)
				(type default)
			)
			(layer "F.SilkS")
		)
		(fp_line
			(start 0.7874 0.4064)
			(end -0.7874 0.4064)
			(stroke
				(width 0.1524)
				(type default)
			)
			(layer "F.SilkS")
		)
		(fp_line
			(start -0.7874 0.4064)
			(end -0.7874 -0.4064)
			(stroke
				(width 0.1524)
				(type default)
			)
			(layer "F.SilkS")
		)
		(fp_line
			(start -0.12065 -0.305054)
			(end -0.12065 -0.2794)
			(stroke
				(width 0.1)
				(type default)
			)
			(layer "F.Fab")
		)
		(fp_line
			(start -0.67945 -0.305054)
			(end -0.12065 -0.305054)
			(stroke
				(width 0.1)
				(type default)
			)
			(layer "F.Fab")
		)
		(fp_line
			(start 0.67945 -0.3048)
			(end 0.67945 0.3048)
			(stroke
				(width 0.1)
				(type default)
			)
			(layer "F.Fab")
		)
		(fp_line
			(start 0.12065 -0.3048)
			(end 0.67945 -0.3048)
			(stroke
				(width 0.1)
				(type default)
			)
			(layer "F.Fab")
		)
		(fp_line
			(start 0.12065 -0.2794)
			(end 0.12065 -0.3048)
			(stroke
				(width 0.1)
				(type default)
			)
			(layer "F.Fab")
		)
		(fp_line
			(start -0.12065 -0.2794)
			(end 0.12065 -0.2794)
			(stroke
				(width 0.1)
				(type default)
			)
			(layer "F.Fab")
		)
		(fp_line
			(start 0.120396 0.2794)
			(end -0.12065 0.2794)
			(stroke
				(width 0.1)
				(type default)
			)
			(layer "F.Fab")
		)
		(fp_line
			(start -0.12065 0.2794)
			(end -0.12065 0.3048)
			(stroke
				(width 0.1)
				(type default)
			)
			(layer "F.Fab")
		)
		(fp_line
			(start 0.67945 0.3048)
			(end 0.120396 0.3048)
			(stroke
				(width 0.1)
				(type default)
			)
			(layer "F.Fab")
		)
		(fp_line
			(start 0.120396 0.3048)
			(end 0.120396 0.2794)
			(stroke
				(width 0.1)
				(type default)
			)
			(layer "F.Fab")
		)
		(fp_line
			(start -0.12065 0.3048)
			(end -0.67945 0.3048)
			(stroke
				(width 0.1)
				(type default)
			)
			(layer "F.Fab")
		)
		(fp_line
			(start -0.67945 0.3048)
			(end -0.67945 -0.305054)
			(stroke
				(width 0.1)
				(type default)
			)
			(layer "F.Fab")
		)
		(pad "1" smd circle
			(at -0.40005 0 90)
			(size 0 0)
			(layers "F.Cu" "F.Mask" "F.Paste")
			(net "FAN_4_TACH_OL_R")
		)
		(pad "2" smd circle
			(at 0.40005 0 90)
			(size 0 0)
			(layers "F.Cu" "F.Mask" "F.Paste")
			(net "GND")
		)
	)
	(footprint ""
		(layer "F.Cu")
		(at 27.305 -143.891 -90)
		(property "Reference" "R4790"
			(at 0 0 270)
			(layer "F.SilkS")
			(hide yes)
			(effects
				(font
					(size 1.27 1.27)
				)
			)
		)
		(property "Value" ""
			(at 0 0 270)
			(layer "F.Fab")
			(effects
				(font
					(size 1.27 1.27)
				)
			)
		)
		(duplicate_pad_numbers_are_jumpers no)
		(fp_line
			(start -0.7874 0.4064)
			(end -0.7874 -0.4064)
			(stroke
				(width 0.1524)
				(type default)
			)
			(layer "F.SilkS")
		)
		(fp_line
			(start 0.7874 0.4064)
			(end -0.7874 0.4064)
			(stroke
				(width 0.1524)
				(type default)
			)
			(layer "F.SilkS")
		)
		(fp_line
			(start -0.7874 -0.4064)
			(end 0.7874 -0.4064)
			(stroke
				(width 0.1524)
				(type default)
			)
			(layer "F.SilkS")
		)
		(fp_line
			(start 0.7874 -0.4064)
			(end 0.7874 0.4064)
			(stroke
				(width 0.1524)
				(type default)
			)
			(layer "F.SilkS")
		)
		(fp_line
			(start -0.67945 0.3048)
			(end -0.67945 -0.305054)
			(stroke
				(width 0.1)
				(type default)
			)
			(layer "F.Fab")
		)
		(fp_line
			(start -0.12065 0.3048)
			(end -0.67945 0.3048)
			(stroke
				(width 0.1)
				(type default)
			)
			(layer "F.Fab")
		)
		(fp_line
			(start 0.120396 0.3048)
			(end 0.120396 0.2794)
			(stroke
				(width 0.1)
				(type default)
			)
			(layer "F.Fab")
		)
		(fp_line
			(start 0.67945 0.3048)
			(end 0.120396 0.3048)
			(stroke
				(width 0.1)
				(type default)
			)
			(layer "F.Fab")
		)
		(fp_line
			(start -0.12065 0.2794)
			(end -0.12065 0.3048)
			(stroke
				(width 0.1)
				(type default)
			)
			(layer "F.Fab")
		)
		(fp_line
			(start 0.120396 0.2794)
			(end -0.12065 0.2794)
			(stroke
				(width 0.1)
				(type default)
			)
			(layer "F.Fab")
		)
		(fp_line
			(start -0.12065 -0.2794)
			(end 0.12065 -0.2794)
			(stroke
				(width 0.1)
				(type default)
			)
			(layer "F.Fab")
		)
		(fp_line
			(start 0.12065 -0.2794)
			(end 0.12065 -0.3048)
			(stroke
				(width 0.1)
				(type default)
			)
			(layer "F.Fab")
		)
		(fp_line
			(start 0.12065 -0.3048)
			(end 0.67945 -0.3048)
			(stroke
				(width 0.1)
				(type default)
			)
			(layer "F.Fab")
		)
		(fp_line
			(start 0.67945 -0.3048)
			(end 0.67945 0.3048)
			(stroke
				(width 0.1)
				(type default)
			)
			(layer "F.Fab")
		)
		(fp_line
			(start -0.67945 -0.305054)
			(end -0.12065 -0.305054)
			(stroke
				(width 0.1)
				(type default)
			)
			(layer "F.Fab")
		)
		(fp_line
			(start -0.12065 -0.305054)
			(end -0.12065 -0.2794)
			(stroke
				(width 0.1)
				(type default)
			)
			(layer "F.Fab")
		)
		(pad "1" smd circle
			(at -0.40005 0 270)
			(size 0 0)
			(layers "F.Cu" "F.Mask" "F.Paste")
			(net "SMB_FAN1_R_SCL")
		)
		(pad "2" smd circle
			(at 0.40005 0 270)
			(size 0 0)
			(layers "F.Cu" "F.Mask" "F.Paste")
			(net "SMB_FAN1_SCL")
		)
	)
	(footprint ""
		(layer "F.Cu")
		(at 18.796 -210.439 180)
		(property "Reference" "R5317"
			(at 0 0 180)
			(layer "F.SilkS")
			(hide yes)
			(effects
				(font
					(size 1.27 1.27)
				)
			)
		)
		(property "Value" ""
			(at 0 0 180)
			(layer "F.Fab")
			(effects
				(font
					(size 1.27 1.27)
				)
			)
		)
		(duplicate_pad_numbers_are_jumpers no)
		(fp_line
			(start 1.2954 0.5842)
			(end -1.2954 0.5842)
			(stroke
				(width 0.1524)
				(type default)
			)
			(layer "F.SilkS")
		)
		(fp_line
			(start 1.2954 -0.5842)
			(end 1.2954 0.5842)
			(stroke
				(width 0.1524)
				(type default)
			)
			(layer "F.SilkS")
		)
		(fp_line
			(start -1.2954 0.5842)
			(end -1.2954 -0.5842)
			(stroke
				(width 0.1524)
				(type default)
			)
			(layer "F.SilkS")
		)
		(fp_line
			(start -1.2954 -0.5842)
			(end 1.2954 -0.5842)
			(stroke
				(width 0.1524)
				(type default)
			)
			(layer "F.SilkS")
		)
		(fp_line
			(start 1.1938 0.4064)
			(end 0.8636 0.4064)
			(stroke
				(width 0.1)
				(type default)
			)
			(layer "F.Fab")
		)
		(fp_line
			(start 1.1938 -0.406654)
			(end 1.1938 0.4064)
			(stroke
				(width 0.1)
				(type default)
			)
			(layer "F.Fab")
		)
		(fp_line
			(start 0.8636 0.4572)
			(end -0.8636 0.4572)
			(stroke
				(width 0.1)
				(type default)
			)
			(layer "F.Fab")
		)
		(fp_line
			(start 0.8636 0.4064)
			(end 0.8636 0.4572)
			(stroke
				(width 0.1)
				(type default)
			)
			(layer "F.Fab")
		)
		(fp_line
			(start 0.8636 -0.406654)
			(end 1.1938 -0.406654)
			(stroke
				(width 0.1)
				(type default)
			)
			(layer "F.Fab")
		)
		(fp_line
			(start 0.8636 -0.4572)
			(end 0.8636 -0.406654)
			(stroke
				(width 0.1)
				(type default)
			)
			(layer "F.Fab")
		)
		(fp_line
			(start -0.8636 0.4572)
			(end -0.8636 0.4318)
			(stroke
				(width 0.1)
				(type default)
			)
			(layer "F.Fab")
		)
		(fp_line
			(start -0.8636 0.4318)
			(end -0.8636 0.4064)
			(stroke
				(width 0.1)
				(type default)
			)
			(layer "F.Fab")
		)
		(fp_line
			(start -0.8636 0.4064)
			(end -1.1938 0.4064)
			(stroke
				(width 0.1)
				(type default)
			)
			(layer "F.Fab")
		)
		(fp_line
			(start -0.8636 -0.406654)
			(end -0.8636 -0.4572)
			(stroke
				(width 0.1)
				(type default)
			)
			(layer "F.Fab")
		)
		(fp_line
			(start -0.8636 -0.4572)
			(end 0.8636 -0.4572)
			(stroke
				(width 0.1)
				(type default)
			)
			(layer "F.Fab")
		)
		(fp_line
			(start -1.1938 0.4064)
			(end -1.1938 -0.406654)
			(stroke
				(width 0.1)
				(type default)
			)
			(layer "F.Fab")
		)
		(fp_line
			(start -1.1938 -0.406654)
			(end -0.8636 -0.406654)
			(stroke
				(width 0.1)
				(type default)
			)
			(layer "F.Fab")
		)
		(pad "1" smd rect
			(at -0.7366 0 90)
			(size 0.7112 0.8128)
			(layers "F.Cu" "F.Mask" "F.Paste")
			(net "P52V_FAN_6")
		)
		(pad "2" smd rect
			(at 0.7366 0 90)
			(size 0.7112 0.8128)
			(layers "F.Cu" "F.Mask" "F.Paste")
			(net "FAN_6_TACH_OL_R")
		)
	)
	(footprint ""
		(layer "F.Cu")
		(at 5.969 -31.496)
		(property "Reference" "R5704"
			(at 0 0 0)
			(layer "F.SilkS")
			(hide yes)
			(effects
				(font
					(size 1.27 1.27)
				)
			)
		)
		(property "Value" ""
			(at 0 0 0)
			(layer "F.Fab")
			(effects
				(font
					(size 1.27 1.27)
				)
			)
		)
		(duplicate_pad_numbers_are_jumpers no)
		(fp_line
			(start -0.7874 -0.4064)
			(end 0.7874 -0.4064)
			(stroke
				(width 0.1524)
				(type default)
			)
			(layer "F.SilkS")
		)
		(fp_line
			(start -0.7874 0.4064)
			(end -0.7874 -0.4064)
			(stroke
				(width 0.1524)
				(type default)
			)
			(layer "F.SilkS")
		)
		(fp_line
			(start 0.7874 -0.4064)
			(end 0.7874 0.4064)
			(stroke
				(width 0.1524)
				(type default)
			)
			(layer "F.SilkS")
		)
		(fp_line
			(start 0.7874 0.4064)
			(end -0.7874 0.4064)
			(stroke
				(width 0.1524)
				(type default)
			)
			(layer "F.SilkS")
		)
		(fp_line
			(start -0.67945 -0.305054)
			(end -0.12065 -0.305054)
			(stroke
				(width 0.1)
				(type default)
			)
			(layer "F.Fab")
		)
		(fp_line
			(start -0.67945 0.3048)
			(end -0.67945 -0.305054)
			(stroke
				(width 0.1)
				(type default)
			)
			(layer "F.Fab")
		)
		(fp_line
			(start -0.12065 -0.305054)
			(end -0.12065 -0.2794)
			(stroke
				(width 0.1)
				(type default)
			)
			(layer "F.Fab")
		)
		(fp_line
			(start -0.12065 -0.2794)
			(end 0.12065 -0.2794)
			(stroke
				(width 0.1)
				(type default)
			)
			(layer "F.Fab")
		)
		(fp_line
			(start -0.12065 0.2794)
			(end -0.12065 0.3048)
			(stroke
				(width 0.1)
				(type default)
			)
			(layer "F.Fab")
		)
		(fp_line
			(start -0.12065 0.3048)
			(end -0.67945 0.3048)
			(stroke
				(width 0.1)
				(type default)
			)
			(layer "F.Fab")
		)
		(fp_line
			(start 0.120396 0.2794)
			(end -0.12065 0.2794)
			(stroke
				(width 0.1)
				(type default)
			)
			(layer "F.Fab")
		)
		(fp_line
			(start 0.120396 0.3048)
			(end 0.120396 0.2794)
			(stroke
				(width 0.1)
				(type default)
			)
			(layer "F.Fab")
		)
		(fp_line
			(start 0.12065 -0.3048)
			(end 0.67945 -0.3048)
			(stroke
				(width 0.1)
				(type default)
			)
			(layer "F.Fab")
		)
		(fp_line
			(start 0.12065 -0.2794)
			(end 0.12065 -0.3048)
			(stroke
				(width 0.1)
				(type default)
			)
			(layer "F.Fab")
		)
		(fp_line
			(start 0.67945 -0.3048)
			(end 0.67945 0.3048)
			(stroke
				(width 0.1)
				(type default)
			)
			(layer "F.Fab")
		)
		(fp_line
			(start 0.67945 0.3048)
			(end 0.120396 0.3048)
			(stroke
				(width 0.1)
				(type default)
			)
			(layer "F.Fab")
		)
		(pad "1" smd rect
			(at -0.40005 0 180)
			(size 0.4572 0.508)
			(layers "F.Cu" "F.Mask" "F.Paste")
			(net "P12V_LED_R_FAN4")
		)
		(pad "2" smd rect
			(at 0.40005 0 180)
			(size 0.4572 0.508)
			(layers "F.Cu" "F.Mask" "F.Paste")
			(net "P12V_LED_R1_FAN4")
		)
	)
	(footprint ""
		(layer "F.Cu")
		(at 14.859 -123.317)
		(property "Reference" "R5610"
			(at 0 0 0)
			(layer "F.SilkS")
			(hide yes)
			(effects
				(font
					(size 1.27 1.27)
				)
			)
		)
		(property "Value" ""
			(at 0 0 0)
			(layer "F.Fab")
			(effects
				(font
					(size 1.27 1.27)
				)
			)
		)
		(duplicate_pad_numbers_are_jumpers no)
		(fp_line
			(start -0.7874 -0.4064)
			(end 0.7874 -0.4064)
			(stroke
				(width 0.1524)
				(type default)
			)
			(layer "F.SilkS")
		)
		(fp_line
			(start -0.7874 0.4064)
			(end -0.7874 -0.4064)
			(stroke
				(width 0.1524)
				(type default)
			)
			(layer "F.SilkS")
		)
		(fp_line
			(start 0.7874 -0.4064)
			(end 0.7874 0.4064)
			(stroke
				(width 0.1524)
				(type default)
			)
			(layer "F.SilkS")
		)
		(fp_line
			(start 0.7874 0.4064)
			(end -0.7874 0.4064)
			(stroke
				(width 0.1524)
				(type default)
			)
			(layer "F.SilkS")
		)
		(fp_line
			(start -0.67945 -0.305054)
			(end -0.12065 -0.305054)
			(stroke
				(width 0.1)
				(type default)
			)
			(layer "F.Fab")
		)
		(fp_line
			(start -0.67945 0.3048)
			(end -0.67945 -0.305054)
			(stroke
				(width 0.1)
				(type default)
			)
			(layer "F.Fab")
		)
		(fp_line
			(start -0.12065 -0.305054)
			(end -0.12065 -0.2794)
			(stroke
				(width 0.1)
				(type default)
			)
			(layer "F.Fab")
		)
		(fp_line
			(start -0.12065 -0.2794)
			(end 0.12065 -0.2794)
			(stroke
				(width 0.1)
				(type default)
			)
			(layer "F.Fab")
		)
		(fp_line
			(start -0.12065 0.2794)
			(end -0.12065 0.3048)
			(stroke
				(width 0.1)
				(type default)
			)
			(layer "F.Fab")
		)
		(fp_line
			(start -0.12065 0.3048)
			(end -0.67945 0.3048)
			(stroke
				(width 0.1)
				(type default)
			)
			(layer "F.Fab")
		)
		(fp_line
			(start 0.120396 0.2794)
			(end -0.12065 0.2794)
			(stroke
				(width 0.1)
				(type default)
			)
			(layer "F.Fab")
		)
		(fp_line
			(start 0.120396 0.3048)
			(end 0.120396 0.2794)
			(stroke
				(width 0.1)
				(type default)
			)
			(layer "F.Fab")
		)
		(fp_line
			(start 0.12065 -0.3048)
			(end 0.67945 -0.3048)
			(stroke
				(width 0.1)
				(type default)
			)
			(layer "F.Fab")
		)
		(fp_line
			(start 0.12065 -0.2794)
			(end 0.12065 -0.3048)
			(stroke
				(width 0.1)
				(type default)
			)
			(layer "F.Fab")
		)
		(fp_line
			(start 0.67945 -0.3048)
			(end 0.67945 0.3048)
			(stroke
				(width 0.1)
				(type default)
			)
			(layer "F.Fab")
		)
		(fp_line
			(start 0.67945 0.3048)
			(end 0.120396 0.3048)
			(stroke
				(width 0.1)
				(type default)
			)
			(layer "F.Fab")
		)
		(pad "1" smd rect
			(at -0.40005 0 180)
			(size 0.4572 0.508)
			(layers "F.Cu" "F.Mask" "F.Paste")
			(net "FAN_4_TACH_IL")
		)
		(pad "2" smd rect
			(at 0.40005 0 180)
			(size 0.4572 0.508)
			(layers "F.Cu" "F.Mask" "F.Paste")
			(net "FAN_4_TACH_IL_R1")
		)
	)
	(footprint ""
		(layer "F.Cu")
		(at 32.004 -110.49)
		(property "Reference" "R5399"
			(at 0 0 0)
			(layer "F.SilkS")
			(hide yes)
			(effects
				(font
					(size 1.27 1.27)
				)
			)
		)
		(property "Value" ""
			(at 0 0 0)
			(layer "F.Fab")
			(effects
				(font
					(size 1.27 1.27)
				)
			)
		)
		(duplicate_pad_numbers_are_jumpers no)
		(fp_line
			(start -0.7874 -0.4064)
			(end 0.7874 -0.4064)
			(stroke
				(width 0.1524)
				(type default)
			)
			(layer "F.SilkS")
		)
		(fp_line
			(start -0.7874 0.4064)
			(end -0.7874 -0.4064)
			(stroke
				(width 0.1524)
				(type default)
			)
			(layer "F.SilkS")
		)
		(fp_line
			(start 0.7874 -0.4064)
			(end 0.7874 0.4064)
			(stroke
				(width 0.1524)
				(type default)
			)
			(layer "F.SilkS")
		)
		(fp_line
			(start 0.7874 0.4064)
			(end -0.7874 0.4064)
			(stroke
				(width 0.1524)
				(type default)
			)
			(layer "F.SilkS")
		)
		(fp_line
			(start -0.67945 -0.305054)
			(end -0.12065 -0.305054)
			(stroke
				(width 0.1)
				(type default)
			)
			(layer "F.Fab")
		)
		(fp_line
			(start -0.67945 0.3048)
			(end -0.67945 -0.305054)
			(stroke
				(width 0.1)
				(type default)
			)
			(layer "F.Fab")
		)
		(fp_line
			(start -0.12065 -0.305054)
			(end -0.12065 -0.2794)
			(stroke
				(width 0.1)
				(type default)
			)
			(layer "F.Fab")
		)
		(fp_line
			(start -0.12065 -0.2794)
			(end 0.12065 -0.2794)
			(stroke
				(width 0.1)
				(type default)
			)
			(layer "F.Fab")
		)
		(fp_line
			(start -0.12065 0.2794)
			(end -0.12065 0.3048)
			(stroke
				(width 0.1)
				(type default)
			)
			(layer "F.Fab")
		)
		(fp_line
			(start -0.12065 0.3048)
			(end -0.67945 0.3048)
			(stroke
				(width 0.1)
				(type default)
			)
			(layer "F.Fab")
		)
		(fp_line
			(start 0.120396 0.2794)
			(end -0.12065 0.2794)
			(stroke
				(width 0.1)
				(type default)
			)
			(layer "F.Fab")
		)
		(fp_line
			(start 0.120396 0.3048)
			(end 0.120396 0.2794)
			(stroke
				(width 0.1)
				(type default)
			)
			(layer "F.Fab")
		)
		(fp_line
			(start 0.12065 -0.3048)
			(end 0.67945 -0.3048)
			(stroke
				(width 0.1)
				(type default)
			)
			(layer "F.Fab")
		)
		(fp_line
			(start 0.12065 -0.2794)
			(end 0.12065 -0.3048)
			(stroke
				(width 0.1)
				(type default)
			)
			(layer "F.Fab")
		)
		(fp_line
			(start 0.67945 -0.3048)
			(end 0.67945 0.3048)
			(stroke
				(width 0.1)
				(type default)
			)
			(layer "F.Fab")
		)
		(fp_line
			(start 0.67945 0.3048)
			(end 0.120396 0.3048)
			(stroke
				(width 0.1)
				(type default)
			)
			(layer "F.Fab")
		)
		(pad "1" smd circle
			(at -0.40005 0)
			(size 0 0)
			(layers "F.Cu" "F.Mask" "F.Paste")
			(net "P3V3_AUX")
		)
		(pad "2" smd circle
			(at 0.40005 0)
			(size 0 0)
			(layers "F.Cu" "F.Mask" "F.Paste")
			(net "FAN_2_FAIL_R_LED")
		)
	)
	(footprint ""
		(layer "F.Cu")
		(at 22.479 -298.45 90)
		(property "Reference" "R336"
			(at 0 0 90)
			(layer "F.SilkS")
			(hide yes)
			(effects
				(font
					(size 1.27 1.27)
				)
			)
		)
		(property "Value" ""
			(at 0 0 90)
			(layer "F.Fab")
			(effects
				(font
					(size 1.27 1.27)
				)
			)
		)
		(duplicate_pad_numbers_are_jumpers no)
		(fp_line
			(start 0.7874 -0.4064)
			(end 0.7874 0.4064)
			(stroke
				(width 0.1524)
				(type default)
			)
			(layer "F.SilkS")
		)
		(fp_line
			(start -0.7874 -0.4064)
			(end 0.7874 -0.4064)
			(stroke
				(width 0.1524)
				(type default)
			)
			(layer "F.SilkS")
		)
		(fp_line
			(start 0.7874 0.4064)
			(end -0.7874 0.4064)
			(stroke
				(width 0.1524)
				(type default)
			)
			(layer "F.SilkS")
		)
		(fp_line
			(start -0.7874 0.4064)
			(end -0.7874 -0.4064)
			(stroke
				(width 0.1524)
				(type default)
			)
			(layer "F.SilkS")
		)
		(fp_line
			(start -0.12065 -0.305054)
			(end -0.12065 -0.2794)
			(stroke
				(width 0.1)
				(type default)
			)
			(layer "F.Fab")
		)
		(fp_line
			(start -0.67945 -0.305054)
			(end -0.12065 -0.305054)
			(stroke
				(width 0.1)
				(type default)
			)
			(layer "F.Fab")
		)
		(fp_line
			(start 0.67945 -0.3048)
			(end 0.67945 0.3048)
			(stroke
				(width 0.1)
				(type default)
			)
			(layer "F.Fab")
		)
		(fp_line
			(start 0.12065 -0.3048)
			(end 0.67945 -0.3048)
			(stroke
				(width 0.1)
				(type default)
			)
			(layer "F.Fab")
		)
		(fp_line
			(start 0.12065 -0.2794)
			(end 0.12065 -0.3048)
			(stroke
				(width 0.1)
				(type default)
			)
			(layer "F.Fab")
		)
		(fp_line
			(start -0.12065 -0.2794)
			(end 0.12065 -0.2794)
			(stroke
				(width 0.1)
				(type default)
			)
			(layer "F.Fab")
		)
		(fp_line
			(start 0.120396 0.2794)
			(end -0.12065 0.2794)
			(stroke
				(width 0.1)
				(type default)
			)
			(layer "F.Fab")
		)
		(fp_line
			(start -0.12065 0.2794)
			(end -0.12065 0.3048)
			(stroke
				(width 0.1)
				(type default)
			)
			(layer "F.Fab")
		)
		(fp_line
			(start 0.67945 0.3048)
			(end 0.120396 0.3048)
			(stroke
				(width 0.1)
				(type default)
			)
			(layer "F.Fab")
		)
		(fp_line
			(start 0.120396 0.3048)
			(end 0.120396 0.2794)
			(stroke
				(width 0.1)
				(type default)
			)
			(layer "F.Fab")
		)
		(fp_line
			(start -0.12065 0.3048)
			(end -0.67945 0.3048)
			(stroke
				(width 0.1)
				(type default)
			)
			(layer "F.Fab")
		)
		(fp_line
			(start -0.67945 0.3048)
			(end -0.67945 -0.305054)
			(stroke
				(width 0.1)
				(type default)
			)
			(layer "F.Fab")
		)
		(pad "1" smd circle
			(at -0.40005 0 90)
			(size 0 0)
			(layers "F.Cu" "F.Mask" "F.Paste")
			(net "P3V3_AUX")
		)
		(pad "2" smd circle
			(at 0.40005 0 90)
			(size 0 0)
			(layers "F.Cu" "F.Mask" "F.Paste")
			(net "FAN_0_PWM")
		)
	)
	(footprint ""
		(layer "F.Cu")
		(at 14.351 -20.241768 180)
		(property "Reference" "R5131"
			(at 0 0 180)
			(layer "F.SilkS")
			(hide yes)
			(effects
				(font
					(size 1.27 1.27)
				)
			)
		)
		(property "Value" ""
			(at 0 0 180)
			(layer "F.Fab")
			(effects
				(font
					(size 1.27 1.27)
				)
			)
		)
		(duplicate_pad_numbers_are_jumpers no)
		(fp_line
			(start 0.7874 0.4064)
			(end -0.7874 0.4064)
			(stroke
				(width 0.1524)
				(type default)
			)
			(layer "F.SilkS")
		)
		(fp_line
			(start 0.7874 -0.4064)
			(end 0.7874 0.4064)
			(stroke
				(width 0.1524)
				(type default)
			)
			(layer "F.SilkS")
		)
		(fp_line
			(start -0.7874 0.4064)
			(end -0.7874 -0.4064)
			(stroke
				(width 0.1524)
				(type default)
			)
			(layer "F.SilkS")
		)
		(fp_line
			(start -0.7874 -0.4064)
			(end 0.7874 -0.4064)
			(stroke
				(width 0.1524)
				(type default)
			)
			(layer "F.SilkS")
		)
		(fp_line
			(start 0.67945 0.3048)
			(end 0.120396 0.3048)
			(stroke
				(width 0.1)
				(type default)
			)
			(layer "F.Fab")
		)
		(fp_line
			(start 0.67945 -0.3048)
			(end 0.67945 0.3048)
			(stroke
				(width 0.1)
				(type default)
			)
			(layer "F.Fab")
		)
		(fp_line
			(start 0.12065 -0.2794)
			(end 0.12065 -0.3048)
			(stroke
				(width 0.1)
				(type default)
			)
			(layer "F.Fab")
		)
		(fp_line
			(start 0.12065 -0.3048)
			(end 0.67945 -0.3048)
			(stroke
				(width 0.1)
				(type default)
			)
			(layer "F.Fab")
		)
		(fp_line
			(start 0.120396 0.3048)
			(end 0.120396 0.2794)
			(stroke
				(width 0.1)
				(type default)
			)
			(layer "F.Fab")
		)
		(fp_line
			(start 0.120396 0.2794)
			(end -0.12065 0.2794)
			(stroke
				(width 0.1)
				(type default)
			)
			(layer "F.Fab")
		)
		(fp_line
			(start -0.12065 0.3048)
			(end -0.67945 0.3048)
			(stroke
				(width 0.1)
				(type default)
			)
			(layer "F.Fab")
		)
		(fp_line
			(start -0.12065 0.2794)
			(end -0.12065 0.3048)
			(stroke
				(width 0.1)
				(type default)
			)
			(layer "F.Fab")
		)
		(fp_line
			(start -0.12065 -0.2794)
			(end 0.12065 -0.2794)
			(stroke
				(width 0.1)
				(type default)
			)
			(layer "F.Fab")
		)
		(fp_line
			(start -0.12065 -0.305054)
			(end -0.12065 -0.2794)
			(stroke
				(width 0.1)
				(type default)
			)
			(layer "F.Fab")
		)
		(fp_line
			(start -0.67945 0.3048)
			(end -0.67945 -0.305054)
			(stroke
				(width 0.1)
				(type default)
			)
			(layer "F.Fab")
		)
		(fp_line
			(start -0.67945 -0.305054)
			(end -0.12065 -0.305054)
			(stroke
				(width 0.1)
				(type default)
			)
			(layer "F.Fab")
		)
		(pad "1" smd circle
			(at -0.40005 0 180)
			(size 0 0)
			(layers "F.Cu" "F.Mask" "F.Paste")
			(net "SMB_FAN4_SCL")
		)
		(pad "2" smd circle
			(at 0.40005 0 180)
			(size 0 0)
			(layers "F.Cu" "F.Mask" "F.Paste")
			(net "SMB_FAN4_SCL_R")
		)
	)
	(footprint ""
		(layer "F.Cu")
		(at 36.703 -18.542 -90)
		(property "Reference" "R5406"
			(at 0 0 270)
			(layer "F.SilkS")
			(hide yes)
			(effects
				(font
					(size 1.27 1.27)
				)
			)
		)
		(property "Value" ""
			(at 0 0 270)
			(layer "F.Fab")
			(effects
				(font
					(size 1.27 1.27)
				)
			)
		)
		(duplicate_pad_numbers_are_jumpers no)
		(fp_line
			(start -0.7874 0.4064)
			(end -0.7874 -0.4064)
			(stroke
				(width 0.1524)
				(type default)
			)
			(layer "F.SilkS")
		)
		(fp_line
			(start 0.7874 0.4064)
			(end -0.7874 0.4064)
			(stroke
				(width 0.1524)
				(type default)
			)
			(layer "F.SilkS")
		)
		(fp_line
			(start -0.7874 -0.4064)
			(end 0.7874 -0.4064)
			(stroke
				(width 0.1524)
				(type default)
			)
			(layer "F.SilkS")
		)
		(fp_line
			(start 0.7874 -0.4064)
			(end 0.7874 0.4064)
			(stroke
				(width 0.1524)
				(type default)
			)
			(layer "F.SilkS")
		)
		(fp_line
			(start -0.67945 0.3048)
			(end -0.67945 -0.305054)
			(stroke
				(width 0.1)
				(type default)
			)
			(layer "F.Fab")
		)
		(fp_line
			(start -0.12065 0.3048)
			(end -0.67945 0.3048)
			(stroke
				(width 0.1)
				(type default)
			)
			(layer "F.Fab")
		)
		(fp_line
			(start 0.120396 0.3048)
			(end 0.120396 0.2794)
			(stroke
				(width 0.1)
				(type default)
			)
			(layer "F.Fab")
		)
		(fp_line
			(start 0.67945 0.3048)
			(end 0.120396 0.3048)
			(stroke
				(width 0.1)
				(type default)
			)
			(layer "F.Fab")
		)
		(fp_line
			(start -0.12065 0.2794)
			(end -0.12065 0.3048)
			(stroke
				(width 0.1)
				(type default)
			)
			(layer "F.Fab")
		)
		(fp_line
			(start 0.120396 0.2794)
			(end -0.12065 0.2794)
			(stroke
				(width 0.1)
				(type default)
			)
			(layer "F.Fab")
		)
		(fp_line
			(start -0.12065 -0.2794)
			(end 0.12065 -0.2794)
			(stroke
				(width 0.1)
				(type default)
			)
			(layer "F.Fab")
		)
		(fp_line
			(start 0.12065 -0.2794)
			(end 0.12065 -0.3048)
			(stroke
				(width 0.1)
				(type default)
			)
			(layer "F.Fab")
		)
		(fp_line
			(start 0.12065 -0.3048)
			(end 0.67945 -0.3048)
			(stroke
				(width 0.1)
				(type default)
			)
			(layer "F.Fab")
		)
		(fp_line
			(start 0.67945 -0.3048)
			(end 0.67945 0.3048)
			(stroke
				(width 0.1)
				(type default)
			)
			(layer "F.Fab")
		)
		(fp_line
			(start -0.67945 -0.305054)
			(end -0.12065 -0.305054)
			(stroke
				(width 0.1)
				(type default)
			)
			(layer "F.Fab")
		)
		(fp_line
			(start -0.12065 -0.305054)
			(end -0.12065 -0.2794)
			(stroke
				(width 0.1)
				(type default)
			)
			(layer "F.Fab")
		)
		(pad "1" smd rect
			(at -0.40005 0 90)
			(size 0.4572 0.508)
			(layers "F.Cu" "F.Mask" "F.Paste")
			(net "FAN_3_OK_LED_R_N")
		)
		(pad "2" smd rect
			(at 0.40005 0 90)
			(size 0.4572 0.508)
			(layers "F.Cu" "F.Mask" "F.Paste")
			(net "FAN_3_OK_R_LED_N")
		)
	)
	(footprint ""
		(layer "F.Cu")
		(at 37.719 -14.351 90)
		(property "Reference" "D283"
			(at -4.064 0.02667 90)
			(unlocked yes)
			(layer "F.SilkS")
			(effects
				(font
					(size 0.7874 0.5842)
					(thickness 0.1524)
				)
				(justify left)
			)
		)
		(property "Value" ""
			(at 0 0 90)
			(layer "F.Fab")
			(effects
				(font
					(size 1.27 1.27)
				)
			)
		)
		(duplicate_pad_numbers_are_jumpers no)
		(fp_line
			(start 0.94488 -0.450088)
			(end -0.854964 -0.450088)
			(stroke
				(width 0.1524)
				(type default)
			)
			(layer "F.SilkS")
		)
		(fp_line
			(start -0.854964 -0.450088)
			(end -0.854964 0.450088)
			(stroke
				(width 0.1524)
				(type default)
			)
			(layer "F.SilkS")
		)
		(fp_line
			(start 0.870458 -0.2794)
			(end 0.845058 0.4064)
			(stroke
				(width 0.1524)
				(type default)
			)
			(layer "F.SilkS")
		)
		(fp_line
			(start 0.845058 0.4064)
			(end 0.845058 -0.381)
			(stroke
				(width 0.1524)
				(type default)
			)
			(layer "F.SilkS")
		)
		(fp_line
			(start 0.94488 0.450088)
			(end 0.94488 -0.450088)
			(stroke
				(width 0.1524)
				(type default)
			)
			(layer "F.SilkS")
		)
		(fp_line
			(start -0.854964 0.450088)
			(end 0.925068 0.450088)
			(stroke
				(width 0.1524)
				(type default)
			)
			(layer "F.SilkS")
		)
		(fp_line
			(start 0.54991 -0.350012)
			(end -0.54991 -0.350012)
			(stroke
				(width 0.1)
				(type default)
			)
			(layer "F.Fab")
		)
		(fp_line
			(start -0.54991 -0.350012)
			(end -0.54991 0.350012)
			(stroke
				(width 0.1)
				(type default)
			)
			(layer "F.Fab")
		)
		(fp_line
			(start 0.54991 0.350012)
			(end 0.54991 -0.350012)
			(stroke
				(width 0.1)
				(type default)
			)
			(layer "F.Fab")
		)
		(fp_line
			(start -0.54991 0.350012)
			(end 0.54991 0.350012)
			(stroke
				(width 0.1)
				(type default)
			)
			(layer "F.Fab")
		)
		(fp_text user "-"
			(at 1.27 1.36525 270)
			(unlocked yes)
			(layer "F.SilkS")
			(effects
				(font
					(size 1.905 1.4224)
					(thickness 0.1524)
				)
				(justify left)
			)
		)
		(fp_text user "+"
			(at 0.254 1.36525 270)
			(unlocked yes)
			(layer "F.SilkS")
			(effects
				(font
					(size 1.905 1.4224)
					(thickness 0.1524)
				)
				(justify left)
			)
		)
		(fp_text user "-"
			(at 2.48539 0.239014 270)
			(unlocked yes)
			(layer "F.Fab")
			(effects
				(font
					(size 1.905 1.4224)
					(thickness 0.1524)
				)
				(justify left)
			)
		)
		(fp_text user "+"
			(at -0.808228 0.239014 270)
			(unlocked yes)
			(layer "F.Fab")
			(effects
				(font
					(size 1.905 1.4224)
					(thickness 0.1524)
				)
				(justify left)
			)
		)
		(pad "A" smd rect
			(at -0.424942 0 90)
			(size 0.5588 0.6096)
			(layers "F.Cu" "F.Mask" "F.Paste")
			(net "GND")
		)
		(pad "C" smd rect
			(at 0.424942 0 270)
			(size 0.5588 0.6096)
			(layers "F.Cu" "F.Mask" "F.Paste")
			(net "FAN_3_TACH_OL_D")
		)
	)
	(footprint ""
		(layer "F.Cu")
		(at 19.177 -211.836)
		(property "Reference" "C2047"
			(at 0 0 0)
			(layer "F.SilkS")
			(hide yes)
			(effects
				(font
					(size 1.27 1.27)
				)
			)
		)
		(property "Value" ""
			(at 0 0 0)
			(layer "F.Fab")
			(effects
				(font
					(size 1.27 1.27)
				)
			)
		)
		(duplicate_pad_numbers_are_jumpers no)
		(fp_line
			(start -0.7874 -0.4064)
			(end 0.7874 -0.4064)
			(stroke
				(width 0.1524)
				(type default)
			)
			(layer "F.SilkS")
		)
		(fp_line
			(start -0.7874 0.4064)
			(end -0.7874 -0.4064)
			(stroke
				(width 0.1524)
				(type default)
			)
			(layer "F.SilkS")
		)
		(fp_line
			(start 0.7874 -0.4064)
			(end 0.7874 0.4064)
			(stroke
				(width 0.1524)
				(type default)
			)
			(layer "F.SilkS")
		)
		(fp_line
			(start 0.7874 0.4064)
			(end -0.7874 0.4064)
			(stroke
				(width 0.1524)
				(type default)
			)
			(layer "F.SilkS")
		)
		(fp_line
			(start -0.67945 -0.305054)
			(end -0.12065 -0.305054)
			(stroke
				(width 0.1)
				(type default)
			)
			(layer "F.Fab")
		)
		(fp_line
			(start -0.67945 0.3048)
			(end -0.67945 -0.305054)
			(stroke
				(width 0.1)
				(type default)
			)
			(layer "F.Fab")
		)
		(fp_line
			(start -0.12065 -0.305054)
			(end -0.12065 -0.2794)
			(stroke
				(width 0.1)
				(type default)
			)
			(layer "F.Fab")
		)
		(fp_line
			(start -0.12065 -0.2794)
			(end 0.12065 -0.2794)
			(stroke
				(width 0.1)
				(type default)
			)
			(layer "F.Fab")
		)
		(fp_line
			(start -0.12065 0.2794)
			(end -0.12065 0.3048)
			(stroke
				(width 0.1)
				(type default)
			)
			(layer "F.Fab")
		)
		(fp_line
			(start -0.12065 0.3048)
			(end -0.67945 0.3048)
			(stroke
				(width 0.1)
				(type default)
			)
			(layer "F.Fab")
		)
		(fp_line
			(start 0.120396 0.2794)
			(end -0.12065 0.2794)
			(stroke
				(width 0.1)
				(type default)
			)
			(layer "F.Fab")
		)
		(fp_line
			(start 0.120396 0.3048)
			(end 0.120396 0.2794)
			(stroke
				(width 0.1)
				(type default)
			)
			(layer "F.Fab")
		)
		(fp_line
			(start 0.12065 -0.3048)
			(end 0.67945 -0.3048)
			(stroke
				(width 0.1)
				(type default)
			)
			(layer "F.Fab")
		)
		(fp_line
			(start 0.12065 -0.2794)
			(end 0.12065 -0.3048)
			(stroke
				(width 0.1)
				(type default)
			)
			(layer "F.Fab")
		)
		(fp_line
			(start 0.67945 -0.3048)
			(end 0.67945 0.3048)
			(stroke
				(width 0.1)
				(type default)
			)
			(layer "F.Fab")
		)
		(fp_line
			(start 0.67945 0.3048)
			(end 0.120396 0.3048)
			(stroke
				(width 0.1)
				(type default)
			)
			(layer "F.Fab")
		)
		(pad "1" smd circle
			(at -0.40005 0)
			(size 0 0)
			(layers "F.Cu" "F.Mask" "F.Paste")
			(net "FAN_6_TACH_OL_R")
		)
		(pad "2" smd circle
			(at 0.40005 0)
			(size 0 0)
			(layers "F.Cu" "F.Mask" "F.Paste")
			(net "GND")
		)
	)
	(footprint ""
		(layer "F.Cu")
		(at 37.211 -194.691)
		(property "Reference" "D271"
			(at 2.286 0.436626 0)
			(unlocked yes)
			(layer "F.SilkS")
			(effects
				(font
					(size 0.7874 0.5842)
					(thickness 0.1524)
				)
				(justify left)
			)
		)
		(property "Value" ""
			(at 0 0 0)
			(layer "F.Fab")
			(effects
				(font
					(size 1.27 1.27)
				)
			)
		)
		(duplicate_pad_numbers_are_jumpers no)
		(fp_line
			(start -0.854964 -0.450088)
			(end -0.854964 0.450088)
			(stroke
				(width 0.1524)
				(type default)
			)
			(layer "F.SilkS")
		)
		(fp_line
			(start -0.854964 0.450088)
			(end 0.925068 0.450088)
			(stroke
				(width 0.1524)
				(type default)
			)
			(layer "F.SilkS")
		)
		(fp_line
			(start 0.845058 0.4064)
			(end 0.845058 -0.381)
			(stroke
				(width 0.1524)
				(type default)
			)
			(layer "F.SilkS")
		)
		(fp_line
			(start 0.870458 -0.2794)
			(end 0.845058 0.4064)
			(stroke
				(width 0.1524)
				(type default)
			)
			(layer "F.SilkS")
		)
		(fp_line
			(start 0.94488 -0.450088)
			(end -0.854964 -0.450088)
			(stroke
				(width 0.1524)
				(type default)
			)
			(layer "F.SilkS")
		)
		(fp_line
			(start 0.94488 0.450088)
			(end 0.94488 -0.450088)
			(stroke
				(width 0.1524)
				(type default)
			)
			(layer "F.SilkS")
		)
		(fp_line
			(start -0.54991 -0.350012)
			(end -0.54991 0.350012)
			(stroke
				(width 0.1)
				(type default)
			)
			(layer "F.Fab")
		)
		(fp_line
			(start -0.54991 0.350012)
			(end 0.54991 0.350012)
			(stroke
				(width 0.1)
				(type default)
			)
			(layer "F.Fab")
		)
		(fp_line
			(start 0.54991 -0.350012)
			(end -0.54991 -0.350012)
			(stroke
				(width 0.1)
				(type default)
			)
			(layer "F.Fab")
		)
		(fp_line
			(start 0.54991 0.350012)
			(end 0.54991 -0.350012)
			(stroke
				(width 0.1)
				(type default)
			)
			(layer "F.Fab")
		)
		(fp_text user "+"
			(at -0.635 0.251206 180)
			(unlocked yes)
			(layer "F.SilkS")
			(effects
				(font
					(size 1.905 1.4224)
					(thickness 0.1524)
				)
				(justify left)
			)
		)
		(fp_text user "-"
			(at 2.159 0.251206 180)
			(unlocked yes)
			(layer "F.SilkS")
			(effects
				(font
					(size 1.905 1.4224)
					(thickness 0.1524)
				)
				(justify left)
			)
		)
		(fp_text user "+"
			(at -0.808228 0.239014 180)
			(unlocked yes)
			(layer "F.Fab")
			(effects
				(font
					(size 1.905 1.4224)
					(thickness 0.1524)
				)
				(justify left)
			)
		)
		(fp_text user "-"
			(at 2.48539 0.239014 180)
			(unlocked yes)
			(layer "F.Fab")
			(effects
				(font
					(size 1.905 1.4224)
					(thickness 0.1524)
				)
				(justify left)
			)
		)
		(pad "A" smd rect
			(at -0.424942 0)
			(size 0.5588 0.6096)
			(layers "F.Cu" "F.Mask" "F.Paste")
			(net "GND")
		)
		(pad "C" smd rect
			(at 0.424942 0 180)
			(size 0.5588 0.6096)
			(layers "F.Cu" "F.Mask" "F.Paste")
			(net "FAN_1_TACH_OL_D")
		)
	)
	(footprint ""
		(layer "F.Cu")
		(at 16.129 -258.572 90)
		(property "Reference" "PR72"
			(at 0 0 90)
			(layer "F.SilkS")
			(hide yes)
			(effects
				(font
					(size 1.27 1.27)
				)
			)
		)
		(property "Value" ""
			(at 0 0 90)
			(layer "F.Fab")
			(effects
				(font
					(size 1.27 1.27)
				)
			)
		)
		(duplicate_pad_numbers_are_jumpers no)
		(fp_line
			(start 0.7874 -0.4064)
			(end 0.7874 0.4064)
			(stroke
				(width 0.1524)
				(type default)
			)
			(layer "F.SilkS")
		)
		(fp_line
			(start -0.7874 -0.4064)
			(end 0.7874 -0.4064)
			(stroke
				(width 0.1524)
				(type default)
			)
			(layer "F.SilkS")
		)
		(fp_line
			(start 0.7874 0.4064)
			(end -0.7874 0.4064)
			(stroke
				(width 0.1524)
				(type default)
			)
			(layer "F.SilkS")
		)
		(fp_line
			(start -0.7874 0.4064)
			(end -0.7874 -0.4064)
			(stroke
				(width 0.1524)
				(type default)
			)
			(layer "F.SilkS")
		)
		(fp_line
			(start -0.12065 -0.305054)
			(end -0.12065 -0.2794)
			(stroke
				(width 0.1)
				(type default)
			)
			(layer "F.Fab")
		)
		(fp_line
			(start -0.67945 -0.305054)
			(end -0.12065 -0.305054)
			(stroke
				(width 0.1)
				(type default)
			)
			(layer "F.Fab")
		)
		(fp_line
			(start 0.67945 -0.3048)
			(end 0.67945 0.3048)
			(stroke
				(width 0.1)
				(type default)
			)
			(layer "F.Fab")
		)
		(fp_line
			(start 0.12065 -0.3048)
			(end 0.67945 -0.3048)
			(stroke
				(width 0.1)
				(type default)
			)
			(layer "F.Fab")
		)
		(fp_line
			(start 0.12065 -0.2794)
			(end 0.12065 -0.3048)
			(stroke
				(width 0.1)
				(type default)
			)
			(layer "F.Fab")
		)
		(fp_line
			(start -0.12065 -0.2794)
			(end 0.12065 -0.2794)
			(stroke
				(width 0.1)
				(type default)
			)
			(layer "F.Fab")
		)
		(fp_line
			(start 0.120396 0.2794)
			(end -0.12065 0.2794)
			(stroke
				(width 0.1)
				(type default)
			)
			(layer "F.Fab")
		)
		(fp_line
			(start -0.12065 0.2794)
			(end -0.12065 0.3048)
			(stroke
				(width 0.1)
				(type default)
			)
			(layer "F.Fab")
		)
		(fp_line
			(start 0.67945 0.3048)
			(end 0.120396 0.3048)
			(stroke
				(width 0.1)
				(type default)
			)
			(layer "F.Fab")
		)
		(fp_line
			(start 0.120396 0.3048)
			(end 0.120396 0.2794)
			(stroke
				(width 0.1)
				(type default)
			)
			(layer "F.Fab")
		)
		(fp_line
			(start -0.12065 0.3048)
			(end -0.67945 0.3048)
			(stroke
				(width 0.1)
				(type default)
			)
			(layer "F.Fab")
		)
		(fp_line
			(start -0.67945 0.3048)
			(end -0.67945 -0.305054)
			(stroke
				(width 0.1)
				(type default)
			)
			(layer "F.Fab")
		)
		(pad "1" smd rect
			(at -0.40005 0 270)
			(size 0.4572 0.508)
			(layers "F.Cu" "F.Mask" "F.Paste")
			(net "FAN_7_FAULT_R")
		)
		(pad "2" smd rect
			(at 0.40005 0 270)
			(size 0.4572 0.508)
			(layers "F.Cu" "F.Mask" "F.Paste")
			(net "FAN_7_FAULT")
		)
	)
	(footprint ""
		(layer "F.Cu")
		(at 16.393922 -14.310868 -90)
		(property "Reference" "C2014"
			(at 0 0 270)
			(layer "F.SilkS")
			(hide yes)
			(effects
				(font
					(size 1.27 1.27)
				)
			)
		)
		(property "Value" ""
			(at 0 0 270)
			(layer "F.Fab")
			(effects
				(font
					(size 1.27 1.27)
				)
			)
		)
		(duplicate_pad_numbers_are_jumpers no)
		(fp_line
			(start -0.7874 0.4064)
			(end -0.7874 -0.4064)
			(stroke
				(width 0.1524)
				(type default)
			)
			(layer "F.SilkS")
		)
		(fp_line
			(start 0.7874 0.4064)
			(end -0.7874 0.4064)
			(stroke
				(width 0.1524)
				(type default)
			)
			(layer "F.SilkS")
		)
		(fp_line
			(start -0.7874 -0.4064)
			(end 0.7874 -0.4064)
			(stroke
				(width 0.1524)
				(type default)
			)
			(layer "F.SilkS")
		)
		(fp_line
			(start 0.7874 -0.4064)
			(end 0.7874 0.4064)
			(stroke
				(width 0.1524)
				(type default)
			)
			(layer "F.SilkS")
		)
		(fp_line
			(start -0.67945 0.3048)
			(end -0.67945 -0.305054)
			(stroke
				(width 0.1)
				(type default)
			)
			(layer "F.Fab")
		)
		(fp_line
			(start -0.12065 0.3048)
			(end -0.67945 0.3048)
			(stroke
				(width 0.1)
				(type default)
			)
			(layer "F.Fab")
		)
		(fp_line
			(start 0.120396 0.3048)
			(end 0.120396 0.2794)
			(stroke
				(width 0.1)
				(type default)
			)
			(layer "F.Fab")
		)
		(fp_line
			(start 0.67945 0.3048)
			(end 0.120396 0.3048)
			(stroke
				(width 0.1)
				(type default)
			)
			(layer "F.Fab")
		)
		(fp_line
			(start -0.12065 0.2794)
			(end -0.12065 0.3048)
			(stroke
				(width 0.1)
				(type default)
			)
			(layer "F.Fab")
		)
		(fp_line
			(start 0.120396 0.2794)
			(end -0.12065 0.2794)
			(stroke
				(width 0.1)
				(type default)
			)
			(layer "F.Fab")
		)
		(fp_line
			(start -0.12065 -0.2794)
			(end 0.12065 -0.2794)
			(stroke
				(width 0.1)
				(type default)
			)
			(layer "F.Fab")
		)
		(fp_line
			(start 0.12065 -0.2794)
			(end 0.12065 -0.3048)
			(stroke
				(width 0.1)
				(type default)
			)
			(layer "F.Fab")
		)
		(fp_line
			(start 0.12065 -0.3048)
			(end 0.67945 -0.3048)
			(stroke
				(width 0.1)
				(type default)
			)
			(layer "F.Fab")
		)
		(fp_line
			(start 0.67945 -0.3048)
			(end 0.67945 0.3048)
			(stroke
				(width 0.1)
				(type default)
			)
			(layer "F.Fab")
		)
		(fp_line
			(start -0.67945 -0.305054)
			(end -0.12065 -0.305054)
			(stroke
				(width 0.1)
				(type default)
			)
			(layer "F.Fab")
		)
		(fp_line
			(start -0.12065 -0.305054)
			(end -0.12065 -0.2794)
			(stroke
				(width 0.1)
				(type default)
			)
			(layer "F.Fab")
		)
		(pad "1" smd circle
			(at -0.40005 0 270)
			(size 0 0)
			(layers "F.Cu" "F.Mask" "F.Paste")
			(net "FAN_4_PWM_OL_R")
		)
		(pad "2" smd circle
			(at 0.40005 0 270)
			(size 0 0)
			(layers "F.Cu" "F.Mask" "F.Paste")
			(net "GND")
		)
	)
	(footprint ""
		(layer "F.Cu")
		(at 17.399 -26.924 180)
		(property "Reference" "U340"
			(at -0.254 1.75133 0)
			(unlocked yes)
			(layer "F.SilkS")
			(effects
				(font
					(size 0.7874 0.5842)
					(thickness 0.1524)
				)
				(justify left)
			)
		)
		(property "Value" ""
			(at 0 0 180)
			(layer "F.Fab")
			(effects
				(font
					(size 1.27 1.27)
				)
			)
		)
		(duplicate_pad_numbers_are_jumpers no)
		(fp_line
			(start 1.335278 1.100074)
			(end 1.335278 -1.100074)
			(stroke
				(width 0.1524)
				(type default)
			)
			(layer "F.SilkS")
		)
		(fp_line
			(start 1.335278 -1.100074)
			(end -1.335278 -1.100074)
			(stroke
				(width 0.1524)
				(type default)
			)
			(layer "F.SilkS")
		)
		(fp_line
			(start -1.335278 1.100074)
			(end 1.335278 1.100074)
			(stroke
				(width 0.1524)
				(type default)
			)
			(layer "F.SilkS")
		)
		(fp_line
			(start -1.335278 -1.100074)
			(end -1.335278 1.100074)
			(stroke
				(width 0.1524)
				(type default)
			)
			(layer "F.SilkS")
		)
		(fp_line
			(start 0.674878 1.100074)
			(end 0.674878 -1.100074)
			(stroke
				(width 0.1)
				(type default)
			)
			(layer "F.Fab")
		)
		(fp_line
			(start 0.674878 -1.100074)
			(end -0.674878 -1.100074)
			(stroke
				(width 0.1)
				(type default)
			)
			(layer "F.Fab")
		)
		(fp_line
			(start -0.674878 1.100074)
			(end 0.674878 1.100074)
			(stroke
				(width 0.1)
				(type default)
			)
			(layer "F.Fab")
		)
		(fp_line
			(start -0.674878 -1.100074)
			(end -0.674878 1.100074)
			(stroke
				(width 0.1)
				(type default)
			)
			(layer "F.Fab")
		)
		(pad "D" smd rect
			(at 0.8001 0 90)
			(size 0.6096 0.8128)
			(layers "F.Cu" "F.Mask" "F.Paste")
			(net "FAN_4_OK_LED_R_N")
		)
		(pad "G" smd rect
			(at -0.8001 -0.649986 90)
			(size 0.6096 0.8128)
			(layers "F.Cu" "F.Mask" "F.Paste")
			(net "FAN_4_OK_R_LED")
		)
		(pad "S" smd rect
			(at -0.8001 0.649986 90)
			(size 0.6096 0.8128)
			(layers "F.Cu" "F.Mask" "F.Paste")
			(net "GND")
		)
	)
	(footprint ""
		(layer "F.Cu")
		(at 28.829 -102.108 -90)
		(property "Reference" "C2091"
			(at 0 0 270)
			(layer "F.SilkS")
			(hide yes)
			(effects
				(font
					(size 1.27 1.27)
				)
			)
		)
		(property "Value" ""
			(at 0 0 270)
			(layer "F.Fab")
			(effects
				(font
					(size 1.27 1.27)
				)
			)
		)
		(duplicate_pad_numbers_are_jumpers no)
		(fp_line
			(start -0.7874 0.4064)
			(end -0.7874 -0.4064)
			(stroke
				(width 0.1524)
				(type default)
			)
			(layer "F.SilkS")
		)
		(fp_line
			(start 0.7874 0.4064)
			(end -0.7874 0.4064)
			(stroke
				(width 0.1524)
				(type default)
			)
			(layer "F.SilkS")
		)
		(fp_line
			(start -0.7874 -0.4064)
			(end 0.7874 -0.4064)
			(stroke
				(width 0.1524)
				(type default)
			)
			(layer "F.SilkS")
		)
		(fp_line
			(start 0.7874 -0.4064)
			(end 0.7874 0.4064)
			(stroke
				(width 0.1524)
				(type default)
			)
			(layer "F.SilkS")
		)
		(fp_line
			(start -0.67945 0.3048)
			(end -0.67945 -0.305054)
			(stroke
				(width 0.1)
				(type default)
			)
			(layer "F.Fab")
		)
		(fp_line
			(start -0.12065 0.3048)
			(end -0.67945 0.3048)
			(stroke
				(width 0.1)
				(type default)
			)
			(layer "F.Fab")
		)
		(fp_line
			(start 0.120396 0.3048)
			(end 0.120396 0.2794)
			(stroke
				(width 0.1)
				(type default)
			)
			(layer "F.Fab")
		)
		(fp_line
			(start 0.67945 0.3048)
			(end 0.120396 0.3048)
			(stroke
				(width 0.1)
				(type default)
			)
			(layer "F.Fab")
		)
		(fp_line
			(start -0.12065 0.2794)
			(end -0.12065 0.3048)
			(stroke
				(width 0.1)
				(type default)
			)
			(layer "F.Fab")
		)
		(fp_line
			(start 0.120396 0.2794)
			(end -0.12065 0.2794)
			(stroke
				(width 0.1)
				(type default)
			)
			(layer "F.Fab")
		)
		(fp_line
			(start -0.12065 -0.2794)
			(end 0.12065 -0.2794)
			(stroke
				(width 0.1)
				(type default)
			)
			(layer "F.Fab")
		)
		(fp_line
			(start 0.12065 -0.2794)
			(end 0.12065 -0.3048)
			(stroke
				(width 0.1)
				(type default)
			)
			(layer "F.Fab")
		)
		(fp_line
			(start 0.12065 -0.3048)
			(end 0.67945 -0.3048)
			(stroke
				(width 0.1)
				(type default)
			)
			(layer "F.Fab")
		)
		(fp_line
			(start 0.67945 -0.3048)
			(end 0.67945 0.3048)
			(stroke
				(width 0.1)
				(type default)
			)
			(layer "F.Fab")
		)
		(fp_line
			(start -0.67945 -0.305054)
			(end -0.12065 -0.305054)
			(stroke
				(width 0.1)
				(type default)
			)
			(layer "F.Fab")
		)
		(fp_line
			(start -0.12065 -0.305054)
			(end -0.12065 -0.2794)
			(stroke
				(width 0.1)
				(type default)
			)
			(layer "F.Fab")
		)
		(pad "1" smd circle
			(at -0.40005 0 270)
			(size 0 0)
			(layers "F.Cu" "F.Mask" "F.Paste")
			(net "P3V3_AUX")
		)
		(pad "2" smd circle
			(at 0.40005 0 270)
			(size 0 0)
			(layers "F.Cu" "F.Mask" "F.Paste")
			(net "GND")
		)
	)
	(footprint ""
		(layer "F.Cu")
		(at -14.841474 -296.164 180)
		(property "Reference" "J83"
			(at -1.252474 -5.48767 0)
			(unlocked yes)
			(layer "F.SilkS")
			(effects
				(font
					(size 0.7874 0.5842)
					(thickness 0.1524)
				)
				(justify left)
			)
		)
		(property "Value" ""
			(at 0 0 180)
			(layer "F.Fab")
			(effects
				(font
					(size 1.27 1.27)
				)
			)
		)
		(duplicate_pad_numbers_are_jumpers no)
		(fp_line
			(start 3.330702 -4.771136)
			(end 0 4.011168)
			(stroke
				(width 0.1524)
				(type default)
			)
			(layer "F.SilkS")
		)
		(fp_line
			(start 0 4.011168)
			(end -3.330702 -4.771136)
			(stroke
				(width 0.1524)
				(type default)
			)
			(layer "F.SilkS")
		)
		(fp_line
			(start -3.330702 -4.771136)
			(end 3.330702 -4.771136)
			(stroke
				(width 0.1524)
				(type default)
			)
			(layer "F.SilkS")
		)
		(fp_line
			(start 3.330702 -4.771136)
			(end 0 4.011168)
			(stroke
				(width 0.1)
				(type default)
			)
			(layer "F.Fab")
		)
		(fp_line
			(start 0 4.011168)
			(end -3.330702 -4.771136)
			(stroke
				(width 0.1)
				(type default)
			)
			(layer "F.Fab")
		)
		(fp_line
			(start -3.330702 -4.771136)
			(end 3.330702 -4.771136)
			(stroke
				(width 0.1)
				(type default)
			)
			(layer "F.Fab")
		)
		(pad "1" thru_hole circle
			(at 0 0 180)
			(size 2.159 2.159)
			(drill 1.7018)
			(layers "*.Cu" "*.Mask")
			(remove_unused_layers no)
			(net "GND2")
			(clearance 0.0254)
			(thermal_gap 0.0254)
		)
		(pad "2" thru_hole circle
			(at -1.27 -3.348736 180)
			(size 2.159 2.159)
			(drill 1.7018)
			(layers "*.Cu" "*.Mask")
			(remove_unused_layers no)
			(net "TDR_SE_50_OHM_IN1")
			(clearance 0.0254)
			(thermal_gap 0.0254)
		)
		(pad "3" thru_hole circle
			(at 1.27 -3.348736 180)
			(size 2.159 2.159)
			(drill 1.7018)
			(layers "*.Cu" "*.Mask")
			(remove_unused_layers no)
			(net "TDR_SE_50_OHM_IN1")
			(clearance 0.0254)
			(thermal_gap 0.0254)
		)
	)
	(footprint ""
		(layer "F.Cu")
		(at 27.178 -162.941 90)
		(property "Reference" "R5273"
			(at 0 0 90)
			(layer "F.SilkS")
			(hide yes)
			(effects
				(font
					(size 1.27 1.27)
				)
			)
		)
		(property "Value" ""
			(at 0 0 90)
			(layer "F.Fab")
			(effects
				(font
					(size 1.27 1.27)
				)
			)
		)
		(duplicate_pad_numbers_are_jumpers no)
		(fp_line
			(start 0.7874 -0.4064)
			(end 0.7874 0.4064)
			(stroke
				(width 0.1524)
				(type default)
			)
			(layer "F.SilkS")
		)
		(fp_line
			(start -0.7874 -0.4064)
			(end 0.7874 -0.4064)
			(stroke
				(width 0.1524)
				(type default)
			)
			(layer "F.SilkS")
		)
		(fp_line
			(start 0.7874 0.4064)
			(end -0.7874 0.4064)
			(stroke
				(width 0.1524)
				(type default)
			)
			(layer "F.SilkS")
		)
		(fp_line
			(start -0.7874 0.4064)
			(end -0.7874 -0.4064)
			(stroke
				(width 0.1524)
				(type default)
			)
			(layer "F.SilkS")
		)
		(fp_line
			(start -0.12065 -0.305054)
			(end -0.12065 -0.2794)
			(stroke
				(width 0.1)
				(type default)
			)
			(layer "F.Fab")
		)
		(fp_line
			(start -0.67945 -0.305054)
			(end -0.12065 -0.305054)
			(stroke
				(width 0.1)
				(type default)
			)
			(layer "F.Fab")
		)
		(fp_line
			(start 0.67945 -0.3048)
			(end 0.67945 0.3048)
			(stroke
				(width 0.1)
				(type default)
			)
			(layer "F.Fab")
		)
		(fp_line
			(start 0.12065 -0.3048)
			(end 0.67945 -0.3048)
			(stroke
				(width 0.1)
				(type default)
			)
			(layer "F.Fab")
		)
		(fp_line
			(start 0.12065 -0.2794)
			(end 0.12065 -0.3048)
			(stroke
				(width 0.1)
				(type default)
			)
			(layer "F.Fab")
		)
		(fp_line
			(start -0.12065 -0.2794)
			(end 0.12065 -0.2794)
			(stroke
				(width 0.1)
				(type default)
			)
			(layer "F.Fab")
		)
		(fp_line
			(start 0.120396 0.2794)
			(end -0.12065 0.2794)
			(stroke
				(width 0.1)
				(type default)
			)
			(layer "F.Fab")
		)
		(fp_line
			(start -0.12065 0.2794)
			(end -0.12065 0.3048)
			(stroke
				(width 0.1)
				(type default)
			)
			(layer "F.Fab")
		)
		(fp_line
			(start 0.67945 0.3048)
			(end 0.120396 0.3048)
			(stroke
				(width 0.1)
				(type default)
			)
			(layer "F.Fab")
		)
		(fp_line
			(start 0.120396 0.3048)
			(end 0.120396 0.2794)
			(stroke
				(width 0.1)
				(type default)
			)
			(layer "F.Fab")
		)
		(fp_line
			(start -0.12065 0.3048)
			(end -0.67945 0.3048)
			(stroke
				(width 0.1)
				(type default)
			)
			(layer "F.Fab")
		)
		(fp_line
			(start -0.67945 0.3048)
			(end -0.67945 -0.305054)
			(stroke
				(width 0.1)
				(type default)
			)
			(layer "F.Fab")
		)
		(pad "1" smd circle
			(at -0.40005 0 90)
			(size 0 0)
			(layers "F.Cu" "F.Mask" "F.Paste")
			(net "SMB_FAN6_R_SDA")
		)
		(pad "2" smd circle
			(at 0.40005 0 90)
			(size 0 0)
			(layers "F.Cu" "F.Mask" "F.Paste")
			(net "P3V3_AUX")
		)
	)
	(footprint ""
		(layer "F.Cu")
		(at 8.709914 -68.256912)
		(property "Reference" "R5354"
			(at 0 0 0)
			(layer "F.SilkS")
			(hide yes)
			(effects
				(font
					(size 1.27 1.27)
				)
			)
		)
		(property "Value" ""
			(at 0 0 0)
			(layer "F.Fab")
			(effects
				(font
					(size 1.27 1.27)
				)
			)
		)
		(duplicate_pad_numbers_are_jumpers no)
		(fp_line
			(start -0.7874 -0.4064)
			(end 0.7874 -0.4064)
			(stroke
				(width 0.1524)
				(type default)
			)
			(layer "F.SilkS")
		)
		(fp_line
			(start -0.7874 0.4064)
			(end -0.7874 -0.4064)
			(stroke
				(width 0.1524)
				(type default)
			)
			(layer "F.SilkS")
		)
		(fp_line
			(start 0.7874 -0.4064)
			(end 0.7874 0.4064)
			(stroke
				(width 0.1524)
				(type default)
			)
			(layer "F.SilkS")
		)
		(fp_line
			(start 0.7874 0.4064)
			(end -0.7874 0.4064)
			(stroke
				(width 0.1524)
				(type default)
			)
			(layer "F.SilkS")
		)
		(fp_line
			(start -0.67945 -0.305054)
			(end -0.12065 -0.305054)
			(stroke
				(width 0.1)
				(type default)
			)
			(layer "F.Fab")
		)
		(fp_line
			(start -0.67945 0.3048)
			(end -0.67945 -0.305054)
			(stroke
				(width 0.1)
				(type default)
			)
			(layer "F.Fab")
		)
		(fp_line
			(start -0.12065 -0.305054)
			(end -0.12065 -0.2794)
			(stroke
				(width 0.1)
				(type default)
			)
			(layer "F.Fab")
		)
		(fp_line
			(start -0.12065 -0.2794)
			(end 0.12065 -0.2794)
			(stroke
				(width 0.1)
				(type default)
			)
			(layer "F.Fab")
		)
		(fp_line
			(start -0.12065 0.2794)
			(end -0.12065 0.3048)
			(stroke
				(width 0.1)
				(type default)
			)
			(layer "F.Fab")
		)
		(fp_line
			(start -0.12065 0.3048)
			(end -0.67945 0.3048)
			(stroke
				(width 0.1)
				(type default)
			)
			(layer "F.Fab")
		)
		(fp_line
			(start 0.120396 0.2794)
			(end -0.12065 0.2794)
			(stroke
				(width 0.1)
				(type default)
			)
			(layer "F.Fab")
		)
		(fp_line
			(start 0.120396 0.3048)
			(end 0.120396 0.2794)
			(stroke
				(width 0.1)
				(type default)
			)
			(layer "F.Fab")
		)
		(fp_line
			(start 0.12065 -0.3048)
			(end 0.67945 -0.3048)
			(stroke
				(width 0.1)
				(type default)
			)
			(layer "F.Fab")
		)
		(fp_line
			(start 0.12065 -0.2794)
			(end 0.12065 -0.3048)
			(stroke
				(width 0.1)
				(type default)
			)
			(layer "F.Fab")
		)
		(fp_line
			(start 0.67945 -0.3048)
			(end 0.67945 0.3048)
			(stroke
				(width 0.1)
				(type default)
			)
			(layer "F.Fab")
		)
		(fp_line
			(start 0.67945 0.3048)
			(end 0.120396 0.3048)
			(stroke
				(width 0.1)
				(type default)
			)
			(layer "F.Fab")
		)
		(pad "1" smd circle
			(at -0.40005 0)
			(size 0 0)
			(layers "F.Cu" "F.Mask" "F.Paste")
			(net "FAN_4_ON")
		)
		(pad "2" smd circle
			(at 0.40005 0)
			(size 0 0)
			(layers "F.Cu" "F.Mask" "F.Paste")
			(net "P52V_FAN_4_EN")
		)
	)
	(footprint ""
		(layer "F.Cu")
		(at 43.561 -167.513 180)
		(property "Reference" "R5113"
			(at 0 0 180)
			(layer "F.SilkS")
			(hide yes)
			(effects
				(font
					(size 1.27 1.27)
				)
			)
		)
		(property "Value" ""
			(at 0 0 180)
			(layer "F.Fab")
			(effects
				(font
					(size 1.27 1.27)
				)
			)
		)
		(duplicate_pad_numbers_are_jumpers no)
		(fp_line
			(start 0.7874 0.4064)
			(end -0.7874 0.4064)
			(stroke
				(width 0.1524)
				(type default)
			)
			(layer "F.SilkS")
		)
		(fp_line
			(start 0.7874 -0.4064)
			(end 0.7874 0.4064)
			(stroke
				(width 0.1524)
				(type default)
			)
			(layer "F.SilkS")
		)
		(fp_line
			(start -0.7874 0.4064)
			(end -0.7874 -0.4064)
			(stroke
				(width 0.1524)
				(type default)
			)
			(layer "F.SilkS")
		)
		(fp_line
			(start -0.7874 -0.4064)
			(end 0.7874 -0.4064)
			(stroke
				(width 0.1524)
				(type default)
			)
			(layer "F.SilkS")
		)
		(fp_line
			(start 0.67945 0.3048)
			(end 0.120396 0.3048)
			(stroke
				(width 0.1)
				(type default)
			)
			(layer "F.Fab")
		)
		(fp_line
			(start 0.67945 -0.3048)
			(end 0.67945 0.3048)
			(stroke
				(width 0.1)
				(type default)
			)
			(layer "F.Fab")
		)
		(fp_line
			(start 0.12065 -0.2794)
			(end 0.12065 -0.3048)
			(stroke
				(width 0.1)
				(type default)
			)
			(layer "F.Fab")
		)
		(fp_line
			(start 0.12065 -0.3048)
			(end 0.67945 -0.3048)
			(stroke
				(width 0.1)
				(type default)
			)
			(layer "F.Fab")
		)
		(fp_line
			(start 0.120396 0.3048)
			(end 0.120396 0.2794)
			(stroke
				(width 0.1)
				(type default)
			)
			(layer "F.Fab")
		)
		(fp_line
			(start 0.120396 0.2794)
			(end -0.12065 0.2794)
			(stroke
				(width 0.1)
				(type default)
			)
			(layer "F.Fab")
		)
		(fp_line
			(start -0.12065 0.3048)
			(end -0.67945 0.3048)
			(stroke
				(width 0.1)
				(type default)
			)
			(layer "F.Fab")
		)
		(fp_line
			(start -0.12065 0.2794)
			(end -0.12065 0.3048)
			(stroke
				(width 0.1)
				(type default)
			)
			(layer "F.Fab")
		)
		(fp_line
			(start -0.12065 -0.2794)
			(end 0.12065 -0.2794)
			(stroke
				(width 0.1)
				(type default)
			)
			(layer "F.Fab")
		)
		(fp_line
			(start -0.12065 -0.305054)
			(end -0.12065 -0.2794)
			(stroke
				(width 0.1)
				(type default)
			)
			(layer "F.Fab")
		)
		(fp_line
			(start -0.67945 0.3048)
			(end -0.67945 -0.305054)
			(stroke
				(width 0.1)
				(type default)
			)
			(layer "F.Fab")
		)
		(fp_line
			(start -0.67945 -0.305054)
			(end -0.12065 -0.305054)
			(stroke
				(width 0.1)
				(type default)
			)
			(layer "F.Fab")
		)
		(pad "1" smd circle
			(at -0.40005 0 180)
			(size 0 0)
			(layers "F.Cu" "F.Mask" "F.Paste")
			(net "P3V3_AUX")
		)
		(pad "2" smd circle
			(at 0.40005 0 180)
			(size 0 0)
			(layers "F.Cu" "F.Mask" "F.Paste")
			(net "PCA9552_MB1_A1")
		)
	)
	(footprint ""
		(layer "F.Cu")
		(at 5.461 -188.214)
		(property "Reference" "R311"
			(at 0 0 0)
			(layer "F.SilkS")
			(hide yes)
			(effects
				(font
					(size 1.27 1.27)
				)
			)
		)
		(property "Value" ""
			(at 0 0 0)
			(layer "F.Fab")
			(effects
				(font
					(size 1.27 1.27)
				)
			)
		)
		(duplicate_pad_numbers_are_jumpers no)
		(fp_line
			(start -0.7874 -0.4064)
			(end 0.7874 -0.4064)
			(stroke
				(width 0.1524)
				(type default)
			)
			(layer "F.SilkS")
		)
		(fp_line
			(start -0.7874 0.4064)
			(end -0.7874 -0.4064)
			(stroke
				(width 0.1524)
				(type default)
			)
			(layer "F.SilkS")
		)
		(fp_line
			(start 0.7874 -0.4064)
			(end 0.7874 0.4064)
			(stroke
				(width 0.1524)
				(type default)
			)
			(layer "F.SilkS")
		)
		(fp_line
			(start 0.7874 0.4064)
			(end -0.7874 0.4064)
			(stroke
				(width 0.1524)
				(type default)
			)
			(layer "F.SilkS")
		)
		(fp_line
			(start -0.67945 -0.305054)
			(end -0.12065 -0.305054)
			(stroke
				(width 0.1)
				(type default)
			)
			(layer "F.Fab")
		)
		(fp_line
			(start -0.67945 0.3048)
			(end -0.67945 -0.305054)
			(stroke
				(width 0.1)
				(type default)
			)
			(layer "F.Fab")
		)
		(fp_line
			(start -0.12065 -0.305054)
			(end -0.12065 -0.2794)
			(stroke
				(width 0.1)
				(type default)
			)
			(layer "F.Fab")
		)
		(fp_line
			(start -0.12065 -0.2794)
			(end 0.12065 -0.2794)
			(stroke
				(width 0.1)
				(type default)
			)
			(layer "F.Fab")
		)
		(fp_line
			(start -0.12065 0.2794)
			(end -0.12065 0.3048)
			(stroke
				(width 0.1)
				(type default)
			)
			(layer "F.Fab")
		)
		(fp_line
			(start -0.12065 0.3048)
			(end -0.67945 0.3048)
			(stroke
				(width 0.1)
				(type default)
			)
			(layer "F.Fab")
		)
		(fp_line
			(start 0.120396 0.2794)
			(end -0.12065 0.2794)
			(stroke
				(width 0.1)
				(type default)
			)
			(layer "F.Fab")
		)
		(fp_line
			(start 0.120396 0.3048)
			(end 0.120396 0.2794)
			(stroke
				(width 0.1)
				(type default)
			)
			(layer "F.Fab")
		)
		(fp_line
			(start 0.12065 -0.3048)
			(end 0.67945 -0.3048)
			(stroke
				(width 0.1)
				(type default)
			)
			(layer "F.Fab")
		)
		(fp_line
			(start 0.12065 -0.2794)
			(end 0.12065 -0.3048)
			(stroke
				(width 0.1)
				(type default)
			)
			(layer "F.Fab")
		)
		(fp_line
			(start 0.67945 -0.3048)
			(end 0.67945 0.3048)
			(stroke
				(width 0.1)
				(type default)
			)
			(layer "F.Fab")
		)
		(fp_line
			(start 0.67945 0.3048)
			(end 0.120396 0.3048)
			(stroke
				(width 0.1)
				(type default)
			)
			(layer "F.Fab")
		)
		(pad "1" smd circle
			(at -0.40005 0)
			(size 0 0)
			(layers "F.Cu" "F.Mask" "F.Paste")
			(net "P3V3_AUX")
		)
		(pad "2" smd circle
			(at 0.40005 0)
			(size 0 0)
			(layers "F.Cu" "F.Mask" "F.Paste")
			(net "FRU_ADDR1")
		)
	)
	(footprint ""
		(layer "F.Cu")
		(at 42.40784 -331.27442)
		(property "Reference" ""
			(at 0 0 0)
			(layer "F.SilkS")
			(hide yes)
			(effects
				(font
					(size 1.27 1.27)
				)
			)
		)
		(property "Value" ""
			(at 0 0 0)
			(layer "F.Fab")
			(effects
				(font
					(size 1.27 1.27)
				)
			)
		)
		(duplicate_pad_numbers_are_jumpers no)
		(pad "1" smd circle
			(at 0 0)
			(size 0.9906 0.9906)
			(layers "F.Cu" "F.Mask" "F.Paste")
			(net "Net_595")
		)
		(zone
			(layer "F.Cu")
			(hatch none 0.5)
			(connect_pads
				(clearance 0)
			)
			(min_thickness 0.25)
			(keepout
				(tracks not_allowed)
				(vias allowed)
				(pads allowed)
				(copperpour not_allowed)
				(footprints allowed)
			)
			(placement
				(enabled no)
				(sheetname "")
			)
			(fill
				(thermal_gap 0.5)
				(thermal_bridge_width 0.5)
				(island_removal_mode 0)
			)
			(polygon
				(pts
					(arc
						(start 44.03344 -331.27442)
						(mid 40.78224 -331.27442)
						(end 44.03344 -331.27442)
					)
				)
			)
		)
	)
	(footprint ""
		(layer "F.Cu")
		(at 20.828 -181.61)
		(property "Reference" "R2354"
			(at 0 0 0)
			(layer "F.SilkS")
			(hide yes)
			(effects
				(font
					(size 1.27 1.27)
				)
			)
		)
		(property "Value" ""
			(at 0 0 0)
			(layer "F.Fab")
			(effects
				(font
					(size 1.27 1.27)
				)
			)
		)
		(duplicate_pad_numbers_are_jumpers no)
		(fp_line
			(start -0.7874 -0.4064)
			(end 0.7874 -0.4064)
			(stroke
				(width 0.1524)
				(type default)
			)
			(layer "F.SilkS")
		)
		(fp_line
			(start -0.7874 0.4064)
			(end -0.7874 -0.4064)
			(stroke
				(width 0.1524)
				(type default)
			)
			(layer "F.SilkS")
		)
		(fp_line
			(start 0.7874 -0.4064)
			(end 0.7874 0.4064)
			(stroke
				(width 0.1524)
				(type default)
			)
			(layer "F.SilkS")
		)
		(fp_line
			(start 0.7874 0.4064)
			(end -0.7874 0.4064)
			(stroke
				(width 0.1524)
				(type default)
			)
			(layer "F.SilkS")
		)
		(fp_line
			(start -0.67945 -0.305054)
			(end -0.12065 -0.305054)
			(stroke
				(width 0.1)
				(type default)
			)
			(layer "F.Fab")
		)
		(fp_line
			(start -0.67945 0.3048)
			(end -0.67945 -0.305054)
			(stroke
				(width 0.1)
				(type default)
			)
			(layer "F.Fab")
		)
		(fp_line
			(start -0.12065 -0.305054)
			(end -0.12065 -0.2794)
			(stroke
				(width 0.1)
				(type default)
			)
			(layer "F.Fab")
		)
		(fp_line
			(start -0.12065 -0.2794)
			(end 0.12065 -0.2794)
			(stroke
				(width 0.1)
				(type default)
			)
			(layer "F.Fab")
		)
		(fp_line
			(start -0.12065 0.2794)
			(end -0.12065 0.3048)
			(stroke
				(width 0.1)
				(type default)
			)
			(layer "F.Fab")
		)
		(fp_line
			(start -0.12065 0.3048)
			(end -0.67945 0.3048)
			(stroke
				(width 0.1)
				(type default)
			)
			(layer "F.Fab")
		)
		(fp_line
			(start 0.120396 0.2794)
			(end -0.12065 0.2794)
			(stroke
				(width 0.1)
				(type default)
			)
			(layer "F.Fab")
		)
		(fp_line
			(start 0.120396 0.3048)
			(end 0.120396 0.2794)
			(stroke
				(width 0.1)
				(type default)
			)
			(layer "F.Fab")
		)
		(fp_line
			(start 0.12065 -0.3048)
			(end 0.67945 -0.3048)
			(stroke
				(width 0.1)
				(type default)
			)
			(layer "F.Fab")
		)
		(fp_line
			(start 0.12065 -0.2794)
			(end 0.12065 -0.3048)
			(stroke
				(width 0.1)
				(type default)
			)
			(layer "F.Fab")
		)
		(fp_line
			(start 0.67945 -0.3048)
			(end 0.67945 0.3048)
			(stroke
				(width 0.1)
				(type default)
			)
			(layer "F.Fab")
		)
		(fp_line
			(start 0.67945 0.3048)
			(end 0.120396 0.3048)
			(stroke
				(width 0.1)
				(type default)
			)
			(layer "F.Fab")
		)
		(pad "1" smd circle
			(at -0.40005 0)
			(size 0 0)
			(layers "F.Cu" "F.Mask" "F.Paste")
			(net "PCA9555_MB0_A0")
		)
		(pad "2" smd circle
			(at 0.40005 0)
			(size 0 0)
			(layers "F.Cu" "F.Mask" "F.Paste")
			(net "GND")
		)
	)
	(footprint ""
		(layer "F.Cu")
		(at 20.32 -143.891 90)
		(property "Reference" "R5645"
			(at 0 0 90)
			(layer "F.SilkS")
			(hide yes)
			(effects
				(font
					(size 1.27 1.27)
				)
			)
		)
		(property "Value" ""
			(at 0 0 90)
			(layer "F.Fab")
			(effects
				(font
					(size 1.27 1.27)
				)
			)
		)
		(duplicate_pad_numbers_are_jumpers no)
		(fp_line
			(start 0.7874 -0.4064)
			(end 0.7874 0.4064)
			(stroke
				(width 0.1524)
				(type default)
			)
			(layer "F.SilkS")
		)
		(fp_line
			(start -0.7874 -0.4064)
			(end 0.7874 -0.4064)
			(stroke
				(width 0.1524)
				(type default)
			)
			(layer "F.SilkS")
		)
		(fp_line
			(start 0.7874 0.4064)
			(end -0.7874 0.4064)
			(stroke
				(width 0.1524)
				(type default)
			)
			(layer "F.SilkS")
		)
		(fp_line
			(start -0.7874 0.4064)
			(end -0.7874 -0.4064)
			(stroke
				(width 0.1524)
				(type default)
			)
			(layer "F.SilkS")
		)
		(fp_line
			(start -0.12065 -0.305054)
			(end -0.12065 -0.2794)
			(stroke
				(width 0.1)
				(type default)
			)
			(layer "F.Fab")
		)
		(fp_line
			(start -0.67945 -0.305054)
			(end -0.12065 -0.305054)
			(stroke
				(width 0.1)
				(type default)
			)
			(layer "F.Fab")
		)
		(fp_line
			(start 0.67945 -0.3048)
			(end 0.67945 0.3048)
			(stroke
				(width 0.1)
				(type default)
			)
			(layer "F.Fab")
		)
		(fp_line
			(start 0.12065 -0.3048)
			(end 0.67945 -0.3048)
			(stroke
				(width 0.1)
				(type default)
			)
			(layer "F.Fab")
		)
		(fp_line
			(start 0.12065 -0.2794)
			(end 0.12065 -0.3048)
			(stroke
				(width 0.1)
				(type default)
			)
			(layer "F.Fab")
		)
		(fp_line
			(start -0.12065 -0.2794)
			(end 0.12065 -0.2794)
			(stroke
				(width 0.1)
				(type default)
			)
			(layer "F.Fab")
		)
		(fp_line
			(start 0.120396 0.2794)
			(end -0.12065 0.2794)
			(stroke
				(width 0.1)
				(type default)
			)
			(layer "F.Fab")
		)
		(fp_line
			(start -0.12065 0.2794)
			(end -0.12065 0.3048)
			(stroke
				(width 0.1)
				(type default)
			)
			(layer "F.Fab")
		)
		(fp_line
			(start 0.67945 0.3048)
			(end 0.120396 0.3048)
			(stroke
				(width 0.1)
				(type default)
			)
			(layer "F.Fab")
		)
		(fp_line
			(start 0.120396 0.3048)
			(end 0.120396 0.2794)
			(stroke
				(width 0.1)
				(type default)
			)
			(layer "F.Fab")
		)
		(fp_line
			(start -0.12065 0.3048)
			(end -0.67945 0.3048)
			(stroke
				(width 0.1)
				(type default)
			)
			(layer "F.Fab")
		)
		(fp_line
			(start -0.67945 0.3048)
			(end -0.67945 -0.305054)
			(stroke
				(width 0.1)
				(type default)
			)
			(layer "F.Fab")
		)
		(pad "1" smd circle
			(at -0.40005 0 90)
			(size 0 0)
			(layers "F.Cu" "F.Mask" "F.Paste")
			(net "RST_SMB_PDB_N")
		)
		(pad "2" smd circle
			(at 0.40005 0 90)
			(size 0 0)
			(layers "F.Cu" "F.Mask" "F.Paste")
			(net "RST_SMB_PDB_R_N")
		)
	)
	(footprint ""
		(layer "F.Cu")
		(at 46.355 -168.529)
		(property "Reference" "R5117"
			(at 0 0 0)
			(layer "F.SilkS")
			(hide yes)
			(effects
				(font
					(size 1.27 1.27)
				)
			)
		)
		(property "Value" ""
			(at 0 0 0)
			(layer "F.Fab")
			(effects
				(font
					(size 1.27 1.27)
				)
			)
		)
		(duplicate_pad_numbers_are_jumpers no)
		(fp_line
			(start -0.7874 -0.4064)
			(end 0.7874 -0.4064)
			(stroke
				(width 0.1524)
				(type default)
			)
			(layer "F.SilkS")
		)
		(fp_line
			(start -0.7874 0.4064)
			(end -0.7874 -0.4064)
			(stroke
				(width 0.1524)
				(type default)
			)
			(layer "F.SilkS")
		)
		(fp_line
			(start 0.7874 -0.4064)
			(end 0.7874 0.4064)
			(stroke
				(width 0.1524)
				(type default)
			)
			(layer "F.SilkS")
		)
		(fp_line
			(start 0.7874 0.4064)
			(end -0.7874 0.4064)
			(stroke
				(width 0.1524)
				(type default)
			)
			(layer "F.SilkS")
		)
		(fp_line
			(start -0.67945 -0.305054)
			(end -0.12065 -0.305054)
			(stroke
				(width 0.1)
				(type default)
			)
			(layer "F.Fab")
		)
		(fp_line
			(start -0.67945 0.3048)
			(end -0.67945 -0.305054)
			(stroke
				(width 0.1)
				(type default)
			)
			(layer "F.Fab")
		)
		(fp_line
			(start -0.12065 -0.305054)
			(end -0.12065 -0.2794)
			(stroke
				(width 0.1)
				(type default)
			)
			(layer "F.Fab")
		)
		(fp_line
			(start -0.12065 -0.2794)
			(end 0.12065 -0.2794)
			(stroke
				(width 0.1)
				(type default)
			)
			(layer "F.Fab")
		)
		(fp_line
			(start -0.12065 0.2794)
			(end -0.12065 0.3048)
			(stroke
				(width 0.1)
				(type default)
			)
			(layer "F.Fab")
		)
		(fp_line
			(start -0.12065 0.3048)
			(end -0.67945 0.3048)
			(stroke
				(width 0.1)
				(type default)
			)
			(layer "F.Fab")
		)
		(fp_line
			(start 0.120396 0.2794)
			(end -0.12065 0.2794)
			(stroke
				(width 0.1)
				(type default)
			)
			(layer "F.Fab")
		)
		(fp_line
			(start 0.120396 0.3048)
			(end 0.120396 0.2794)
			(stroke
				(width 0.1)
				(type default)
			)
			(layer "F.Fab")
		)
		(fp_line
			(start 0.12065 -0.3048)
			(end 0.67945 -0.3048)
			(stroke
				(width 0.1)
				(type default)
			)
			(layer "F.Fab")
		)
		(fp_line
			(start 0.12065 -0.2794)
			(end 0.12065 -0.3048)
			(stroke
				(width 0.1)
				(type default)
			)
			(layer "F.Fab")
		)
		(fp_line
			(start 0.67945 -0.3048)
			(end 0.67945 0.3048)
			(stroke
				(width 0.1)
				(type default)
			)
			(layer "F.Fab")
		)
		(fp_line
			(start 0.67945 0.3048)
			(end 0.120396 0.3048)
			(stroke
				(width 0.1)
				(type default)
			)
			(layer "F.Fab")
		)
		(pad "1" smd circle
			(at -0.40005 0)
			(size 0 0)
			(layers "F.Cu" "F.Mask" "F.Paste")
			(net "PCA9552_MB1_A2")
		)
		(pad "2" smd circle
			(at 0.40005 0)
			(size 0 0)
			(layers "F.Cu" "F.Mask" "F.Paste")
			(net "GND")
		)
	)
	(footprint ""
		(layer "F.Cu")
		(at 20.828 -178.816)
		(property "Reference" "R5687"
			(at 0 0 0)
			(layer "F.SilkS")
			(hide yes)
			(effects
				(font
					(size 1.27 1.27)
				)
			)
		)
		(property "Value" ""
			(at 0 0 0)
			(layer "F.Fab")
			(effects
				(font
					(size 1.27 1.27)
				)
			)
		)
		(duplicate_pad_numbers_are_jumpers no)
		(fp_line
			(start -0.7874 -0.4064)
			(end 0.7874 -0.4064)
			(stroke
				(width 0.1524)
				(type default)
			)
			(layer "F.SilkS")
		)
		(fp_line
			(start -0.7874 0.4064)
			(end -0.7874 -0.4064)
			(stroke
				(width 0.1524)
				(type default)
			)
			(layer "F.SilkS")
		)
		(fp_line
			(start 0.7874 -0.4064)
			(end 0.7874 0.4064)
			(stroke
				(width 0.1524)
				(type default)
			)
			(layer "F.SilkS")
		)
		(fp_line
			(start 0.7874 0.4064)
			(end -0.7874 0.4064)
			(stroke
				(width 0.1524)
				(type default)
			)
			(layer "F.SilkS")
		)
		(fp_line
			(start -0.67945 -0.305054)
			(end -0.12065 -0.305054)
			(stroke
				(width 0.1)
				(type default)
			)
			(layer "F.Fab")
		)
		(fp_line
			(start -0.67945 0.3048)
			(end -0.67945 -0.305054)
			(stroke
				(width 0.1)
				(type default)
			)
			(layer "F.Fab")
		)
		(fp_line
			(start -0.12065 -0.305054)
			(end -0.12065 -0.2794)
			(stroke
				(width 0.1)
				(type default)
			)
			(layer "F.Fab")
		)
		(fp_line
			(start -0.12065 -0.2794)
			(end 0.12065 -0.2794)
			(stroke
				(width 0.1)
				(type default)
			)
			(layer "F.Fab")
		)
		(fp_line
			(start -0.12065 0.2794)
			(end -0.12065 0.3048)
			(stroke
				(width 0.1)
				(type default)
			)
			(layer "F.Fab")
		)
		(fp_line
			(start -0.12065 0.3048)
			(end -0.67945 0.3048)
			(stroke
				(width 0.1)
				(type default)
			)
			(layer "F.Fab")
		)
		(fp_line
			(start 0.120396 0.2794)
			(end -0.12065 0.2794)
			(stroke
				(width 0.1)
				(type default)
			)
			(layer "F.Fab")
		)
		(fp_line
			(start 0.120396 0.3048)
			(end 0.120396 0.2794)
			(stroke
				(width 0.1)
				(type default)
			)
			(layer "F.Fab")
		)
		(fp_line
			(start 0.12065 -0.3048)
			(end 0.67945 -0.3048)
			(stroke
				(width 0.1)
				(type default)
			)
			(layer "F.Fab")
		)
		(fp_line
			(start 0.12065 -0.2794)
			(end 0.12065 -0.3048)
			(stroke
				(width 0.1)
				(type default)
			)
			(layer "F.Fab")
		)
		(fp_line
			(start 0.67945 -0.3048)
			(end 0.67945 0.3048)
			(stroke
				(width 0.1)
				(type default)
			)
			(layer "F.Fab")
		)
		(fp_line
			(start 0.67945 0.3048)
			(end 0.120396 0.3048)
			(stroke
				(width 0.1)
				(type default)
			)
			(layer "F.Fab")
		)
		(pad "1" smd circle
			(at -0.40005 0)
			(size 0 0)
			(layers "F.Cu" "F.Mask" "F.Paste")
			(net "FM_BOARD_ID1")
		)
		(pad "2" smd circle
			(at 0.40005 0)
			(size 0 0)
			(layers "F.Cu" "F.Mask" "F.Paste")
			(net "GND")
		)
	)
	(footprint ""
		(layer "F.Cu")
		(at 14.351 -293.624 180)
		(property "Reference" "R5697"
			(at 0 0 180)
			(layer "F.SilkS")
			(hide yes)
			(effects
				(font
					(size 1.27 1.27)
				)
			)
		)
		(property "Value" ""
			(at 0 0 180)
			(layer "F.Fab")
			(effects
				(font
					(size 1.27 1.27)
				)
			)
		)
		(duplicate_pad_numbers_are_jumpers no)
		(fp_line
			(start 0.7874 0.4064)
			(end -0.7874 0.4064)
			(stroke
				(width 0.1524)
				(type default)
			)
			(layer "F.SilkS")
		)
		(fp_line
			(start 0.7874 -0.4064)
			(end 0.7874 0.4064)
			(stroke
				(width 0.1524)
				(type default)
			)
			(layer "F.SilkS")
		)
		(fp_line
			(start -0.7874 0.4064)
			(end -0.7874 -0.4064)
			(stroke
				(width 0.1524)
				(type default)
			)
			(layer "F.SilkS")
		)
		(fp_line
			(start -0.7874 -0.4064)
			(end 0.7874 -0.4064)
			(stroke
				(width 0.1524)
				(type default)
			)
			(layer "F.SilkS")
		)
		(fp_line
			(start 0.67945 0.3048)
			(end 0.120396 0.3048)
			(stroke
				(width 0.1)
				(type default)
			)
			(layer "F.Fab")
		)
		(fp_line
			(start 0.67945 -0.3048)
			(end 0.67945 0.3048)
			(stroke
				(width 0.1)
				(type default)
			)
			(layer "F.Fab")
		)
		(fp_line
			(start 0.12065 -0.2794)
			(end 0.12065 -0.3048)
			(stroke
				(width 0.1)
				(type default)
			)
			(layer "F.Fab")
		)
		(fp_line
			(start 0.12065 -0.3048)
			(end 0.67945 -0.3048)
			(stroke
				(width 0.1)
				(type default)
			)
			(layer "F.Fab")
		)
		(fp_line
			(start 0.120396 0.3048)
			(end 0.120396 0.2794)
			(stroke
				(width 0.1)
				(type default)
			)
			(layer "F.Fab")
		)
		(fp_line
			(start 0.120396 0.2794)
			(end -0.12065 0.2794)
			(stroke
				(width 0.1)
				(type default)
			)
			(layer "F.Fab")
		)
		(fp_line
			(start -0.12065 0.3048)
			(end -0.67945 0.3048)
			(stroke
				(width 0.1)
				(type default)
			)
			(layer "F.Fab")
		)
		(fp_line
			(start -0.12065 0.2794)
			(end -0.12065 0.3048)
			(stroke
				(width 0.1)
				(type default)
			)
			(layer "F.Fab")
		)
		(fp_line
			(start -0.12065 -0.2794)
			(end 0.12065 -0.2794)
			(stroke
				(width 0.1)
				(type default)
			)
			(layer "F.Fab")
		)
		(fp_line
			(start -0.12065 -0.305054)
			(end -0.12065 -0.2794)
			(stroke
				(width 0.1)
				(type default)
			)
			(layer "F.Fab")
		)
		(fp_line
			(start -0.67945 0.3048)
			(end -0.67945 -0.305054)
			(stroke
				(width 0.1)
				(type default)
			)
			(layer "F.Fab")
		)
		(fp_line
			(start -0.67945 -0.305054)
			(end -0.12065 -0.305054)
			(stroke
				(width 0.1)
				(type default)
			)
			(layer "F.Fab")
		)
		(pad "1" smd rect
			(at -0.40005 0)
			(size 0.4572 0.508)
			(layers "F.Cu" "F.Mask" "F.Paste")
			(net "P12V_LED_FAN7")
		)
		(pad "2" smd rect
			(at 0.40005 0)
			(size 0.4572 0.508)
			(layers "F.Cu" "F.Mask" "F.Paste")
			(net "P12V_LED_R_FAN7")
		)
	)
	(footprint ""
		(layer "F.Cu")
		(at 37.338 -293.624)
		(property "Reference" "R5414"
			(at 0 0 0)
			(layer "F.SilkS")
			(hide yes)
			(effects
				(font
					(size 1.27 1.27)
				)
			)
		)
		(property "Value" ""
			(at 0 0 0)
			(layer "F.Fab")
			(effects
				(font
					(size 1.27 1.27)
				)
			)
		)
		(duplicate_pad_numbers_are_jumpers no)
		(fp_line
			(start -0.7874 -0.4064)
			(end 0.7874 -0.4064)
			(stroke
				(width 0.1524)
				(type default)
			)
			(layer "F.SilkS")
		)
		(fp_line
			(start -0.7874 0.4064)
			(end -0.7874 -0.4064)
			(stroke
				(width 0.1524)
				(type default)
			)
			(layer "F.SilkS")
		)
		(fp_line
			(start 0.7874 -0.4064)
			(end 0.7874 0.4064)
			(stroke
				(width 0.1524)
				(type default)
			)
			(layer "F.SilkS")
		)
		(fp_line
			(start 0.7874 0.4064)
			(end -0.7874 0.4064)
			(stroke
				(width 0.1524)
				(type default)
			)
			(layer "F.SilkS")
		)
		(fp_line
			(start -0.67945 -0.305054)
			(end -0.12065 -0.305054)
			(stroke
				(width 0.1)
				(type default)
			)
			(layer "F.Fab")
		)
		(fp_line
			(start -0.67945 0.3048)
			(end -0.67945 -0.305054)
			(stroke
				(width 0.1)
				(type default)
			)
			(layer "F.Fab")
		)
		(fp_line
			(start -0.12065 -0.305054)
			(end -0.12065 -0.2794)
			(stroke
				(width 0.1)
				(type default)
			)
			(layer "F.Fab")
		)
		(fp_line
			(start -0.12065 -0.2794)
			(end 0.12065 -0.2794)
			(stroke
				(width 0.1)
				(type default)
			)
			(layer "F.Fab")
		)
		(fp_line
			(start -0.12065 0.2794)
			(end -0.12065 0.3048)
			(stroke
				(width 0.1)
				(type default)
			)
			(layer "F.Fab")
		)
		(fp_line
			(start -0.12065 0.3048)
			(end -0.67945 0.3048)
			(stroke
				(width 0.1)
				(type default)
			)
			(layer "F.Fab")
		)
		(fp_line
			(start 0.120396 0.2794)
			(end -0.12065 0.2794)
			(stroke
				(width 0.1)
				(type default)
			)
			(layer "F.Fab")
		)
		(fp_line
			(start 0.120396 0.3048)
			(end 0.120396 0.2794)
			(stroke
				(width 0.1)
				(type default)
			)
			(layer "F.Fab")
		)
		(fp_line
			(start 0.12065 -0.3048)
			(end 0.67945 -0.3048)
			(stroke
				(width 0.1)
				(type default)
			)
			(layer "F.Fab")
		)
		(fp_line
			(start 0.12065 -0.2794)
			(end 0.12065 -0.3048)
			(stroke
				(width 0.1)
				(type default)
			)
			(layer "F.Fab")
		)
		(fp_line
			(start 0.67945 -0.3048)
			(end 0.67945 0.3048)
			(stroke
				(width 0.1)
				(type default)
			)
			(layer "F.Fab")
		)
		(fp_line
			(start 0.67945 0.3048)
			(end 0.120396 0.3048)
			(stroke
				(width 0.1)
				(type default)
			)
			(layer "F.Fab")
		)
		(pad "1" smd rect
			(at -0.40005 0 180)
			(size 0.4572 0.508)
			(layers "F.Cu" "F.Mask" "F.Paste")
			(net "FAN_0_FAIL_LED_R_N")
		)
		(pad "2" smd rect
			(at 0.40005 0 180)
			(size 0.4572 0.508)
			(layers "F.Cu" "F.Mask" "F.Paste")
			(net "FAN_0_FAIL_R_LED_N")
		)
	)
	(footprint ""
		(layer "F.Cu")
		(at 42.291 -259.461)
		(property "Reference" "PR5"
			(at 0 0 0)
			(layer "F.SilkS")
			(hide yes)
			(effects
				(font
					(size 1.27 1.27)
				)
			)
		)
		(property "Value" ""
			(at 0 0 0)
			(layer "F.Fab")
			(effects
				(font
					(size 1.27 1.27)
				)
			)
		)
		(duplicate_pad_numbers_are_jumpers no)
		(fp_line
			(start -0.7874 -0.4064)
			(end 0.7874 -0.4064)
			(stroke
				(width 0.1524)
				(type default)
			)
			(layer "F.SilkS")
		)
		(fp_line
			(start -0.7874 0.4064)
			(end -0.7874 -0.4064)
			(stroke
				(width 0.1524)
				(type default)
			)
			(layer "F.SilkS")
		)
		(fp_line
			(start 0.7874 -0.4064)
			(end 0.7874 0.4064)
			(stroke
				(width 0.1524)
				(type default)
			)
			(layer "F.SilkS")
		)
		(fp_line
			(start 0.7874 0.4064)
			(end -0.7874 0.4064)
			(stroke
				(width 0.1524)
				(type default)
			)
			(layer "F.SilkS")
		)
		(fp_line
			(start -0.67945 -0.305054)
			(end -0.12065 -0.305054)
			(stroke
				(width 0.1)
				(type default)
			)
			(layer "F.Fab")
		)
		(fp_line
			(start -0.67945 0.3048)
			(end -0.67945 -0.305054)
			(stroke
				(width 0.1)
				(type default)
			)
			(layer "F.Fab")
		)
		(fp_line
			(start -0.12065 -0.305054)
			(end -0.12065 -0.2794)
			(stroke
				(width 0.1)
				(type default)
			)
			(layer "F.Fab")
		)
		(fp_line
			(start -0.12065 -0.2794)
			(end 0.12065 -0.2794)
			(stroke
				(width 0.1)
				(type default)
			)
			(layer "F.Fab")
		)
		(fp_line
			(start -0.12065 0.2794)
			(end -0.12065 0.3048)
			(stroke
				(width 0.1)
				(type default)
			)
			(layer "F.Fab")
		)
		(fp_line
			(start -0.12065 0.3048)
			(end -0.67945 0.3048)
			(stroke
				(width 0.1)
				(type default)
			)
			(layer "F.Fab")
		)
		(fp_line
			(start 0.120396 0.2794)
			(end -0.12065 0.2794)
			(stroke
				(width 0.1)
				(type default)
			)
			(layer "F.Fab")
		)
		(fp_line
			(start 0.120396 0.3048)
			(end 0.120396 0.2794)
			(stroke
				(width 0.1)
				(type default)
			)
			(layer "F.Fab")
		)
		(fp_line
			(start 0.12065 -0.3048)
			(end 0.67945 -0.3048)
			(stroke
				(width 0.1)
				(type default)
			)
			(layer "F.Fab")
		)
		(fp_line
			(start 0.12065 -0.2794)
			(end 0.12065 -0.3048)
			(stroke
				(width 0.1)
				(type default)
			)
			(layer "F.Fab")
		)
		(fp_line
			(start 0.67945 -0.3048)
			(end 0.67945 0.3048)
			(stroke
				(width 0.1)
				(type default)
			)
			(layer "F.Fab")
		)
		(fp_line
			(start 0.67945 0.3048)
			(end 0.120396 0.3048)
			(stroke
				(width 0.1)
				(type default)
			)
			(layer "F.Fab")
		)
		(pad "1" smd circle
			(at -0.40005 0)
			(size 0 0)
			(layers "F.Cu" "F.Mask" "F.Paste")
			(net "FAN_0_P3V_R")
		)
		(pad "2" smd circle
			(at 0.40005 0)
			(size 0 0)
			(layers "F.Cu" "F.Mask" "F.Paste")
			(net "FAN_0_MODE")
		)
	)
	(footprint ""
		(layer "F.Cu")
		(at 43.561 -173.863)
		(property "Reference" "R5098"
			(at 0 0 0)
			(layer "F.SilkS")
			(hide yes)
			(effects
				(font
					(size 1.27 1.27)
				)
			)
		)
		(property "Value" ""
			(at 0 0 0)
			(layer "F.Fab")
			(effects
				(font
					(size 1.27 1.27)
				)
			)
		)
		(duplicate_pad_numbers_are_jumpers no)
		(fp_line
			(start -0.7874 -0.4064)
			(end 0.7874 -0.4064)
			(stroke
				(width 0.1524)
				(type default)
			)
			(layer "F.SilkS")
		)
		(fp_line
			(start -0.7874 0.4064)
			(end -0.7874 -0.4064)
			(stroke
				(width 0.1524)
				(type default)
			)
			(layer "F.SilkS")
		)
		(fp_line
			(start 0.7874 -0.4064)
			(end 0.7874 0.4064)
			(stroke
				(width 0.1524)
				(type default)
			)
			(layer "F.SilkS")
		)
		(fp_line
			(start 0.7874 0.4064)
			(end -0.7874 0.4064)
			(stroke
				(width 0.1524)
				(type default)
			)
			(layer "F.SilkS")
		)
		(fp_line
			(start -0.67945 -0.305054)
			(end -0.12065 -0.305054)
			(stroke
				(width 0.1)
				(type default)
			)
			(layer "F.Fab")
		)
		(fp_line
			(start -0.67945 0.3048)
			(end -0.67945 -0.305054)
			(stroke
				(width 0.1)
				(type default)
			)
			(layer "F.Fab")
		)
		(fp_line
			(start -0.12065 -0.305054)
			(end -0.12065 -0.2794)
			(stroke
				(width 0.1)
				(type default)
			)
			(layer "F.Fab")
		)
		(fp_line
			(start -0.12065 -0.2794)
			(end 0.12065 -0.2794)
			(stroke
				(width 0.1)
				(type default)
			)
			(layer "F.Fab")
		)
		(fp_line
			(start -0.12065 0.2794)
			(end -0.12065 0.3048)
			(stroke
				(width 0.1)
				(type default)
			)
			(layer "F.Fab")
		)
		(fp_line
			(start -0.12065 0.3048)
			(end -0.67945 0.3048)
			(stroke
				(width 0.1)
				(type default)
			)
			(layer "F.Fab")
		)
		(fp_line
			(start 0.120396 0.2794)
			(end -0.12065 0.2794)
			(stroke
				(width 0.1)
				(type default)
			)
			(layer "F.Fab")
		)
		(fp_line
			(start 0.120396 0.3048)
			(end 0.120396 0.2794)
			(stroke
				(width 0.1)
				(type default)
			)
			(layer "F.Fab")
		)
		(fp_line
			(start 0.12065 -0.3048)
			(end 0.67945 -0.3048)
			(stroke
				(width 0.1)
				(type default)
			)
			(layer "F.Fab")
		)
		(fp_line
			(start 0.12065 -0.2794)
			(end 0.12065 -0.3048)
			(stroke
				(width 0.1)
				(type default)
			)
			(layer "F.Fab")
		)
		(fp_line
			(start 0.67945 -0.3048)
			(end 0.67945 0.3048)
			(stroke
				(width 0.1)
				(type default)
			)
			(layer "F.Fab")
		)
		(fp_line
			(start 0.67945 0.3048)
			(end 0.120396 0.3048)
			(stroke
				(width 0.1)
				(type default)
			)
			(layer "F.Fab")
		)
		(pad "1" smd circle
			(at -0.40005 0)
			(size 0 0)
			(layers "F.Cu" "F.Mask" "F.Paste")
			(net "FAN_2_OK_LED")
		)
		(pad "2" smd circle
			(at 0.40005 0)
			(size 0 0)
			(layers "F.Cu" "F.Mask" "F.Paste")
			(net "FAN_2_OK_R_LED")
		)
	)
	(footprint ""
		(layer "F.Cu")
		(at 32.893 -114.709956)
		(property "Reference" "D280"
			(at 0.254 1.452626 0)
			(unlocked yes)
			(layer "F.SilkS")
			(effects
				(font
					(size 0.7874 0.5842)
					(thickness 0.1524)
				)
				(justify left)
			)
		)
		(property "Value" ""
			(at 0 0 0)
			(layer "F.Fab")
			(effects
				(font
					(size 1.27 1.27)
				)
			)
		)
		(duplicate_pad_numbers_are_jumpers no)
		(fp_line
			(start -0.854964 -0.450088)
			(end -0.854964 0.450088)
			(stroke
				(width 0.1524)
				(type default)
			)
			(layer "F.SilkS")
		)
		(fp_line
			(start -0.854964 0.450088)
			(end 0.925068 0.450088)
			(stroke
				(width 0.1524)
				(type default)
			)
			(layer "F.SilkS")
		)
		(fp_line
			(start 0.845058 0.4064)
			(end 0.845058 -0.381)
			(stroke
				(width 0.1524)
				(type default)
			)
			(layer "F.SilkS")
		)
		(fp_line
			(start 0.870458 -0.2794)
			(end 0.845058 0.4064)
			(stroke
				(width 0.1524)
				(type default)
			)
			(layer "F.SilkS")
		)
		(fp_line
			(start 0.94488 -0.450088)
			(end -0.854964 -0.450088)
			(stroke
				(width 0.1524)
				(type default)
			)
			(layer "F.SilkS")
		)
		(fp_line
			(start 0.94488 0.450088)
			(end 0.94488 -0.450088)
			(stroke
				(width 0.1524)
				(type default)
			)
			(layer "F.SilkS")
		)
		(fp_line
			(start -0.54991 -0.350012)
			(end -0.54991 0.350012)
			(stroke
				(width 0.1)
				(type default)
			)
			(layer "F.Fab")
		)
		(fp_line
			(start -0.54991 0.350012)
			(end 0.54991 0.350012)
			(stroke
				(width 0.1)
				(type default)
			)
			(layer "F.Fab")
		)
		(fp_line
			(start 0.54991 -0.350012)
			(end -0.54991 -0.350012)
			(stroke
				(width 0.1)
				(type default)
			)
			(layer "F.Fab")
		)
		(fp_line
			(start 0.54991 0.350012)
			(end 0.54991 -0.350012)
			(stroke
				(width 0.1)
				(type default)
			)
			(layer "F.Fab")
		)
		(fp_text user "+"
			(at -0.635 0.251206 180)
			(unlocked yes)
			(layer "F.SilkS")
			(effects
				(font
					(size 1.905 1.4224)
					(thickness 0.1524)
				)
				(justify left)
			)
		)
		(fp_text user "-"
			(at 1.27 1.013206 180)
			(unlocked yes)
			(layer "F.SilkS")
			(effects
				(font
					(size 1.905 1.4224)
					(thickness 0.1524)
				)
				(justify left)
			)
		)
		(fp_text user "+"
			(at -0.808228 0.239014 180)
			(unlocked yes)
			(layer "F.Fab")
			(effects
				(font
					(size 1.905 1.4224)
					(thickness 0.1524)
				)
				(justify left)
			)
		)
		(fp_text user "-"
			(at 2.48539 0.239014 180)
			(unlocked yes)
			(layer "F.Fab")
			(effects
				(font
					(size 1.905 1.4224)
					(thickness 0.1524)
				)
				(justify left)
			)
		)
		(pad "A" smd rect
			(at -0.424942 0)
			(size 0.5588 0.6096)
			(layers "F.Cu" "F.Mask" "F.Paste")
			(net "GND")
		)
		(pad "C" smd rect
			(at 0.424942 0 180)
			(size 0.5588 0.6096)
			(layers "F.Cu" "F.Mask" "F.Paste")
			(net "FAN_2_PWM_IL_R")
		)
	)
	(footprint ""
		(layer "F.Cu")
		(at 30.353 -189.23)
		(property "Reference" "R4955"
			(at 0 0 0)
			(layer "F.SilkS")
			(hide yes)
			(effects
				(font
					(size 1.27 1.27)
				)
			)
		)
		(property "Value" ""
			(at 0 0 0)
			(layer "F.Fab")
			(effects
				(font
					(size 1.27 1.27)
				)
			)
		)
		(duplicate_pad_numbers_are_jumpers no)
		(fp_line
			(start -0.7874 -0.4064)
			(end 0.7874 -0.4064)
			(stroke
				(width 0.1524)
				(type default)
			)
			(layer "F.SilkS")
		)
		(fp_line
			(start -0.7874 0.4064)
			(end -0.7874 -0.4064)
			(stroke
				(width 0.1524)
				(type default)
			)
			(layer "F.SilkS")
		)
		(fp_line
			(start 0.7874 -0.4064)
			(end 0.7874 0.4064)
			(stroke
				(width 0.1524)
				(type default)
			)
			(layer "F.SilkS")
		)
		(fp_line
			(start 0.7874 0.4064)
			(end -0.7874 0.4064)
			(stroke
				(width 0.1524)
				(type default)
			)
			(layer "F.SilkS")
		)
		(fp_line
			(start -0.67945 -0.305054)
			(end -0.12065 -0.305054)
			(stroke
				(width 0.1)
				(type default)
			)
			(layer "F.Fab")
		)
		(fp_line
			(start -0.67945 0.3048)
			(end -0.67945 -0.305054)
			(stroke
				(width 0.1)
				(type default)
			)
			(layer "F.Fab")
		)
		(fp_line
			(start -0.12065 -0.305054)
			(end -0.12065 -0.2794)
			(stroke
				(width 0.1)
				(type default)
			)
			(layer "F.Fab")
		)
		(fp_line
			(start -0.12065 -0.2794)
			(end 0.12065 -0.2794)
			(stroke
				(width 0.1)
				(type default)
			)
			(layer "F.Fab")
		)
		(fp_line
			(start -0.12065 0.2794)
			(end -0.12065 0.3048)
			(stroke
				(width 0.1)
				(type default)
			)
			(layer "F.Fab")
		)
		(fp_line
			(start -0.12065 0.3048)
			(end -0.67945 0.3048)
			(stroke
				(width 0.1)
				(type default)
			)
			(layer "F.Fab")
		)
		(fp_line
			(start 0.120396 0.2794)
			(end -0.12065 0.2794)
			(stroke
				(width 0.1)
				(type default)
			)
			(layer "F.Fab")
		)
		(fp_line
			(start 0.120396 0.3048)
			(end 0.120396 0.2794)
			(stroke
				(width 0.1)
				(type default)
			)
			(layer "F.Fab")
		)
		(fp_line
			(start 0.12065 -0.3048)
			(end 0.67945 -0.3048)
			(stroke
				(width 0.1)
				(type default)
			)
			(layer "F.Fab")
		)
		(fp_line
			(start 0.12065 -0.2794)
			(end 0.12065 -0.3048)
			(stroke
				(width 0.1)
				(type default)
			)
			(layer "F.Fab")
		)
		(fp_line
			(start 0.67945 -0.3048)
			(end 0.67945 0.3048)
			(stroke
				(width 0.1)
				(type default)
			)
			(layer "F.Fab")
		)
		(fp_line
			(start 0.67945 0.3048)
			(end 0.120396 0.3048)
			(stroke
				(width 0.1)
				(type default)
			)
			(layer "F.Fab")
		)
		(pad "1" smd circle
			(at -0.40005 0)
			(size 0 0)
			(layers "F.Cu" "F.Mask" "F.Paste")
			(net "P3V3_AUX")
		)
		(pad "2" smd circle
			(at 0.40005 0)
			(size 0 0)
			(layers "F.Cu" "F.Mask" "F.Paste")
			(net "P52V_FAN_4_BUFF_EN")
		)
	)
	(footprint ""
		(layer "F.Cu")
		(at 36.83 -198.374 90)
		(property "Reference" "R5691"
			(at 0 0 90)
			(layer "F.SilkS")
			(hide yes)
			(effects
				(font
					(size 1.27 1.27)
				)
			)
		)
		(property "Value" ""
			(at 0 0 90)
			(layer "F.Fab")
			(effects
				(font
					(size 1.27 1.27)
				)
			)
		)
		(duplicate_pad_numbers_are_jumpers no)
		(fp_line
			(start 0.7874 -0.4064)
			(end 0.7874 0.4064)
			(stroke
				(width 0.1524)
				(type default)
			)
			(layer "F.SilkS")
		)
		(fp_line
			(start -0.7874 -0.4064)
			(end 0.7874 -0.4064)
			(stroke
				(width 0.1524)
				(type default)
			)
			(layer "F.SilkS")
		)
		(fp_line
			(start 0.7874 0.4064)
			(end -0.7874 0.4064)
			(stroke
				(width 0.1524)
				(type default)
			)
			(layer "F.SilkS")
		)
		(fp_line
			(start -0.7874 0.4064)
			(end -0.7874 -0.4064)
			(stroke
				(width 0.1524)
				(type default)
			)
			(layer "F.SilkS")
		)
		(fp_line
			(start -0.12065 -0.305054)
			(end -0.12065 -0.2794)
			(stroke
				(width 0.1)
				(type default)
			)
			(layer "F.Fab")
		)
		(fp_line
			(start -0.67945 -0.305054)
			(end -0.12065 -0.305054)
			(stroke
				(width 0.1)
				(type default)
			)
			(layer "F.Fab")
		)
		(fp_line
			(start 0.67945 -0.3048)
			(end 0.67945 0.3048)
			(stroke
				(width 0.1)
				(type default)
			)
			(layer "F.Fab")
		)
		(fp_line
			(start 0.12065 -0.3048)
			(end 0.67945 -0.3048)
			(stroke
				(width 0.1)
				(type default)
			)
			(layer "F.Fab")
		)
		(fp_line
			(start 0.12065 -0.2794)
			(end 0.12065 -0.3048)
			(stroke
				(width 0.1)
				(type default)
			)
			(layer "F.Fab")
		)
		(fp_line
			(start -0.12065 -0.2794)
			(end 0.12065 -0.2794)
			(stroke
				(width 0.1)
				(type default)
			)
			(layer "F.Fab")
		)
		(fp_line
			(start 0.120396 0.2794)
			(end -0.12065 0.2794)
			(stroke
				(width 0.1)
				(type default)
			)
			(layer "F.Fab")
		)
		(fp_line
			(start -0.12065 0.2794)
			(end -0.12065 0.3048)
			(stroke
				(width 0.1)
				(type default)
			)
			(layer "F.Fab")
		)
		(fp_line
			(start 0.67945 0.3048)
			(end 0.120396 0.3048)
			(stroke
				(width 0.1)
				(type default)
			)
			(layer "F.Fab")
		)
		(fp_line
			(start 0.120396 0.3048)
			(end 0.120396 0.2794)
			(stroke
				(width 0.1)
				(type default)
			)
			(layer "F.Fab")
		)
		(fp_line
			(start -0.12065 0.3048)
			(end -0.67945 0.3048)
			(stroke
				(width 0.1)
				(type default)
			)
			(layer "F.Fab")
		)
		(fp_line
			(start -0.67945 0.3048)
			(end -0.67945 -0.305054)
			(stroke
				(width 0.1)
				(type default)
			)
			(layer "F.Fab")
		)
		(pad "1" smd rect
			(at -0.40005 0 270)
			(size 0.4572 0.508)
			(layers "F.Cu" "F.Mask" "F.Paste")
			(net "P12V_LED_FAN1")
		)
		(pad "2" smd rect
			(at 0.40005 0 270)
			(size 0.4572 0.508)
			(layers "F.Cu" "F.Mask" "F.Paste")
			(net "P12V_LED_R_FAN1")
		)
	)
	(footprint ""
		(layer "F.Cu")
		(at 17.399 -110.49 180)
		(property "Reference" "U363"
			(at -1.651 1.37033 0)
			(unlocked yes)
			(layer "F.SilkS")
			(effects
				(font
					(size 0.7874 0.5842)
					(thickness 0.1524)
				)
				(justify left)
			)
		)
		(property "Value" ""
			(at 0 0 180)
			(layer "F.Fab")
			(effects
				(font
					(size 1.27 1.27)
				)
			)
		)
		(duplicate_pad_numbers_are_jumpers no)
		(fp_line
			(start 1.335278 1.100074)
			(end 1.335278 -1.100074)
			(stroke
				(width 0.1524)
				(type default)
			)
			(layer "F.SilkS")
		)
		(fp_line
			(start 1.335278 -1.100074)
			(end -1.335278 -1.100074)
			(stroke
				(width 0.1524)
				(type default)
			)
			(layer "F.SilkS")
		)
		(fp_line
			(start -1.335278 1.100074)
			(end 1.335278 1.100074)
			(stroke
				(width 0.1524)
				(type default)
			)
			(layer "F.SilkS")
		)
		(fp_line
			(start -1.335278 -1.100074)
			(end -1.335278 1.100074)
			(stroke
				(width 0.1524)
				(type default)
			)
			(layer "F.SilkS")
		)
		(fp_line
			(start 0.674878 1.100074)
			(end 0.674878 -1.100074)
			(stroke
				(width 0.1)
				(type default)
			)
			(layer "F.Fab")
		)
		(fp_line
			(start 0.674878 -1.100074)
			(end -0.674878 -1.100074)
			(stroke
				(width 0.1)
				(type default)
			)
			(layer "F.Fab")
		)
		(fp_line
			(start -0.674878 1.100074)
			(end 0.674878 1.100074)
			(stroke
				(width 0.1)
				(type default)
			)
			(layer "F.Fab")
		)
		(fp_line
			(start -0.674878 -1.100074)
			(end -0.674878 1.100074)
			(stroke
				(width 0.1)
				(type default)
			)
			(layer "F.Fab")
		)
		(pad "D" smd rect
			(at 0.8001 0 90)
			(size 0.6096 0.8128)
			(layers "F.Cu" "F.Mask" "F.Paste")
			(net "FAN_5_FAIL_LED_R_N")
		)
		(pad "G" smd rect
			(at -0.8001 -0.649986 90)
			(size 0.6096 0.8128)
			(layers "F.Cu" "F.Mask" "F.Paste")
			(net "FAN_5_FAIL_R_LED")
		)
		(pad "S" smd rect
			(at -0.8001 0.649986 90)
			(size 0.6096 0.8128)
			(layers "F.Cu" "F.Mask" "F.Paste")
			(net "GND")
		)
	)
	(footprint ""
		(layer "F.Cu")
		(at 14.224 -304.546 -90)
		(property "Reference" "D259"
			(at 1.02616 1.22555 90)
			(unlocked yes)
			(layer "F.SilkS")
			(effects
				(font
					(size 0.7874 0.5842)
					(thickness 0.1524)
				)
				(justify left)
			)
		)
		(property "Value" ""
			(at 0 0 270)
			(layer "F.Fab")
			(effects
				(font
					(size 1.27 1.27)
				)
			)
		)
		(duplicate_pad_numbers_are_jumpers no)
		(fp_line
			(start -0.854964 0.450088)
			(end 0.925068 0.450088)
			(stroke
				(width 0.1524)
				(type default)
			)
			(layer "F.SilkS")
		)
		(fp_line
			(start 0.94488 0.450088)
			(end 0.94488 -0.450088)
			(stroke
				(width 0.1524)
				(type default)
			)
			(layer "F.SilkS")
		)
		(fp_line
			(start 0.845058 0.4064)
			(end 0.845058 -0.381)
			(stroke
				(width 0.1524)
				(type default)
			)
			(layer "F.SilkS")
		)
		(fp_line
			(start 0.870458 -0.2794)
			(end 0.845058 0.4064)
			(stroke
				(width 0.1524)
				(type default)
			)
			(layer "F.SilkS")
		)
		(fp_line
			(start -0.854964 -0.450088)
			(end -0.854964 0.450088)
			(stroke
				(width 0.1524)
				(type default)
			)
			(layer "F.SilkS")
		)
		(fp_line
			(start 0.94488 -0.450088)
			(end -0.854964 -0.450088)
			(stroke
				(width 0.1524)
				(type default)
			)
			(layer "F.SilkS")
		)
		(fp_line
			(start -0.54991 0.350012)
			(end 0.54991 0.350012)
			(stroke
				(width 0.1)
				(type default)
			)
			(layer "F.Fab")
		)
		(fp_line
			(start 0.54991 0.350012)
			(end 0.54991 -0.350012)
			(stroke
				(width 0.1)
				(type default)
			)
			(layer "F.Fab")
		)
		(fp_line
			(start -0.54991 -0.350012)
			(end -0.54991 0.350012)
			(stroke
				(width 0.1)
				(type default)
			)
			(layer "F.Fab")
		)
		(fp_line
			(start 0.54991 -0.350012)
			(end -0.54991 -0.350012)
			(stroke
				(width 0.1)
				(type default)
			)
			(layer "F.Fab")
		)
		(fp_text user "+"
			(at -1.143 0.22225 90)
			(unlocked yes)
			(layer "F.SilkS")
			(effects
				(font
					(size 1.905 1.4224)
					(thickness 0.1524)
				)
				(justify left)
			)
		)
		(fp_text user "-"
			(at 1.5113 -0.62103 90)
			(unlocked yes)
			(layer "F.SilkS")
			(effects
				(font
					(size 1.905 1.4224)
					(thickness 0.1524)
				)
				(justify left)
			)
		)
		(fp_text user "+"
			(at -0.808228 0.239014 90)
			(unlocked yes)
			(layer "F.Fab")
			(effects
				(font
					(size 1.905 1.4224)
					(thickness 0.1524)
				)
				(justify left)
			)
		)
		(fp_text user "-"
			(at 2.48539 0.239014 90)
			(unlocked yes)
			(layer "F.Fab")
			(effects
				(font
					(size 1.905 1.4224)
					(thickness 0.1524)
				)
				(justify left)
			)
		)
		(pad "A" smd rect
			(at -0.424942 0 270)
			(size 0.5588 0.6096)
			(layers "F.Cu" "F.Mask" "F.Paste")
			(net "GND")
		)
		(pad "C" smd rect
			(at 0.424942 0 90)
			(size 0.5588 0.6096)
			(layers "F.Cu" "F.Mask" "F.Paste")
			(net "FAN_7_TACH_OL_D")
		)
	)
	(footprint ""
		(layer "F.Cu")
		(at 33.274 -102.546912 180)
		(property "Reference" "R5331"
			(at 0 0 180)
			(layer "F.SilkS")
			(hide yes)
			(effects
				(font
					(size 1.27 1.27)
				)
			)
		)
		(property "Value" ""
			(at 0 0 180)
			(layer "F.Fab")
			(effects
				(font
					(size 1.27 1.27)
				)
			)
		)
		(duplicate_pad_numbers_are_jumpers no)
		(fp_line
			(start 0.7874 0.4064)
			(end -0.7874 0.4064)
			(stroke
				(width 0.1524)
				(type default)
			)
			(layer "F.SilkS")
		)
		(fp_line
			(start 0.7874 -0.4064)
			(end 0.7874 0.4064)
			(stroke
				(width 0.1524)
				(type default)
			)
			(layer "F.SilkS")
		)
		(fp_line
			(start -0.7874 0.4064)
			(end -0.7874 -0.4064)
			(stroke
				(width 0.1524)
				(type default)
			)
			(layer "F.SilkS")
		)
		(fp_line
			(start -0.7874 -0.4064)
			(end 0.7874 -0.4064)
			(stroke
				(width 0.1524)
				(type default)
			)
			(layer "F.SilkS")
		)
		(fp_line
			(start 0.67945 0.3048)
			(end 0.120396 0.3048)
			(stroke
				(width 0.1)
				(type default)
			)
			(layer "F.Fab")
		)
		(fp_line
			(start 0.67945 -0.3048)
			(end 0.67945 0.3048)
			(stroke
				(width 0.1)
				(type default)
			)
			(layer "F.Fab")
		)
		(fp_line
			(start 0.12065 -0.2794)
			(end 0.12065 -0.3048)
			(stroke
				(width 0.1)
				(type default)
			)
			(layer "F.Fab")
		)
		(fp_line
			(start 0.12065 -0.3048)
			(end 0.67945 -0.3048)
			(stroke
				(width 0.1)
				(type default)
			)
			(layer "F.Fab")
		)
		(fp_line
			(start 0.120396 0.3048)
			(end 0.120396 0.2794)
			(stroke
				(width 0.1)
				(type default)
			)
			(layer "F.Fab")
		)
		(fp_line
			(start 0.120396 0.2794)
			(end -0.12065 0.2794)
			(stroke
				(width 0.1)
				(type default)
			)
			(layer "F.Fab")
		)
		(fp_line
			(start -0.12065 0.3048)
			(end -0.67945 0.3048)
			(stroke
				(width 0.1)
				(type default)
			)
			(layer "F.Fab")
		)
		(fp_line
			(start -0.12065 0.2794)
			(end -0.12065 0.3048)
			(stroke
				(width 0.1)
				(type default)
			)
			(layer "F.Fab")
		)
		(fp_line
			(start -0.12065 -0.2794)
			(end 0.12065 -0.2794)
			(stroke
				(width 0.1)
				(type default)
			)
			(layer "F.Fab")
		)
		(fp_line
			(start -0.12065 -0.305054)
			(end -0.12065 -0.2794)
			(stroke
				(width 0.1)
				(type default)
			)
			(layer "F.Fab")
		)
		(fp_line
			(start -0.67945 0.3048)
			(end -0.67945 -0.305054)
			(stroke
				(width 0.1)
				(type default)
			)
			(layer "F.Fab")
		)
		(fp_line
			(start -0.67945 -0.305054)
			(end -0.12065 -0.305054)
			(stroke
				(width 0.1)
				(type default)
			)
			(layer "F.Fab")
		)
		(pad "1" smd rect
			(at -0.40005 0)
			(size 0.4572 0.508)
			(layers "F.Cu" "F.Mask" "F.Paste")
			(net "FAN_2_TACH_OL_R")
		)
		(pad "2" smd rect
			(at 0.40005 0)
			(size 0.4572 0.508)
			(layers "F.Cu" "F.Mask" "F.Paste")
			(net "FAN_2_TACH_OL")
		)
	)
	(footprint ""
		(layer "F.Cu")
		(at 33.02 -301.752 180)
		(property "Reference" "R5302"
			(at 0 0 180)
			(layer "F.SilkS")
			(hide yes)
			(effects
				(font
					(size 1.27 1.27)
				)
			)
		)
		(property "Value" ""
			(at 0 0 180)
			(layer "F.Fab")
			(effects
				(font
					(size 1.27 1.27)
				)
			)
		)
		(duplicate_pad_numbers_are_jumpers no)
		(fp_line
			(start 0.7874 0.4064)
			(end -0.7874 0.4064)
			(stroke
				(width 0.1524)
				(type default)
			)
			(layer "F.SilkS")
		)
		(fp_line
			(start 0.7874 -0.4064)
			(end 0.7874 0.4064)
			(stroke
				(width 0.1524)
				(type default)
			)
			(layer "F.SilkS")
		)
		(fp_line
			(start -0.7874 0.4064)
			(end -0.7874 -0.4064)
			(stroke
				(width 0.1524)
				(type default)
			)
			(layer "F.SilkS")
		)
		(fp_line
			(start -0.7874 -0.4064)
			(end 0.7874 -0.4064)
			(stroke
				(width 0.1524)
				(type default)
			)
			(layer "F.SilkS")
		)
		(fp_line
			(start 0.67945 0.3048)
			(end 0.120396 0.3048)
			(stroke
				(width 0.1)
				(type default)
			)
			(layer "F.Fab")
		)
		(fp_line
			(start 0.67945 -0.3048)
			(end 0.67945 0.3048)
			(stroke
				(width 0.1)
				(type default)
			)
			(layer "F.Fab")
		)
		(fp_line
			(start 0.12065 -0.2794)
			(end 0.12065 -0.3048)
			(stroke
				(width 0.1)
				(type default)
			)
			(layer "F.Fab")
		)
		(fp_line
			(start 0.12065 -0.3048)
			(end 0.67945 -0.3048)
			(stroke
				(width 0.1)
				(type default)
			)
			(layer "F.Fab")
		)
		(fp_line
			(start 0.120396 0.3048)
			(end 0.120396 0.2794)
			(stroke
				(width 0.1)
				(type default)
			)
			(layer "F.Fab")
		)
		(fp_line
			(start 0.120396 0.2794)
			(end -0.12065 0.2794)
			(stroke
				(width 0.1)
				(type default)
			)
			(layer "F.Fab")
		)
		(fp_line
			(start -0.12065 0.3048)
			(end -0.67945 0.3048)
			(stroke
				(width 0.1)
				(type default)
			)
			(layer "F.Fab")
		)
		(fp_line
			(start -0.12065 0.2794)
			(end -0.12065 0.3048)
			(stroke
				(width 0.1)
				(type default)
			)
			(layer "F.Fab")
		)
		(fp_line
			(start -0.12065 -0.2794)
			(end 0.12065 -0.2794)
			(stroke
				(width 0.1)
				(type default)
			)
			(layer "F.Fab")
		)
		(fp_line
			(start -0.12065 -0.305054)
			(end -0.12065 -0.2794)
			(stroke
				(width 0.1)
				(type default)
			)
			(layer "F.Fab")
		)
		(fp_line
			(start -0.67945 0.3048)
			(end -0.67945 -0.305054)
			(stroke
				(width 0.1)
				(type default)
			)
			(layer "F.Fab")
		)
		(fp_line
			(start -0.67945 -0.305054)
			(end -0.12065 -0.305054)
			(stroke
				(width 0.1)
				(type default)
			)
			(layer "F.Fab")
		)
		(pad "1" smd rect
			(at -0.40005 0)
			(size 0.4572 0.508)
			(layers "F.Cu" "F.Mask" "F.Paste")
			(net "FAN_0_TACH_IL_R")
		)
		(pad "2" smd rect
			(at 0.40005 0)
			(size 0.4572 0.508)
			(layers "F.Cu" "F.Mask" "F.Paste")
			(net "FAN_0_TACH_IL")
		)
	)
	(footprint ""
		(layer "F.Cu")
		(at 36.322 -171.577 180)
		(property "Reference" "U8"
			(at -0.889 -4.72567 0)
			(unlocked yes)
			(layer "F.SilkS")
			(effects
				(font
					(size 0.7874 0.5842)
					(thickness 0.1524)
				)
				(justify left)
			)
		)
		(property "Value" ""
			(at 0 0 180)
			(layer "F.Fab")
			(effects
				(font
					(size 1.27 1.27)
				)
			)
		)
		(duplicate_pad_numbers_are_jumpers no)
		(fp_line
			(start 2.0066 3.9624)
			(end -2.0066 3.9624)
			(stroke
				(width 0.1524)
				(type default)
			)
			(layer "F.SilkS")
		)
		(fp_line
			(start 2.0066 -3.9624)
			(end 2.0066 3.9624)
			(stroke
				(width 0.1524)
				(type default)
			)
			(layer "F.SilkS")
		)
		(fp_line
			(start 0.5842 -3.9624)
			(end 2.0066 -3.9624)
			(stroke
				(width 0.1524)
				(type default)
			)
			(layer "F.SilkS")
		)
		(fp_line
			(start 0 -3.3782)
			(end 0.5842 -3.9624)
			(stroke
				(width 0.1524)
				(type default)
			)
			(layer "F.SilkS")
		)
		(fp_line
			(start -0.5842 -3.9624)
			(end 0 -3.3782)
			(stroke
				(width 0.1524)
				(type default)
			)
			(layer "F.SilkS")
		)
		(fp_line
			(start -2.0066 3.9624)
			(end -2.0066 -3.9624)
			(stroke
				(width 0.1524)
				(type default)
			)
			(layer "F.SilkS")
		)
		(fp_line
			(start -2.0066 -3.9624)
			(end -0.5842 -3.9624)
			(stroke
				(width 0.1524)
				(type default)
			)
			(layer "F.SilkS")
		)
		(fp_poly
			(pts
				(xy -3.8862 -3.570986) (xy -4.6482 -3.189986) (xy -4.6482 -3.951986)
			)
			(stroke
				(width 0)
				(type default)
			)
			(fill yes)
			(layer "F.SilkS")
		)
		(fp_line
			(start 3.7211 3.80365)
			(end 3.7211 -3.80365)
			(stroke
				(width 0.1)
				(type default)
			)
			(layer "F.Fab")
		)
		(fp_line
			(start 3.7211 -3.80365)
			(end 2.2479 -3.80365)
			(stroke
				(width 0.1)
				(type default)
			)
			(layer "F.Fab")
		)
		(fp_line
			(start 2.2479 3.9624)
			(end 2.2479 3.80365)
			(stroke
				(width 0.1)
				(type default)
			)
			(layer "F.Fab")
		)
		(fp_line
			(start 2.2479 3.80365)
			(end 3.7211 3.80365)
			(stroke
				(width 0.1)
				(type default)
			)
			(layer "F.Fab")
		)
		(fp_line
			(start 2.2479 -3.80365)
			(end 2.2479 -3.974846)
			(stroke
				(width 0.1)
				(type default)
			)
			(layer "F.Fab")
		)
		(fp_line
			(start 2.2479 -3.974846)
			(end -2.2479 -3.974846)
			(stroke
				(width 0.1)
				(type default)
			)
			(layer "F.Fab")
		)
		(fp_line
			(start -2.2479 3.9624)
			(end 2.2479 3.9624)
			(stroke
				(width 0.1)
				(type default)
			)
			(layer "F.Fab")
		)
		(fp_line
			(start -2.2479 3.80365)
			(end -2.2479 3.9624)
			(stroke
				(width 0.1)
				(type default)
			)
			(layer "F.Fab")
		)
		(fp_line
			(start -2.2479 -3.80365)
			(end -3.724402 -3.80365)
			(stroke
				(width 0.1)
				(type default)
			)
			(layer "F.Fab")
		)
		(fp_line
			(start -2.2479 -3.974846)
			(end -2.2479 -3.80365)
			(stroke
				(width 0.1)
				(type default)
			)
			(layer "F.Fab")
		)
		(fp_line
			(start -3.7211 -3.34645)
			(end -3.7211 -3.80365)
			(stroke
				(width 0.1)
				(type default)
			)
			(layer "F.Fab")
		)
		(fp_line
			(start -3.724402 3.80365)
			(end -2.2479 3.80365)
			(stroke
				(width 0.1)
				(type default)
			)
			(layer "F.Fab")
		)
		(fp_line
			(start -3.724402 -3.80365)
			(end -3.724402 3.80365)
			(stroke
				(width 0.1)
				(type default)
			)
			(layer "F.Fab")
		)
		(fp_poly
			(pts
				(xy -3.8862 -3.570986) (xy -4.6482 -3.189986) (xy -4.6482 -3.951986)
			)
			(stroke
				(width 0)
				(type default)
			)
			(fill yes)
			(layer "F.Fab")
		)
		(pad "1" smd rect
			(at -2.921 -3.57505 90)
			(size 0.3556 1.4986)
			(layers "F.Cu" "F.Mask" "F.Paste")
			(net "PCA9552_MB1_A0")
		)
		(pad "2" smd rect
			(at -2.921 -2.925064 90)
			(size 0.3556 1.4986)
			(layers "F.Cu" "F.Mask" "F.Paste")
			(net "PCA9552_MB1_A1")
		)
		(pad "3" smd rect
			(at -2.921 -2.275078 90)
			(size 0.3556 1.4986)
			(layers "F.Cu" "F.Mask" "F.Paste")
			(net "PCA9552_MB1_A2")
		)
		(pad "4" smd rect
			(at -2.921 -1.625092 90)
			(size 0.3556 1.4986)
			(layers "F.Cu" "F.Mask" "F.Paste")
			(net "FAN_0_OK_LED")
		)
		(pad "5" smd rect
			(at -2.921 -0.975106 90)
			(size 0.3556 1.4986)
			(layers "F.Cu" "F.Mask" "F.Paste")
			(net "FAN_0_FAIL_LED")
		)
		(pad "6" smd rect
			(at -2.921 -0.32512 90)
			(size 0.3556 1.4986)
			(layers "F.Cu" "F.Mask" "F.Paste")
			(net "FAN_1_OK_LED")
		)
		(pad "7" smd rect
			(at -2.921 0.32512 90)
			(size 0.3556 1.4986)
			(layers "F.Cu" "F.Mask" "F.Paste")
			(net "FAN_1_FAIL_LED")
		)
		(pad "8" smd rect
			(at -2.921 0.975106 90)
			(size 0.3556 1.4986)
			(layers "F.Cu" "F.Mask" "F.Paste")
			(net "FAN_2_OK_LED")
		)
		(pad "9" smd rect
			(at -2.921 1.625092 90)
			(size 0.3556 1.4986)
			(layers "F.Cu" "F.Mask" "F.Paste")
			(net "FAN_2_FAIL_LED")
		)
		(pad "10" smd rect
			(at -2.921 2.275078 90)
			(size 0.3556 1.4986)
			(layers "F.Cu" "F.Mask" "F.Paste")
			(net "FAN_3_OK_LED")
		)
		(pad "11" smd rect
			(at -2.921 2.925064 90)
			(size 0.3556 1.4986)
			(layers "F.Cu" "F.Mask" "F.Paste")
			(net "FAN_3_FAIL_LED")
		)
		(pad "12" smd rect
			(at -2.921 3.57505 90)
			(size 0.3556 1.4986)
			(layers "F.Cu" "F.Mask" "F.Paste")
			(net "GND")
		)
		(pad "13" smd rect
			(at 2.921 3.57505 90)
			(size 0.3556 1.4986)
			(layers "F.Cu" "F.Mask" "F.Paste")
			(net "FAN_4_OK_LED")
		)
		(pad "14" smd rect
			(at 2.921 2.925064 90)
			(size 0.3556 1.4986)
			(layers "F.Cu" "F.Mask" "F.Paste")
			(net "FAN_4_FAIL_LED")
		)
		(pad "15" smd rect
			(at 2.921 2.275078 90)
			(size 0.3556 1.4986)
			(layers "F.Cu" "F.Mask" "F.Paste")
			(net "FAN_5_OK_LED")
		)
		(pad "16" smd rect
			(at 2.921 1.625092 90)
			(size 0.3556 1.4986)
			(layers "F.Cu" "F.Mask" "F.Paste")
			(net "FAN_5_FAIL_LED")
		)
		(pad "17" smd rect
			(at 2.921 0.975106 90)
			(size 0.3556 1.4986)
			(layers "F.Cu" "F.Mask" "F.Paste")
			(net "FAN_6_OK_LED")
		)
		(pad "18" smd rect
			(at 2.921 0.32512 90)
			(size 0.3556 1.4986)
			(layers "F.Cu" "F.Mask" "F.Paste")
			(net "FAN_6_FAIL_LED")
		)
		(pad "19" smd rect
			(at 2.921 -0.32512 90)
			(size 0.3556 1.4986)
			(layers "F.Cu" "F.Mask" "F.Paste")
			(net "FAN_7_OK_LED")
		)
		(pad "20" smd rect
			(at 2.921 -0.975106 90)
			(size 0.3556 1.4986)
			(layers "F.Cu" "F.Mask" "F.Paste")
			(net "FAN_7_FAIL_LED")
		)
		(pad "21" smd rect
			(at 2.921 -1.625092 90)
			(size 0.3556 1.4986)
			(layers "F.Cu" "F.Mask" "F.Paste")
			(net "PU_U8_PIN2")
		)
		(pad "22" smd rect
			(at 2.921 -2.275078 90)
			(size 0.3556 1.4986)
			(layers "F.Cu" "F.Mask" "F.Paste")
			(net "SMB_PDBV_FAN_R1_IOX_SCL")
		)
		(pad "23" smd rect
			(at 2.921 -2.925064 90)
			(size 0.3556 1.4986)
			(layers "F.Cu" "F.Mask" "F.Paste")
			(net "SMB_PDBV_FAN_R1_IOX_SDA")
		)
		(pad "24" smd rect
			(at 2.921 -3.57505 90)
			(size 0.3556 1.4986)
			(layers "F.Cu" "F.Mask" "F.Paste")
			(net "P3V3_AUX")
		)
	)
	(footprint ""
		(layer "F.Cu")
		(at 40.127428 -252.386846 180)
		(property "Reference" "C2066"
			(at 0 0 180)
			(layer "F.SilkS")
			(hide yes)
			(effects
				(font
					(size 1.27 1.27)
				)
			)
		)
		(property "Value" ""
			(at 0 0 180)
			(layer "F.Fab")
			(effects
				(font
					(size 1.27 1.27)
				)
			)
		)
		(duplicate_pad_numbers_are_jumpers no)
		(fp_line
			(start 0.7874 0.4064)
			(end -0.7874 0.4064)
			(stroke
				(width 0.1524)
				(type default)
			)
			(layer "F.SilkS")
		)
		(fp_line
			(start 0.7874 -0.4064)
			(end 0.7874 0.4064)
			(stroke
				(width 0.1524)
				(type default)
			)
			(layer "F.SilkS")
		)
		(fp_line
			(start -0.7874 0.4064)
			(end -0.7874 -0.4064)
			(stroke
				(width 0.1524)
				(type default)
			)
			(layer "F.SilkS")
		)
		(fp_line
			(start -0.7874 -0.4064)
			(end 0.7874 -0.4064)
			(stroke
				(width 0.1524)
				(type default)
			)
			(layer "F.SilkS")
		)
		(fp_line
			(start 0.67945 0.3048)
			(end 0.120396 0.3048)
			(stroke
				(width 0.1)
				(type default)
			)
			(layer "F.Fab")
		)
		(fp_line
			(start 0.67945 -0.3048)
			(end 0.67945 0.3048)
			(stroke
				(width 0.1)
				(type default)
			)
			(layer "F.Fab")
		)
		(fp_line
			(start 0.12065 -0.2794)
			(end 0.12065 -0.3048)
			(stroke
				(width 0.1)
				(type default)
			)
			(layer "F.Fab")
		)
		(fp_line
			(start 0.12065 -0.3048)
			(end 0.67945 -0.3048)
			(stroke
				(width 0.1)
				(type default)
			)
			(layer "F.Fab")
		)
		(fp_line
			(start 0.120396 0.3048)
			(end 0.120396 0.2794)
			(stroke
				(width 0.1)
				(type default)
			)
			(layer "F.Fab")
		)
		(fp_line
			(start 0.120396 0.2794)
			(end -0.12065 0.2794)
			(stroke
				(width 0.1)
				(type default)
			)
			(layer "F.Fab")
		)
		(fp_line
			(start -0.12065 0.3048)
			(end -0.67945 0.3048)
			(stroke
				(width 0.1)
				(type default)
			)
			(layer "F.Fab")
		)
		(fp_line
			(start -0.12065 0.2794)
			(end -0.12065 0.3048)
			(stroke
				(width 0.1)
				(type default)
			)
			(layer "F.Fab")
		)
		(fp_line
			(start -0.12065 -0.2794)
			(end 0.12065 -0.2794)
			(stroke
				(width 0.1)
				(type default)
			)
			(layer "F.Fab")
		)
		(fp_line
			(start -0.12065 -0.305054)
			(end -0.12065 -0.2794)
			(stroke
				(width 0.1)
				(type default)
			)
			(layer "F.Fab")
		)
		(fp_line
			(start -0.67945 0.3048)
			(end -0.67945 -0.305054)
			(stroke
				(width 0.1)
				(type default)
			)
			(layer "F.Fab")
		)
		(fp_line
			(start -0.67945 -0.305054)
			(end -0.12065 -0.305054)
			(stroke
				(width 0.1)
				(type default)
			)
			(layer "F.Fab")
		)
		(pad "1" smd circle
			(at -0.40005 0 180)
			(size 0 0)
			(layers "F.Cu" "F.Mask" "F.Paste")
			(net "P3V3_AUX")
		)
		(pad "2" smd circle
			(at 0.40005 0 180)
			(size 0 0)
			(layers "F.Cu" "F.Mask" "F.Paste")
			(net "GND")
		)
	)
	(footprint ""
		(layer "F.Cu")
		(at 44.831 -314.071)
		(property "Reference" "R5648"
			(at 0 0 0)
			(layer "F.SilkS")
			(hide yes)
			(effects
				(font
					(size 1.27 1.27)
				)
			)
		)
		(property "Value" ""
			(at 0 0 0)
			(layer "F.Fab")
			(effects
				(font
					(size 1.27 1.27)
				)
			)
		)
		(duplicate_pad_numbers_are_jumpers no)
		(fp_line
			(start -0.7874 -0.4064)
			(end 0.7874 -0.4064)
			(stroke
				(width 0.1524)
				(type default)
			)
			(layer "F.SilkS")
		)
		(fp_line
			(start -0.7874 0.4064)
			(end -0.7874 -0.4064)
			(stroke
				(width 0.1524)
				(type default)
			)
			(layer "F.SilkS")
		)
		(fp_line
			(start 0.7874 -0.4064)
			(end 0.7874 0.4064)
			(stroke
				(width 0.1524)
				(type default)
			)
			(layer "F.SilkS")
		)
		(fp_line
			(start 0.7874 0.4064)
			(end -0.7874 0.4064)
			(stroke
				(width 0.1524)
				(type default)
			)
			(layer "F.SilkS")
		)
		(fp_line
			(start -0.67945 -0.305054)
			(end -0.12065 -0.305054)
			(stroke
				(width 0.1)
				(type default)
			)
			(layer "F.Fab")
		)
		(fp_line
			(start -0.67945 0.3048)
			(end -0.67945 -0.305054)
			(stroke
				(width 0.1)
				(type default)
			)
			(layer "F.Fab")
		)
		(fp_line
			(start -0.12065 -0.305054)
			(end -0.12065 -0.2794)
			(stroke
				(width 0.1)
				(type default)
			)
			(layer "F.Fab")
		)
		(fp_line
			(start -0.12065 -0.2794)
			(end 0.12065 -0.2794)
			(stroke
				(width 0.1)
				(type default)
			)
			(layer "F.Fab")
		)
		(fp_line
			(start -0.12065 0.2794)
			(end -0.12065 0.3048)
			(stroke
				(width 0.1)
				(type default)
			)
			(layer "F.Fab")
		)
		(fp_line
			(start -0.12065 0.3048)
			(end -0.67945 0.3048)
			(stroke
				(width 0.1)
				(type default)
			)
			(layer "F.Fab")
		)
		(fp_line
			(start 0.120396 0.2794)
			(end -0.12065 0.2794)
			(stroke
				(width 0.1)
				(type default)
			)
			(layer "F.Fab")
		)
		(fp_line
			(start 0.120396 0.3048)
			(end 0.120396 0.2794)
			(stroke
				(width 0.1)
				(type default)
			)
			(layer "F.Fab")
		)
		(fp_line
			(start 0.12065 -0.3048)
			(end 0.67945 -0.3048)
			(stroke
				(width 0.1)
				(type default)
			)
			(layer "F.Fab")
		)
		(fp_line
			(start 0.12065 -0.2794)
			(end 0.12065 -0.3048)
			(stroke
				(width 0.1)
				(type default)
			)
			(layer "F.Fab")
		)
		(fp_line
			(start 0.67945 -0.3048)
			(end 0.67945 0.3048)
			(stroke
				(width 0.1)
				(type default)
			)
			(layer "F.Fab")
		)
		(fp_line
			(start 0.67945 0.3048)
			(end 0.120396 0.3048)
			(stroke
				(width 0.1)
				(type default)
			)
			(layer "F.Fab")
		)
		(pad "1" smd rect
			(at -0.40005 0 180)
			(size 0.4572 0.508)
			(layers "F.Cu" "F.Mask" "F.Paste")
			(net "P12V_LED")
		)
		(pad "2" smd rect
			(at 0.40005 0 180)
			(size 0.4572 0.508)
			(layers "F.Cu" "F.Mask" "F.Paste")
			(net "U405_D1")
		)
	)
	(footprint ""
		(layer "F.Cu")
		(at 28.956 -172.593 180)
		(property "Reference" "R5108"
			(at 0 0 180)
			(layer "F.SilkS")
			(hide yes)
			(effects
				(font
					(size 1.27 1.27)
				)
			)
		)
		(property "Value" ""
			(at 0 0 180)
			(layer "F.Fab")
			(effects
				(font
					(size 1.27 1.27)
				)
			)
		)
		(duplicate_pad_numbers_are_jumpers no)
		(fp_line
			(start 0.7874 0.4064)
			(end -0.7874 0.4064)
			(stroke
				(width 0.1524)
				(type default)
			)
			(layer "F.SilkS")
		)
		(fp_line
			(start 0.7874 -0.4064)
			(end 0.7874 0.4064)
			(stroke
				(width 0.1524)
				(type default)
			)
			(layer "F.SilkS")
		)
		(fp_line
			(start -0.7874 0.4064)
			(end -0.7874 -0.4064)
			(stroke
				(width 0.1524)
				(type default)
			)
			(layer "F.SilkS")
		)
		(fp_line
			(start -0.7874 -0.4064)
			(end 0.7874 -0.4064)
			(stroke
				(width 0.1524)
				(type default)
			)
			(layer "F.SilkS")
		)
		(fp_line
			(start 0.67945 0.3048)
			(end 0.120396 0.3048)
			(stroke
				(width 0.1)
				(type default)
			)
			(layer "F.Fab")
		)
		(fp_line
			(start 0.67945 -0.3048)
			(end 0.67945 0.3048)
			(stroke
				(width 0.1)
				(type default)
			)
			(layer "F.Fab")
		)
		(fp_line
			(start 0.12065 -0.2794)
			(end 0.12065 -0.3048)
			(stroke
				(width 0.1)
				(type default)
			)
			(layer "F.Fab")
		)
		(fp_line
			(start 0.12065 -0.3048)
			(end 0.67945 -0.3048)
			(stroke
				(width 0.1)
				(type default)
			)
			(layer "F.Fab")
		)
		(fp_line
			(start 0.120396 0.3048)
			(end 0.120396 0.2794)
			(stroke
				(width 0.1)
				(type default)
			)
			(layer "F.Fab")
		)
		(fp_line
			(start 0.120396 0.2794)
			(end -0.12065 0.2794)
			(stroke
				(width 0.1)
				(type default)
			)
			(layer "F.Fab")
		)
		(fp_line
			(start -0.12065 0.3048)
			(end -0.67945 0.3048)
			(stroke
				(width 0.1)
				(type default)
			)
			(layer "F.Fab")
		)
		(fp_line
			(start -0.12065 0.2794)
			(end -0.12065 0.3048)
			(stroke
				(width 0.1)
				(type default)
			)
			(layer "F.Fab")
		)
		(fp_line
			(start -0.12065 -0.2794)
			(end 0.12065 -0.2794)
			(stroke
				(width 0.1)
				(type default)
			)
			(layer "F.Fab")
		)
		(fp_line
			(start -0.12065 -0.305054)
			(end -0.12065 -0.2794)
			(stroke
				(width 0.1)
				(type default)
			)
			(layer "F.Fab")
		)
		(fp_line
			(start -0.67945 0.3048)
			(end -0.67945 -0.305054)
			(stroke
				(width 0.1)
				(type default)
			)
			(layer "F.Fab")
		)
		(fp_line
			(start -0.67945 -0.305054)
			(end -0.12065 -0.305054)
			(stroke
				(width 0.1)
				(type default)
			)
			(layer "F.Fab")
		)
		(pad "1" smd circle
			(at -0.40005 0 180)
			(size 0 0)
			(layers "F.Cu" "F.Mask" "F.Paste")
			(net "FAN_6_FAIL_LED")
		)
		(pad "2" smd circle
			(at 0.40005 0 180)
			(size 0 0)
			(layers "F.Cu" "F.Mask" "F.Paste")
			(net "FAN_6_FAIL_R_LED")
		)
	)
	(footprint ""
		(layer "F.Cu")
		(at 16.764 -296.672 180)
		(property "Reference" "R5534"
			(at 0 0 180)
			(layer "F.SilkS")
			(hide yes)
			(effects
				(font
					(size 1.27 1.27)
				)
			)
		)
		(property "Value" ""
			(at 0 0 180)
			(layer "F.Fab")
			(effects
				(font
					(size 1.27 1.27)
				)
			)
		)
		(duplicate_pad_numbers_are_jumpers no)
		(fp_line
			(start 0.7874 0.4064)
			(end -0.7874 0.4064)
			(stroke
				(width 0.1524)
				(type default)
			)
			(layer "F.SilkS")
		)
		(fp_line
			(start 0.7874 -0.4064)
			(end 0.7874 0.4064)
			(stroke
				(width 0.1524)
				(type default)
			)
			(layer "F.SilkS")
		)
		(fp_line
			(start -0.7874 0.4064)
			(end -0.7874 -0.4064)
			(stroke
				(width 0.1524)
				(type default)
			)
			(layer "F.SilkS")
		)
		(fp_line
			(start -0.7874 -0.4064)
			(end 0.7874 -0.4064)
			(stroke
				(width 0.1524)
				(type default)
			)
			(layer "F.SilkS")
		)
		(fp_line
			(start 0.67945 0.3048)
			(end 0.120396 0.3048)
			(stroke
				(width 0.1)
				(type default)
			)
			(layer "F.Fab")
		)
		(fp_line
			(start 0.67945 -0.3048)
			(end 0.67945 0.3048)
			(stroke
				(width 0.1)
				(type default)
			)
			(layer "F.Fab")
		)
		(fp_line
			(start 0.12065 -0.2794)
			(end 0.12065 -0.3048)
			(stroke
				(width 0.1)
				(type default)
			)
			(layer "F.Fab")
		)
		(fp_line
			(start 0.12065 -0.3048)
			(end 0.67945 -0.3048)
			(stroke
				(width 0.1)
				(type default)
			)
			(layer "F.Fab")
		)
		(fp_line
			(start 0.120396 0.3048)
			(end 0.120396 0.2794)
			(stroke
				(width 0.1)
				(type default)
			)
			(layer "F.Fab")
		)
		(fp_line
			(start 0.120396 0.2794)
			(end -0.12065 0.2794)
			(stroke
				(width 0.1)
				(type default)
			)
			(layer "F.Fab")
		)
		(fp_line
			(start -0.12065 0.3048)
			(end -0.67945 0.3048)
			(stroke
				(width 0.1)
				(type default)
			)
			(layer "F.Fab")
		)
		(fp_line
			(start -0.12065 0.2794)
			(end -0.12065 0.3048)
			(stroke
				(width 0.1)
				(type default)
			)
			(layer "F.Fab")
		)
		(fp_line
			(start -0.12065 -0.2794)
			(end 0.12065 -0.2794)
			(stroke
				(width 0.1)
				(type default)
			)
			(layer "F.Fab")
		)
		(fp_line
			(start -0.12065 -0.305054)
			(end -0.12065 -0.2794)
			(stroke
				(width 0.1)
				(type default)
			)
			(layer "F.Fab")
		)
		(fp_line
			(start -0.67945 0.3048)
			(end -0.67945 -0.305054)
			(stroke
				(width 0.1)
				(type default)
			)
			(layer "F.Fab")
		)
		(fp_line
			(start -0.67945 -0.305054)
			(end -0.12065 -0.305054)
			(stroke
				(width 0.1)
				(type default)
			)
			(layer "F.Fab")
		)
		(pad "1" smd rect
			(at -0.40005 0)
			(size 0.4572 0.508)
			(layers "F.Cu" "F.Mask" "F.Paste")
			(net "P12V_LED_FAN7")
		)
		(pad "2" smd rect
			(at 0.40005 0)
			(size 0.4572 0.508)
			(layers "F.Cu" "F.Mask" "F.Paste")
			(net "FAN_7_FAIL_LED_R_N")
		)
	)
	(footprint ""
		(layer "F.Cu")
		(at 18.034 -303.911)
		(property "Reference" "R5323"
			(at 0 0 0)
			(layer "F.SilkS")
			(hide yes)
			(effects
				(font
					(size 1.27 1.27)
				)
			)
		)
		(property "Value" ""
			(at 0 0 0)
			(layer "F.Fab")
			(effects
				(font
					(size 1.27 1.27)
				)
			)
		)
		(duplicate_pad_numbers_are_jumpers no)
		(fp_line
			(start -0.7874 -0.4064)
			(end 0.7874 -0.4064)
			(stroke
				(width 0.1524)
				(type default)
			)
			(layer "F.SilkS")
		)
		(fp_line
			(start -0.7874 0.4064)
			(end -0.7874 -0.4064)
			(stroke
				(width 0.1524)
				(type default)
			)
			(layer "F.SilkS")
		)
		(fp_line
			(start 0.7874 -0.4064)
			(end 0.7874 0.4064)
			(stroke
				(width 0.1524)
				(type default)
			)
			(layer "F.SilkS")
		)
		(fp_line
			(start 0.7874 0.4064)
			(end -0.7874 0.4064)
			(stroke
				(width 0.1524)
				(type default)
			)
			(layer "F.SilkS")
		)
		(fp_line
			(start -0.67945 -0.305054)
			(end -0.12065 -0.305054)
			(stroke
				(width 0.1)
				(type default)
			)
			(layer "F.Fab")
		)
		(fp_line
			(start -0.67945 0.3048)
			(end -0.67945 -0.305054)
			(stroke
				(width 0.1)
				(type default)
			)
			(layer "F.Fab")
		)
		(fp_line
			(start -0.12065 -0.305054)
			(end -0.12065 -0.2794)
			(stroke
				(width 0.1)
				(type default)
			)
			(layer "F.Fab")
		)
		(fp_line
			(start -0.12065 -0.2794)
			(end 0.12065 -0.2794)
			(stroke
				(width 0.1)
				(type default)
			)
			(layer "F.Fab")
		)
		(fp_line
			(start -0.12065 0.2794)
			(end -0.12065 0.3048)
			(stroke
				(width 0.1)
				(type default)
			)
			(layer "F.Fab")
		)
		(fp_line
			(start -0.12065 0.3048)
			(end -0.67945 0.3048)
			(stroke
				(width 0.1)
				(type default)
			)
			(layer "F.Fab")
		)
		(fp_line
			(start 0.120396 0.2794)
			(end -0.12065 0.2794)
			(stroke
				(width 0.1)
				(type default)
			)
			(layer "F.Fab")
		)
		(fp_line
			(start 0.120396 0.3048)
			(end 0.120396 0.2794)
			(stroke
				(width 0.1)
				(type default)
			)
			(layer "F.Fab")
		)
		(fp_line
			(start 0.12065 -0.3048)
			(end 0.67945 -0.3048)
			(stroke
				(width 0.1)
				(type default)
			)
			(layer "F.Fab")
		)
		(fp_line
			(start 0.12065 -0.2794)
			(end 0.12065 -0.3048)
			(stroke
				(width 0.1)
				(type default)
			)
			(layer "F.Fab")
		)
		(fp_line
			(start 0.67945 -0.3048)
			(end 0.67945 0.3048)
			(stroke
				(width 0.1)
				(type default)
			)
			(layer "F.Fab")
		)
		(fp_line
			(start 0.67945 0.3048)
			(end 0.120396 0.3048)
			(stroke
				(width 0.1)
				(type default)
			)
			(layer "F.Fab")
		)
		(pad "1" smd rect
			(at -0.40005 0 180)
			(size 0.4572 0.508)
			(layers "F.Cu" "F.Mask" "F.Paste")
			(net "FAN_7_TACH_OL_R")
		)
		(pad "2" smd rect
			(at 0.40005 0 180)
			(size 0.4572 0.508)
			(layers "F.Cu" "F.Mask" "F.Paste")
			(net "FAN_7_TACH_OL")
		)
	)
	(footprint ""
		(layer "F.Cu")
		(at 19.558 -203.708 -90)
		(property "Reference" "R5370"
			(at 0 0 270)
			(layer "F.SilkS")
			(hide yes)
			(effects
				(font
					(size 1.27 1.27)
				)
			)
		)
		(property "Value" ""
			(at 0 0 270)
			(layer "F.Fab")
			(effects
				(font
					(size 1.27 1.27)
				)
			)
		)
		(duplicate_pad_numbers_are_jumpers no)
		(fp_line
			(start -0.7874 0.4064)
			(end -0.7874 -0.4064)
			(stroke
				(width 0.1524)
				(type default)
			)
			(layer "F.SilkS")
		)
		(fp_line
			(start 0.7874 0.4064)
			(end -0.7874 0.4064)
			(stroke
				(width 0.1524)
				(type default)
			)
			(layer "F.SilkS")
		)
		(fp_line
			(start -0.7874 -0.4064)
			(end 0.7874 -0.4064)
			(stroke
				(width 0.1524)
				(type default)
			)
			(layer "F.SilkS")
		)
		(fp_line
			(start 0.7874 -0.4064)
			(end 0.7874 0.4064)
			(stroke
				(width 0.1524)
				(type default)
			)
			(layer "F.SilkS")
		)
		(fp_line
			(start -0.67945 0.3048)
			(end -0.67945 -0.305054)
			(stroke
				(width 0.1)
				(type default)
			)
			(layer "F.Fab")
		)
		(fp_line
			(start -0.12065 0.3048)
			(end -0.67945 0.3048)
			(stroke
				(width 0.1)
				(type default)
			)
			(layer "F.Fab")
		)
		(fp_line
			(start 0.120396 0.3048)
			(end 0.120396 0.2794)
			(stroke
				(width 0.1)
				(type default)
			)
			(layer "F.Fab")
		)
		(fp_line
			(start 0.67945 0.3048)
			(end 0.120396 0.3048)
			(stroke
				(width 0.1)
				(type default)
			)
			(layer "F.Fab")
		)
		(fp_line
			(start -0.12065 0.2794)
			(end -0.12065 0.3048)
			(stroke
				(width 0.1)
				(type default)
			)
			(layer "F.Fab")
		)
		(fp_line
			(start 0.120396 0.2794)
			(end -0.12065 0.2794)
			(stroke
				(width 0.1)
				(type default)
			)
			(layer "F.Fab")
		)
		(fp_line
			(start -0.12065 -0.2794)
			(end 0.12065 -0.2794)
			(stroke
				(width 0.1)
				(type default)
			)
			(layer "F.Fab")
		)
		(fp_line
			(start 0.12065 -0.2794)
			(end 0.12065 -0.3048)
			(stroke
				(width 0.1)
				(type default)
			)
			(layer "F.Fab")
		)
		(fp_line
			(start 0.12065 -0.3048)
			(end 0.67945 -0.3048)
			(stroke
				(width 0.1)
				(type default)
			)
			(layer "F.Fab")
		)
		(fp_line
			(start 0.67945 -0.3048)
			(end 0.67945 0.3048)
			(stroke
				(width 0.1)
				(type default)
			)
			(layer "F.Fab")
		)
		(fp_line
			(start -0.67945 -0.305054)
			(end -0.12065 -0.305054)
			(stroke
				(width 0.1)
				(type default)
			)
			(layer "F.Fab")
		)
		(fp_line
			(start -0.12065 -0.305054)
			(end -0.12065 -0.2794)
			(stroke
				(width 0.1)
				(type default)
			)
			(layer "F.Fab")
		)
		(pad "1" smd circle
			(at -0.40005 0 270)
			(size 0 0)
			(layers "F.Cu" "F.Mask" "F.Paste")
			(net "P3V3_AUX")
		)
		(pad "2" smd circle
			(at 0.40005 0 270)
			(size 0 0)
			(layers "F.Cu" "F.Mask" "F.Paste")
			(net "FAN_6_FAIL_R_LED")
		)
	)
	(footprint ""
		(layer "F.Cu")
		(at 37.338 -108.712)
		(property "Reference" "D275"
			(at 0.127 1.29667 0)
			(unlocked yes)
			(layer "F.SilkS")
			(effects
				(font
					(size 0.7874 0.5842)
					(thickness 0.1524)
				)
				(justify left)
			)
		)
		(property "Value" ""
			(at 0 0 0)
			(layer "F.Fab")
			(effects
				(font
					(size 1.27 1.27)
				)
			)
		)
		(duplicate_pad_numbers_are_jumpers no)
		(fp_line
			(start -0.854964 -0.450088)
			(end -0.854964 0.450088)
			(stroke
				(width 0.1524)
				(type default)
			)
			(layer "F.SilkS")
		)
		(fp_line
			(start -0.854964 0.450088)
			(end 0.925068 0.450088)
			(stroke
				(width 0.1524)
				(type default)
			)
			(layer "F.SilkS")
		)
		(fp_line
			(start 0.845058 0.4064)
			(end 0.845058 -0.381)
			(stroke
				(width 0.1524)
				(type default)
			)
			(layer "F.SilkS")
		)
		(fp_line
			(start 0.870458 -0.2794)
			(end 0.845058 0.4064)
			(stroke
				(width 0.1524)
				(type default)
			)
			(layer "F.SilkS")
		)
		(fp_line
			(start 0.94488 -0.450088)
			(end -0.854964 -0.450088)
			(stroke
				(width 0.1524)
				(type default)
			)
			(layer "F.SilkS")
		)
		(fp_line
			(start 0.94488 0.450088)
			(end 0.94488 -0.450088)
			(stroke
				(width 0.1524)
				(type default)
			)
			(layer "F.SilkS")
		)
		(fp_line
			(start -0.54991 -0.350012)
			(end -0.54991 0.350012)
			(stroke
				(width 0.1)
				(type default)
			)
			(layer "F.Fab")
		)
		(fp_line
			(start -0.54991 0.350012)
			(end 0.54991 0.350012)
			(stroke
				(width 0.1)
				(type default)
			)
			(layer "F.Fab")
		)
		(fp_line
			(start 0.54991 -0.350012)
			(end -0.54991 -0.350012)
			(stroke
				(width 0.1)
				(type default)
			)
			(layer "F.Fab")
		)
		(fp_line
			(start 0.54991 0.350012)
			(end 0.54991 -0.350012)
			(stroke
				(width 0.1)
				(type default)
			)
			(layer "F.Fab")
		)
		(fp_text user "+"
			(at -0.56388 0.50927 180)
			(unlocked yes)
			(layer "F.SilkS")
			(effects
				(font
					(size 1.905 1.4224)
					(thickness 0.1524)
				)
				(justify left)
			)
		)
		(fp_text user "-"
			(at 2.26314 -0.40005 180)
			(unlocked yes)
			(layer "F.SilkS")
			(effects
				(font
					(size 1.905 1.4224)
					(thickness 0.1524)
				)
				(justify left)
			)
		)
		(fp_text user "+"
			(at -0.808228 0.239014 180)
			(unlocked yes)
			(layer "F.Fab")
			(effects
				(font
					(size 1.905 1.4224)
					(thickness 0.1524)
				)
				(justify left)
			)
		)
		(fp_text user "-"
			(at 2.48539 0.239014 180)
			(unlocked yes)
			(layer "F.Fab")
			(effects
				(font
					(size 1.905 1.4224)
					(thickness 0.1524)
				)
				(justify left)
			)
		)
		(pad "A" smd rect
			(at -0.424942 0)
			(size 0.5588 0.6096)
			(layers "F.Cu" "F.Mask" "F.Paste")
			(net "GND")
		)
		(pad "C" smd rect
			(at 0.424942 0 180)
			(size 0.5588 0.6096)
			(layers "F.Cu" "F.Mask" "F.Paste")
			(net "FAN_2_FAIL_R_LED_N")
		)
	)
	(footprint ""
		(layer "F.Cu")
		(at 48.26 -132.334 180)
		(property "Reference" "R5560"
			(at 0 0 180)
			(layer "F.SilkS")
			(hide yes)
			(effects
				(font
					(size 1.27 1.27)
				)
			)
		)
		(property "Value" ""
			(at 0 0 180)
			(layer "F.Fab")
			(effects
				(font
					(size 1.27 1.27)
				)
			)
		)
		(duplicate_pad_numbers_are_jumpers no)
		(fp_line
			(start 0.7874 0.4064)
			(end -0.7874 0.4064)
			(stroke
				(width 0.1524)
				(type default)
			)
			(layer "F.SilkS")
		)
		(fp_line
			(start 0.7874 -0.4064)
			(end 0.7874 0.4064)
			(stroke
				(width 0.1524)
				(type default)
			)
			(layer "F.SilkS")
		)
		(fp_line
			(start -0.7874 0.4064)
			(end -0.7874 -0.4064)
			(stroke
				(width 0.1524)
				(type default)
			)
			(layer "F.SilkS")
		)
		(fp_line
			(start -0.7874 -0.4064)
			(end 0.7874 -0.4064)
			(stroke
				(width 0.1524)
				(type default)
			)
			(layer "F.SilkS")
		)
		(fp_line
			(start 0.67945 0.3048)
			(end 0.120396 0.3048)
			(stroke
				(width 0.1)
				(type default)
			)
			(layer "F.Fab")
		)
		(fp_line
			(start 0.67945 -0.3048)
			(end 0.67945 0.3048)
			(stroke
				(width 0.1)
				(type default)
			)
			(layer "F.Fab")
		)
		(fp_line
			(start 0.12065 -0.2794)
			(end 0.12065 -0.3048)
			(stroke
				(width 0.1)
				(type default)
			)
			(layer "F.Fab")
		)
		(fp_line
			(start 0.12065 -0.3048)
			(end 0.67945 -0.3048)
			(stroke
				(width 0.1)
				(type default)
			)
			(layer "F.Fab")
		)
		(fp_line
			(start 0.120396 0.3048)
			(end 0.120396 0.2794)
			(stroke
				(width 0.1)
				(type default)
			)
			(layer "F.Fab")
		)
		(fp_line
			(start 0.120396 0.2794)
			(end -0.12065 0.2794)
			(stroke
				(width 0.1)
				(type default)
			)
			(layer "F.Fab")
		)
		(fp_line
			(start -0.12065 0.3048)
			(end -0.67945 0.3048)
			(stroke
				(width 0.1)
				(type default)
			)
			(layer "F.Fab")
		)
		(fp_line
			(start -0.12065 0.2794)
			(end -0.12065 0.3048)
			(stroke
				(width 0.1)
				(type default)
			)
			(layer "F.Fab")
		)
		(fp_line
			(start -0.12065 -0.2794)
			(end 0.12065 -0.2794)
			(stroke
				(width 0.1)
				(type default)
			)
			(layer "F.Fab")
		)
		(fp_line
			(start -0.12065 -0.305054)
			(end -0.12065 -0.2794)
			(stroke
				(width 0.1)
				(type default)
			)
			(layer "F.Fab")
		)
		(fp_line
			(start -0.67945 0.3048)
			(end -0.67945 -0.305054)
			(stroke
				(width 0.1)
				(type default)
			)
			(layer "F.Fab")
		)
		(fp_line
			(start -0.67945 -0.305054)
			(end -0.12065 -0.305054)
			(stroke
				(width 0.1)
				(type default)
			)
			(layer "F.Fab")
		)
		(pad "1" smd circle
			(at -0.40005 0 180)
			(size 0 0)
			(layers "F.Cu" "F.Mask" "F.Paste")
			(net "GND")
		)
		(pad "2" smd circle
			(at 0.40005 0 180)
			(size 0 0)
			(layers "F.Cu" "F.Mask" "F.Paste")
			(net "U403_ADD0")
		)
	)
	(footprint ""
		(layer "F.Cu")
		(at 33.02 -121.92 90)
		(property "Reference" "R4781"
			(at 0 0 90)
			(layer "F.SilkS")
			(hide yes)
			(effects
				(font
					(size 1.27 1.27)
				)
			)
		)
		(property "Value" ""
			(at 0 0 90)
			(layer "F.Fab")
			(effects
				(font
					(size 1.27 1.27)
				)
			)
		)
		(duplicate_pad_numbers_are_jumpers no)
		(fp_line
			(start 0.7874 -0.4064)
			(end 0.7874 0.4064)
			(stroke
				(width 0.1524)
				(type default)
			)
			(layer "F.SilkS")
		)
		(fp_line
			(start -0.7874 -0.4064)
			(end 0.7874 -0.4064)
			(stroke
				(width 0.1524)
				(type default)
			)
			(layer "F.SilkS")
		)
		(fp_line
			(start 0.7874 0.4064)
			(end -0.7874 0.4064)
			(stroke
				(width 0.1524)
				(type default)
			)
			(layer "F.SilkS")
		)
		(fp_line
			(start -0.7874 0.4064)
			(end -0.7874 -0.4064)
			(stroke
				(width 0.1524)
				(type default)
			)
			(layer "F.SilkS")
		)
		(fp_line
			(start -0.12065 -0.305054)
			(end -0.12065 -0.2794)
			(stroke
				(width 0.1)
				(type default)
			)
			(layer "F.Fab")
		)
		(fp_line
			(start -0.67945 -0.305054)
			(end -0.12065 -0.305054)
			(stroke
				(width 0.1)
				(type default)
			)
			(layer "F.Fab")
		)
		(fp_line
			(start 0.67945 -0.3048)
			(end 0.67945 0.3048)
			(stroke
				(width 0.1)
				(type default)
			)
			(layer "F.Fab")
		)
		(fp_line
			(start 0.12065 -0.3048)
			(end 0.67945 -0.3048)
			(stroke
				(width 0.1)
				(type default)
			)
			(layer "F.Fab")
		)
		(fp_line
			(start 0.12065 -0.2794)
			(end 0.12065 -0.3048)
			(stroke
				(width 0.1)
				(type default)
			)
			(layer "F.Fab")
		)
		(fp_line
			(start -0.12065 -0.2794)
			(end 0.12065 -0.2794)
			(stroke
				(width 0.1)
				(type default)
			)
			(layer "F.Fab")
		)
		(fp_line
			(start 0.120396 0.2794)
			(end -0.12065 0.2794)
			(stroke
				(width 0.1)
				(type default)
			)
			(layer "F.Fab")
		)
		(fp_line
			(start -0.12065 0.2794)
			(end -0.12065 0.3048)
			(stroke
				(width 0.1)
				(type default)
			)
			(layer "F.Fab")
		)
		(fp_line
			(start 0.67945 0.3048)
			(end 0.120396 0.3048)
			(stroke
				(width 0.1)
				(type default)
			)
			(layer "F.Fab")
		)
		(fp_line
			(start 0.120396 0.3048)
			(end 0.120396 0.2794)
			(stroke
				(width 0.1)
				(type default)
			)
			(layer "F.Fab")
		)
		(fp_line
			(start -0.12065 0.3048)
			(end -0.67945 0.3048)
			(stroke
				(width 0.1)
				(type default)
			)
			(layer "F.Fab")
		)
		(fp_line
			(start -0.67945 0.3048)
			(end -0.67945 -0.305054)
			(stroke
				(width 0.1)
				(type default)
			)
			(layer "F.Fab")
		)
		(pad "1" smd circle
			(at -0.40005 0 90)
			(size 0 0)
			(layers "F.Cu" "F.Mask" "F.Paste")
			(net "GND")
		)
		(pad "2" smd circle
			(at 0.40005 0 90)
			(size 0 0)
			(layers "F.Cu" "F.Mask" "F.Paste")
			(net "MAX31790_U317_ADD0")
		)
	)
	(footprint ""
		(layer "F.Cu")
		(at 30.353 -185.674)
		(property "Reference" "R4957"
			(at 0 0 0)
			(layer "F.SilkS")
			(hide yes)
			(effects
				(font
					(size 1.27 1.27)
				)
			)
		)
		(property "Value" ""
			(at 0 0 0)
			(layer "F.Fab")
			(effects
				(font
					(size 1.27 1.27)
				)
			)
		)
		(duplicate_pad_numbers_are_jumpers no)
		(fp_line
			(start -0.7874 -0.4064)
			(end 0.7874 -0.4064)
			(stroke
				(width 0.1524)
				(type default)
			)
			(layer "F.SilkS")
		)
		(fp_line
			(start -0.7874 0.4064)
			(end -0.7874 -0.4064)
			(stroke
				(width 0.1524)
				(type default)
			)
			(layer "F.SilkS")
		)
		(fp_line
			(start 0.7874 -0.4064)
			(end 0.7874 0.4064)
			(stroke
				(width 0.1524)
				(type default)
			)
			(layer "F.SilkS")
		)
		(fp_line
			(start 0.7874 0.4064)
			(end -0.7874 0.4064)
			(stroke
				(width 0.1524)
				(type default)
			)
			(layer "F.SilkS")
		)
		(fp_line
			(start -0.67945 -0.305054)
			(end -0.12065 -0.305054)
			(stroke
				(width 0.1)
				(type default)
			)
			(layer "F.Fab")
		)
		(fp_line
			(start -0.67945 0.3048)
			(end -0.67945 -0.305054)
			(stroke
				(width 0.1)
				(type default)
			)
			(layer "F.Fab")
		)
		(fp_line
			(start -0.12065 -0.305054)
			(end -0.12065 -0.2794)
			(stroke
				(width 0.1)
				(type default)
			)
			(layer "F.Fab")
		)
		(fp_line
			(start -0.12065 -0.2794)
			(end 0.12065 -0.2794)
			(stroke
				(width 0.1)
				(type default)
			)
			(layer "F.Fab")
		)
		(fp_line
			(start -0.12065 0.2794)
			(end -0.12065 0.3048)
			(stroke
				(width 0.1)
				(type default)
			)
			(layer "F.Fab")
		)
		(fp_line
			(start -0.12065 0.3048)
			(end -0.67945 0.3048)
			(stroke
				(width 0.1)
				(type default)
			)
			(layer "F.Fab")
		)
		(fp_line
			(start 0.120396 0.2794)
			(end -0.12065 0.2794)
			(stroke
				(width 0.1)
				(type default)
			)
			(layer "F.Fab")
		)
		(fp_line
			(start 0.120396 0.3048)
			(end 0.120396 0.2794)
			(stroke
				(width 0.1)
				(type default)
			)
			(layer "F.Fab")
		)
		(fp_line
			(start 0.12065 -0.3048)
			(end 0.67945 -0.3048)
			(stroke
				(width 0.1)
				(type default)
			)
			(layer "F.Fab")
		)
		(fp_line
			(start 0.12065 -0.2794)
			(end 0.12065 -0.3048)
			(stroke
				(width 0.1)
				(type default)
			)
			(layer "F.Fab")
		)
		(fp_line
			(start 0.67945 -0.3048)
			(end 0.67945 0.3048)
			(stroke
				(width 0.1)
				(type default)
			)
			(layer "F.Fab")
		)
		(fp_line
			(start 0.67945 0.3048)
			(end 0.120396 0.3048)
			(stroke
				(width 0.1)
				(type default)
			)
			(layer "F.Fab")
		)
		(pad "1" smd circle
			(at -0.40005 0)
			(size 0 0)
			(layers "F.Cu" "F.Mask" "F.Paste")
			(net "P3V3_AUX")
		)
		(pad "2" smd circle
			(at 0.40005 0)
			(size 0 0)
			(layers "F.Cu" "F.Mask" "F.Paste")
			(net "P52V_FAN_6_BUFF_EN")
		)
	)
	(footprint ""
		(layer "F.Cu")
		(at 37.211 -203.581)
		(property "Reference" "D269"
			(at 1.27 1.04267 0)
			(unlocked yes)
			(layer "F.SilkS")
			(effects
				(font
					(size 0.7874 0.5842)
					(thickness 0.1524)
				)
				(justify left)
			)
		)
		(property "Value" ""
			(at 0 0 0)
			(layer "F.Fab")
			(effects
				(font
					(size 1.27 1.27)
				)
			)
		)
		(duplicate_pad_numbers_are_jumpers no)
		(fp_line
			(start -0.854964 -0.450088)
			(end -0.854964 0.450088)
			(stroke
				(width 0.1524)
				(type default)
			)
			(layer "F.SilkS")
		)
		(fp_line
			(start -0.854964 0.450088)
			(end 0.925068 0.450088)
			(stroke
				(width 0.1524)
				(type default)
			)
			(layer "F.SilkS")
		)
		(fp_line
			(start 0.845058 0.4064)
			(end 0.845058 -0.381)
			(stroke
				(width 0.1524)
				(type default)
			)
			(layer "F.SilkS")
		)
		(fp_line
			(start 0.870458 -0.2794)
			(end 0.845058 0.4064)
			(stroke
				(width 0.1524)
				(type default)
			)
			(layer "F.SilkS")
		)
		(fp_line
			(start 0.94488 -0.450088)
			(end -0.854964 -0.450088)
			(stroke
				(width 0.1524)
				(type default)
			)
			(layer "F.SilkS")
		)
		(fp_line
			(start 0.94488 0.450088)
			(end 0.94488 -0.450088)
			(stroke
				(width 0.1524)
				(type default)
			)
			(layer "F.SilkS")
		)
		(fp_line
			(start -0.54991 -0.350012)
			(end -0.54991 0.350012)
			(stroke
				(width 0.1)
				(type default)
			)
			(layer "F.Fab")
		)
		(fp_line
			(start -0.54991 0.350012)
			(end 0.54991 0.350012)
			(stroke
				(width 0.1)
				(type default)
			)
			(layer "F.Fab")
		)
		(fp_line
			(start 0.54991 -0.350012)
			(end -0.54991 -0.350012)
			(stroke
				(width 0.1)
				(type default)
			)
			(layer "F.Fab")
		)
		(fp_line
			(start 0.54991 0.350012)
			(end 0.54991 -0.350012)
			(stroke
				(width 0.1)
				(type default)
			)
			(layer "F.Fab")
		)
		(fp_text user "+"
			(at -0.381 -1.30175 180)
			(unlocked yes)
			(layer "F.SilkS")
			(effects
				(font
					(size 1.905 1.4224)
					(thickness 0.1524)
				)
				(justify left)
			)
		)
		(fp_text user "-"
			(at 2.159 0.22225 180)
			(unlocked yes)
			(layer "F.SilkS")
			(effects
				(font
					(size 1.905 1.4224)
					(thickness 0.1524)
				)
				(justify left)
			)
		)
		(fp_text user "+"
			(at -0.808228 0.239014 180)
			(unlocked yes)
			(layer "F.Fab")
			(effects
				(font
					(size 1.905 1.4224)
					(thickness 0.1524)
				)
				(justify left)
			)
		)
		(fp_text user "-"
			(at 2.48539 0.239014 180)
			(unlocked yes)
			(layer "F.Fab")
			(effects
				(font
					(size 1.905 1.4224)
					(thickness 0.1524)
				)
				(justify left)
			)
		)
		(pad "A" smd rect
			(at -0.424942 0)
			(size 0.5588 0.6096)
			(layers "F.Cu" "F.Mask" "F.Paste")
			(net "GND")
		)
		(pad "C" smd rect
			(at 0.424942 0 180)
			(size 0.5588 0.6096)
			(layers "F.Cu" "F.Mask" "F.Paste")
			(net "FAN_1_FAIL_R_LED_N")
		)
	)
	(footprint ""
		(layer "F.Cu")
		(at 42.635932 -72.066912)
		(property "Reference" "R5420"
			(at 0 0 0)
			(layer "F.SilkS")
			(hide yes)
			(effects
				(font
					(size 1.27 1.27)
				)
			)
		)
		(property "Value" ""
			(at 0 0 0)
			(layer "F.Fab")
			(effects
				(font
					(size 1.27 1.27)
				)
			)
		)
		(duplicate_pad_numbers_are_jumpers no)
		(fp_line
			(start -0.7874 -0.4064)
			(end 0.7874 -0.4064)
			(stroke
				(width 0.1524)
				(type default)
			)
			(layer "F.SilkS")
		)
		(fp_line
			(start -0.7874 0.4064)
			(end -0.7874 -0.4064)
			(stroke
				(width 0.1524)
				(type default)
			)
			(layer "F.SilkS")
		)
		(fp_line
			(start 0.7874 -0.4064)
			(end 0.7874 0.4064)
			(stroke
				(width 0.1524)
				(type default)
			)
			(layer "F.SilkS")
		)
		(fp_line
			(start 0.7874 0.4064)
			(end -0.7874 0.4064)
			(stroke
				(width 0.1524)
				(type default)
			)
			(layer "F.SilkS")
		)
		(fp_line
			(start -0.67945 -0.305054)
			(end -0.12065 -0.305054)
			(stroke
				(width 0.1)
				(type default)
			)
			(layer "F.Fab")
		)
		(fp_line
			(start -0.67945 0.3048)
			(end -0.67945 -0.305054)
			(stroke
				(width 0.1)
				(type default)
			)
			(layer "F.Fab")
		)
		(fp_line
			(start -0.12065 -0.305054)
			(end -0.12065 -0.2794)
			(stroke
				(width 0.1)
				(type default)
			)
			(layer "F.Fab")
		)
		(fp_line
			(start -0.12065 -0.2794)
			(end 0.12065 -0.2794)
			(stroke
				(width 0.1)
				(type default)
			)
			(layer "F.Fab")
		)
		(fp_line
			(start -0.12065 0.2794)
			(end -0.12065 0.3048)
			(stroke
				(width 0.1)
				(type default)
			)
			(layer "F.Fab")
		)
		(fp_line
			(start -0.12065 0.3048)
			(end -0.67945 0.3048)
			(stroke
				(width 0.1)
				(type default)
			)
			(layer "F.Fab")
		)
		(fp_line
			(start 0.120396 0.2794)
			(end -0.12065 0.2794)
			(stroke
				(width 0.1)
				(type default)
			)
			(layer "F.Fab")
		)
		(fp_line
			(start 0.120396 0.3048)
			(end 0.120396 0.2794)
			(stroke
				(width 0.1)
				(type default)
			)
			(layer "F.Fab")
		)
		(fp_line
			(start 0.12065 -0.3048)
			(end 0.67945 -0.3048)
			(stroke
				(width 0.1)
				(type default)
			)
			(layer "F.Fab")
		)
		(fp_line
			(start 0.12065 -0.2794)
			(end 0.12065 -0.3048)
			(stroke
				(width 0.1)
				(type default)
			)
			(layer "F.Fab")
		)
		(fp_line
			(start 0.67945 -0.3048)
			(end 0.67945 0.3048)
			(stroke
				(width 0.1)
				(type default)
			)
			(layer "F.Fab")
		)
		(fp_line
			(start 0.67945 0.3048)
			(end 0.120396 0.3048)
			(stroke
				(width 0.1)
				(type default)
			)
			(layer "F.Fab")
		)
		(pad "1" smd circle
			(at -0.40005 0)
			(size 0 0)
			(layers "F.Cu" "F.Mask" "F.Paste")
			(net "FAN_2_PRESENT_R")
		)
		(pad "2" smd circle
			(at 0.40005 0)
			(size 0 0)
			(layers "F.Cu" "F.Mask" "F.Paste")
			(net "FAN_2_PRESENT")
		)
	)
	(footprint ""
		(layer "F.Cu")
		(at 37.338 -298.196)
		(property "Reference" "R5187"
			(at 0 0 0)
			(layer "F.SilkS")
			(hide yes)
			(effects
				(font
					(size 1.27 1.27)
				)
			)
		)
		(property "Value" ""
			(at 0 0 0)
			(layer "F.Fab")
			(effects
				(font
					(size 1.27 1.27)
				)
			)
		)
		(duplicate_pad_numbers_are_jumpers no)
		(fp_line
			(start -0.7874 -0.4064)
			(end 0.7874 -0.4064)
			(stroke
				(width 0.1524)
				(type default)
			)
			(layer "F.SilkS")
		)
		(fp_line
			(start -0.7874 0.4064)
			(end -0.7874 -0.4064)
			(stroke
				(width 0.1524)
				(type default)
			)
			(layer "F.SilkS")
		)
		(fp_line
			(start 0.7874 -0.4064)
			(end 0.7874 0.4064)
			(stroke
				(width 0.1524)
				(type default)
			)
			(layer "F.SilkS")
		)
		(fp_line
			(start 0.7874 0.4064)
			(end -0.7874 0.4064)
			(stroke
				(width 0.1524)
				(type default)
			)
			(layer "F.SilkS")
		)
		(fp_line
			(start -0.67945 -0.305054)
			(end -0.12065 -0.305054)
			(stroke
				(width 0.1)
				(type default)
			)
			(layer "F.Fab")
		)
		(fp_line
			(start -0.67945 0.3048)
			(end -0.67945 -0.305054)
			(stroke
				(width 0.1)
				(type default)
			)
			(layer "F.Fab")
		)
		(fp_line
			(start -0.12065 -0.305054)
			(end -0.12065 -0.2794)
			(stroke
				(width 0.1)
				(type default)
			)
			(layer "F.Fab")
		)
		(fp_line
			(start -0.12065 -0.2794)
			(end 0.12065 -0.2794)
			(stroke
				(width 0.1)
				(type default)
			)
			(layer "F.Fab")
		)
		(fp_line
			(start -0.12065 0.2794)
			(end -0.12065 0.3048)
			(stroke
				(width 0.1)
				(type default)
			)
			(layer "F.Fab")
		)
		(fp_line
			(start -0.12065 0.3048)
			(end -0.67945 0.3048)
			(stroke
				(width 0.1)
				(type default)
			)
			(layer "F.Fab")
		)
		(fp_line
			(start 0.120396 0.2794)
			(end -0.12065 0.2794)
			(stroke
				(width 0.1)
				(type default)
			)
			(layer "F.Fab")
		)
		(fp_line
			(start 0.120396 0.3048)
			(end 0.120396 0.2794)
			(stroke
				(width 0.1)
				(type default)
			)
			(layer "F.Fab")
		)
		(fp_line
			(start 0.12065 -0.3048)
			(end 0.67945 -0.3048)
			(stroke
				(width 0.1)
				(type default)
			)
			(layer "F.Fab")
		)
		(fp_line
			(start 0.12065 -0.2794)
			(end 0.12065 -0.3048)
			(stroke
				(width 0.1)
				(type default)
			)
			(layer "F.Fab")
		)
		(fp_line
			(start 0.67945 -0.3048)
			(end 0.67945 0.3048)
			(stroke
				(width 0.1)
				(type default)
			)
			(layer "F.Fab")
		)
		(fp_line
			(start 0.67945 0.3048)
			(end 0.120396 0.3048)
			(stroke
				(width 0.1)
				(type default)
			)
			(layer "F.Fab")
		)
		(pad "1" smd circle
			(at -0.40005 0)
			(size 0 0)
			(layers "F.Cu" "F.Mask" "F.Paste")
			(net "SMB_FAN0_SCL")
		)
		(pad "2" smd circle
			(at 0.40005 0)
			(size 0 0)
			(layers "F.Cu" "F.Mask" "F.Paste")
			(net "SMB_FAN0_SCL_R")
		)
	)
	(footprint ""
		(layer "F.Cu")
		(at 20.9042 -31.496 90)
		(property "Reference" "C2124"
			(at 0 0 90)
			(layer "F.SilkS")
			(hide yes)
			(effects
				(font
					(size 1.27 1.27)
				)
			)
		)
		(property "Value" ""
			(at 0 0 90)
			(layer "F.Fab")
			(effects
				(font
					(size 1.27 1.27)
				)
			)
		)
		(duplicate_pad_numbers_are_jumpers no)
		(fp_line
			(start 1.2954 -0.5842)
			(end 1.2954 0.5842)
			(stroke
				(width 0.1524)
				(type default)
			)
			(layer "F.SilkS")
		)
		(fp_line
			(start -1.2954 -0.5842)
			(end 1.2954 -0.5842)
			(stroke
				(width 0.1524)
				(type default)
			)
			(layer "F.SilkS")
		)
		(fp_line
			(start 1.2954 0.5842)
			(end -1.2954 0.5842)
			(stroke
				(width 0.1524)
				(type default)
			)
			(layer "F.SilkS")
		)
		(fp_line
			(start -1.2954 0.5842)
			(end -1.2954 -0.5842)
			(stroke
				(width 0.1524)
				(type default)
			)
			(layer "F.SilkS")
		)
		(fp_line
			(start 0.8636 -0.4572)
			(end 0.8636 -0.4064)
			(stroke
				(width 0.1)
				(type default)
			)
			(layer "F.Fab")
		)
		(fp_line
			(start -0.8636 -0.4572)
			(end 0.8636 -0.4572)
			(stroke
				(width 0.1)
				(type default)
			)
			(layer "F.Fab")
		)
		(fp_line
			(start 1.1938 -0.4064)
			(end 1.1938 0.4064)
			(stroke
				(width 0.1)
				(type default)
			)
			(layer "F.Fab")
		)
		(fp_line
			(start 0.8636 -0.4064)
			(end 1.1938 -0.4064)
			(stroke
				(width 0.1)
				(type default)
			)
			(layer "F.Fab")
		)
		(fp_line
			(start -0.8636 -0.4064)
			(end -0.8636 -0.4572)
			(stroke
				(width 0.1)
				(type default)
			)
			(layer "F.Fab")
		)
		(fp_line
			(start -1.1938 -0.4064)
			(end -0.8636 -0.4064)
			(stroke
				(width 0.1)
				(type default)
			)
			(layer "F.Fab")
		)
		(fp_line
			(start 1.1938 0.4064)
			(end 0.8636 0.4064)
			(stroke
				(width 0.1)
				(type default)
			)
			(layer "F.Fab")
		)
		(fp_line
			(start 0.8636 0.4064)
			(end 0.8636 0.4572)
			(stroke
				(width 0.1)
				(type default)
			)
			(layer "F.Fab")
		)
		(fp_line
			(start -0.8636 0.4064)
			(end -1.1938 0.4064)
			(stroke
				(width 0.1)
				(type default)
			)
			(layer "F.Fab")
		)
		(fp_line
			(start -1.1938 0.4064)
			(end -1.1938 -0.4064)
			(stroke
				(width 0.1)
				(type default)
			)
			(layer "F.Fab")
		)
		(fp_line
			(start 0.8636 0.4572)
			(end -0.8636 0.4572)
			(stroke
				(width 0.1)
				(type default)
			)
			(layer "F.Fab")
		)
		(fp_line
			(start -0.8636 0.4572)
			(end -0.8636 0.4064)
			(stroke
				(width 0.1)
				(type default)
			)
			(layer "F.Fab")
		)
		(pad "1" smd rect
			(at -0.7366 0)
			(size 0.7112 0.8128)
			(layers "F.Cu" "F.Mask" "F.Paste")
			(net "U409_D1")
		)
		(pad "2" smd rect
			(at 0.7366 0)
			(size 0.7112 0.8128)
			(layers "F.Cu" "F.Mask" "F.Paste")
			(net "GND")
		)
	)
	(footprint ""
		(layer "F.Cu")
		(at 28.829 -121.92 90)
		(property "Reference" "R4940"
			(at 0 0 90)
			(layer "F.SilkS")
			(hide yes)
			(effects
				(font
					(size 1.27 1.27)
				)
			)
		)
		(property "Value" ""
			(at 0 0 90)
			(layer "F.Fab")
			(effects
				(font
					(size 1.27 1.27)
				)
			)
		)
		(duplicate_pad_numbers_are_jumpers no)
		(fp_line
			(start 0.7874 -0.4064)
			(end 0.7874 0.4064)
			(stroke
				(width 0.1524)
				(type default)
			)
			(layer "F.SilkS")
		)
		(fp_line
			(start -0.7874 -0.4064)
			(end 0.7874 -0.4064)
			(stroke
				(width 0.1524)
				(type default)
			)
			(layer "F.SilkS")
		)
		(fp_line
			(start 0.7874 0.4064)
			(end -0.7874 0.4064)
			(stroke
				(width 0.1524)
				(type default)
			)
			(layer "F.SilkS")
		)
		(fp_line
			(start -0.7874 0.4064)
			(end -0.7874 -0.4064)
			(stroke
				(width 0.1524)
				(type default)
			)
			(layer "F.SilkS")
		)
		(fp_line
			(start -0.12065 -0.305054)
			(end -0.12065 -0.2794)
			(stroke
				(width 0.1)
				(type default)
			)
			(layer "F.Fab")
		)
		(fp_line
			(start -0.67945 -0.305054)
			(end -0.12065 -0.305054)
			(stroke
				(width 0.1)
				(type default)
			)
			(layer "F.Fab")
		)
		(fp_line
			(start 0.67945 -0.3048)
			(end 0.67945 0.3048)
			(stroke
				(width 0.1)
				(type default)
			)
			(layer "F.Fab")
		)
		(fp_line
			(start 0.12065 -0.3048)
			(end 0.67945 -0.3048)
			(stroke
				(width 0.1)
				(type default)
			)
			(layer "F.Fab")
		)
		(fp_line
			(start 0.12065 -0.2794)
			(end 0.12065 -0.3048)
			(stroke
				(width 0.1)
				(type default)
			)
			(layer "F.Fab")
		)
		(fp_line
			(start -0.12065 -0.2794)
			(end 0.12065 -0.2794)
			(stroke
				(width 0.1)
				(type default)
			)
			(layer "F.Fab")
		)
		(fp_line
			(start 0.120396 0.2794)
			(end -0.12065 0.2794)
			(stroke
				(width 0.1)
				(type default)
			)
			(layer "F.Fab")
		)
		(fp_line
			(start -0.12065 0.2794)
			(end -0.12065 0.3048)
			(stroke
				(width 0.1)
				(type default)
			)
			(layer "F.Fab")
		)
		(fp_line
			(start 0.67945 0.3048)
			(end 0.120396 0.3048)
			(stroke
				(width 0.1)
				(type default)
			)
			(layer "F.Fab")
		)
		(fp_line
			(start 0.120396 0.3048)
			(end 0.120396 0.2794)
			(stroke
				(width 0.1)
				(type default)
			)
			(layer "F.Fab")
		)
		(fp_line
			(start -0.12065 0.3048)
			(end -0.67945 0.3048)
			(stroke
				(width 0.1)
				(type default)
			)
			(layer "F.Fab")
		)
		(fp_line
			(start -0.67945 0.3048)
			(end -0.67945 -0.305054)
			(stroke
				(width 0.1)
				(type default)
			)
			(layer "F.Fab")
		)
		(pad "1" smd circle
			(at -0.40005 0 90)
			(size 0 0)
			(layers "F.Cu" "F.Mask" "F.Paste")
			(net "GND")
		)
		(pad "2" smd circle
			(at 0.40005 0 90)
			(size 0 0)
			(layers "F.Cu" "F.Mask" "F.Paste")
			(net "MAX31790_U317_FREQ_START")
		)
	)
	(footprint ""
		(layer "F.Cu")
		(at 15.001494 -256.667)
		(property "Reference" "R5424"
			(at 0 0 0)
			(layer "F.SilkS")
			(hide yes)
			(effects
				(font
					(size 1.27 1.27)
				)
			)
		)
		(property "Value" ""
			(at 0 0 0)
			(layer "F.Fab")
			(effects
				(font
					(size 1.27 1.27)
				)
			)
		)
		(duplicate_pad_numbers_are_jumpers no)
		(fp_line
			(start -0.7874 -0.4064)
			(end 0.7874 -0.4064)
			(stroke
				(width 0.1524)
				(type default)
			)
			(layer "F.SilkS")
		)
		(fp_line
			(start -0.7874 0.4064)
			(end -0.7874 -0.4064)
			(stroke
				(width 0.1524)
				(type default)
			)
			(layer "F.SilkS")
		)
		(fp_line
			(start 0.7874 -0.4064)
			(end 0.7874 0.4064)
			(stroke
				(width 0.1524)
				(type default)
			)
			(layer "F.SilkS")
		)
		(fp_line
			(start 0.7874 0.4064)
			(end -0.7874 0.4064)
			(stroke
				(width 0.1524)
				(type default)
			)
			(layer "F.SilkS")
		)
		(fp_line
			(start -0.67945 -0.305054)
			(end -0.12065 -0.305054)
			(stroke
				(width 0.1)
				(type default)
			)
			(layer "F.Fab")
		)
		(fp_line
			(start -0.67945 0.3048)
			(end -0.67945 -0.305054)
			(stroke
				(width 0.1)
				(type default)
			)
			(layer "F.Fab")
		)
		(fp_line
			(start -0.12065 -0.305054)
			(end -0.12065 -0.2794)
			(stroke
				(width 0.1)
				(type default)
			)
			(layer "F.Fab")
		)
		(fp_line
			(start -0.12065 -0.2794)
			(end 0.12065 -0.2794)
			(stroke
				(width 0.1)
				(type default)
			)
			(layer "F.Fab")
		)
		(fp_line
			(start -0.12065 0.2794)
			(end -0.12065 0.3048)
			(stroke
				(width 0.1)
				(type default)
			)
			(layer "F.Fab")
		)
		(fp_line
			(start -0.12065 0.3048)
			(end -0.67945 0.3048)
			(stroke
				(width 0.1)
				(type default)
			)
			(layer "F.Fab")
		)
		(fp_line
			(start 0.120396 0.2794)
			(end -0.12065 0.2794)
			(stroke
				(width 0.1)
				(type default)
			)
			(layer "F.Fab")
		)
		(fp_line
			(start 0.120396 0.3048)
			(end 0.120396 0.2794)
			(stroke
				(width 0.1)
				(type default)
			)
			(layer "F.Fab")
		)
		(fp_line
			(start 0.12065 -0.3048)
			(end 0.67945 -0.3048)
			(stroke
				(width 0.1)
				(type default)
			)
			(layer "F.Fab")
		)
		(fp_line
			(start 0.12065 -0.2794)
			(end 0.12065 -0.3048)
			(stroke
				(width 0.1)
				(type default)
			)
			(layer "F.Fab")
		)
		(fp_line
			(start 0.67945 -0.3048)
			(end 0.67945 0.3048)
			(stroke
				(width 0.1)
				(type default)
			)
			(layer "F.Fab")
		)
		(fp_line
			(start 0.67945 0.3048)
			(end 0.120396 0.3048)
			(stroke
				(width 0.1)
				(type default)
			)
			(layer "F.Fab")
		)
		(pad "1" smd circle
			(at -0.40005 0)
			(size 0 0)
			(layers "F.Cu" "F.Mask" "F.Paste")
			(net "FAN_7_PRESENT_R")
		)
		(pad "2" smd circle
			(at 0.40005 0)
			(size 0 0)
			(layers "F.Cu" "F.Mask" "F.Paste")
			(net "FAN_7_PRESENT")
		)
	)
	(footprint ""
		(layer "F.Cu")
		(at 14.732 -258.064 180)
		(property "Reference" "PR71"
			(at 0 0 180)
			(layer "F.SilkS")
			(hide yes)
			(effects
				(font
					(size 1.27 1.27)
				)
			)
		)
		(property "Value" ""
			(at 0 0 180)
			(layer "F.Fab")
			(effects
				(font
					(size 1.27 1.27)
				)
			)
		)
		(duplicate_pad_numbers_are_jumpers no)
		(fp_line
			(start 0.7874 0.4064)
			(end -0.7874 0.4064)
			(stroke
				(width 0.1524)
				(type default)
			)
			(layer "F.SilkS")
		)
		(fp_line
			(start 0.7874 -0.4064)
			(end 0.7874 0.4064)
			(stroke
				(width 0.1524)
				(type default)
			)
			(layer "F.SilkS")
		)
		(fp_line
			(start -0.7874 0.4064)
			(end -0.7874 -0.4064)
			(stroke
				(width 0.1524)
				(type default)
			)
			(layer "F.SilkS")
		)
		(fp_line
			(start -0.7874 -0.4064)
			(end 0.7874 -0.4064)
			(stroke
				(width 0.1524)
				(type default)
			)
			(layer "F.SilkS")
		)
		(fp_line
			(start 0.67945 0.3048)
			(end 0.120396 0.3048)
			(stroke
				(width 0.1)
				(type default)
			)
			(layer "F.Fab")
		)
		(fp_line
			(start 0.67945 -0.3048)
			(end 0.67945 0.3048)
			(stroke
				(width 0.1)
				(type default)
			)
			(layer "F.Fab")
		)
		(fp_line
			(start 0.12065 -0.2794)
			(end 0.12065 -0.3048)
			(stroke
				(width 0.1)
				(type default)
			)
			(layer "F.Fab")
		)
		(fp_line
			(start 0.12065 -0.3048)
			(end 0.67945 -0.3048)
			(stroke
				(width 0.1)
				(type default)
			)
			(layer "F.Fab")
		)
		(fp_line
			(start 0.120396 0.3048)
			(end 0.120396 0.2794)
			(stroke
				(width 0.1)
				(type default)
			)
			(layer "F.Fab")
		)
		(fp_line
			(start 0.120396 0.2794)
			(end -0.12065 0.2794)
			(stroke
				(width 0.1)
				(type default)
			)
			(layer "F.Fab")
		)
		(fp_line
			(start -0.12065 0.3048)
			(end -0.67945 0.3048)
			(stroke
				(width 0.1)
				(type default)
			)
			(layer "F.Fab")
		)
		(fp_line
			(start -0.12065 0.2794)
			(end -0.12065 0.3048)
			(stroke
				(width 0.1)
				(type default)
			)
			(layer "F.Fab")
		)
		(fp_line
			(start -0.12065 -0.2794)
			(end 0.12065 -0.2794)
			(stroke
				(width 0.1)
				(type default)
			)
			(layer "F.Fab")
		)
		(fp_line
			(start -0.12065 -0.305054)
			(end -0.12065 -0.2794)
			(stroke
				(width 0.1)
				(type default)
			)
			(layer "F.Fab")
		)
		(fp_line
			(start -0.67945 0.3048)
			(end -0.67945 -0.305054)
			(stroke
				(width 0.1)
				(type default)
			)
			(layer "F.Fab")
		)
		(fp_line
			(start -0.67945 -0.305054)
			(end -0.12065 -0.305054)
			(stroke
				(width 0.1)
				(type default)
			)
			(layer "F.Fab")
		)
		(pad "1" smd circle
			(at -0.40005 0 180)
			(size 0 0)
			(layers "F.Cu" "F.Mask" "F.Paste")
			(net "FAN_7_FAULT_R")
		)
		(pad "2" smd circle
			(at 0.40005 0 180)
			(size 0 0)
			(layers "F.Cu" "F.Mask" "F.Paste")
			(net "FAN_7_P3V_R")
		)
	)
	(footprint ""
		(layer "F.Cu")
		(at 8.709914 -251.587 180)
		(property "Reference" "C2070"
			(at 0 0 180)
			(layer "F.SilkS")
			(hide yes)
			(effects
				(font
					(size 1.27 1.27)
				)
			)
		)
		(property "Value" ""
			(at 0 0 180)
			(layer "F.Fab")
			(effects
				(font
					(size 1.27 1.27)
				)
			)
		)
		(duplicate_pad_numbers_are_jumpers no)
		(fp_line
			(start 0.7874 0.4064)
			(end -0.7874 0.4064)
			(stroke
				(width 0.1524)
				(type default)
			)
			(layer "F.SilkS")
		)
		(fp_line
			(start 0.7874 -0.4064)
			(end 0.7874 0.4064)
			(stroke
				(width 0.1524)
				(type default)
			)
			(layer "F.SilkS")
		)
		(fp_line
			(start -0.7874 0.4064)
			(end -0.7874 -0.4064)
			(stroke
				(width 0.1524)
				(type default)
			)
			(layer "F.SilkS")
		)
		(fp_line
			(start -0.7874 -0.4064)
			(end 0.7874 -0.4064)
			(stroke
				(width 0.1524)
				(type default)
			)
			(layer "F.SilkS")
		)
		(fp_line
			(start 0.67945 0.3048)
			(end 0.120396 0.3048)
			(stroke
				(width 0.1)
				(type default)
			)
			(layer "F.Fab")
		)
		(fp_line
			(start 0.67945 -0.3048)
			(end 0.67945 0.3048)
			(stroke
				(width 0.1)
				(type default)
			)
			(layer "F.Fab")
		)
		(fp_line
			(start 0.12065 -0.2794)
			(end 0.12065 -0.3048)
			(stroke
				(width 0.1)
				(type default)
			)
			(layer "F.Fab")
		)
		(fp_line
			(start 0.12065 -0.3048)
			(end 0.67945 -0.3048)
			(stroke
				(width 0.1)
				(type default)
			)
			(layer "F.Fab")
		)
		(fp_line
			(start 0.120396 0.3048)
			(end 0.120396 0.2794)
			(stroke
				(width 0.1)
				(type default)
			)
			(layer "F.Fab")
		)
		(fp_line
			(start 0.120396 0.2794)
			(end -0.12065 0.2794)
			(stroke
				(width 0.1)
				(type default)
			)
			(layer "F.Fab")
		)
		(fp_line
			(start -0.12065 0.3048)
			(end -0.67945 0.3048)
			(stroke
				(width 0.1)
				(type default)
			)
			(layer "F.Fab")
		)
		(fp_line
			(start -0.12065 0.2794)
			(end -0.12065 0.3048)
			(stroke
				(width 0.1)
				(type default)
			)
			(layer "F.Fab")
		)
		(fp_line
			(start -0.12065 -0.2794)
			(end 0.12065 -0.2794)
			(stroke
				(width 0.1)
				(type default)
			)
			(layer "F.Fab")
		)
		(fp_line
			(start -0.12065 -0.305054)
			(end -0.12065 -0.2794)
			(stroke
				(width 0.1)
				(type default)
			)
			(layer "F.Fab")
		)
		(fp_line
			(start -0.67945 0.3048)
			(end -0.67945 -0.305054)
			(stroke
				(width 0.1)
				(type default)
			)
			(layer "F.Fab")
		)
		(fp_line
			(start -0.67945 -0.305054)
			(end -0.12065 -0.305054)
			(stroke
				(width 0.1)
				(type default)
			)
			(layer "F.Fab")
		)
		(pad "1" smd circle
			(at -0.40005 0 180)
			(size 0 0)
			(layers "F.Cu" "F.Mask" "F.Paste")
			(net "P3V3_AUX")
		)
		(pad "2" smd circle
			(at 0.40005 0 180)
			(size 0 0)
			(layers "F.Cu" "F.Mask" "F.Paste")
			(net "GND")
		)
	)
	(footprint ""
		(layer "F.Cu")
		(at 37.338 -23.876)
		(property "Reference" "D281"
			(at 1.143 -0.73533 0)
			(unlocked yes)
			(layer "F.SilkS")
			(effects
				(font
					(size 0.7874 0.5842)
					(thickness 0.1524)
				)
				(justify left)
			)
		)
		(property "Value" ""
			(at 0 0 0)
			(layer "F.Fab")
			(effects
				(font
					(size 1.27 1.27)
				)
			)
		)
		(duplicate_pad_numbers_are_jumpers no)
		(fp_line
			(start -0.854964 -0.450088)
			(end -0.854964 0.450088)
			(stroke
				(width 0.1524)
				(type default)
			)
			(layer "F.SilkS")
		)
		(fp_line
			(start -0.854964 0.450088)
			(end 0.925068 0.450088)
			(stroke
				(width 0.1524)
				(type default)
			)
			(layer "F.SilkS")
		)
		(fp_line
			(start 0.845058 0.4064)
			(end 0.845058 -0.381)
			(stroke
				(width 0.1524)
				(type default)
			)
			(layer "F.SilkS")
		)
		(fp_line
			(start 0.870458 -0.2794)
			(end 0.845058 0.4064)
			(stroke
				(width 0.1524)
				(type default)
			)
			(layer "F.SilkS")
		)
		(fp_line
			(start 0.94488 -0.450088)
			(end -0.854964 -0.450088)
			(stroke
				(width 0.1524)
				(type default)
			)
			(layer "F.SilkS")
		)
		(fp_line
			(start 0.94488 0.450088)
			(end 0.94488 -0.450088)
			(stroke
				(width 0.1524)
				(type default)
			)
			(layer "F.SilkS")
		)
		(fp_line
			(start -0.54991 -0.350012)
			(end -0.54991 0.350012)
			(stroke
				(width 0.1)
				(type default)
			)
			(layer "F.Fab")
		)
		(fp_line
			(start -0.54991 0.350012)
			(end 0.54991 0.350012)
			(stroke
				(width 0.1)
				(type default)
			)
			(layer "F.Fab")
		)
		(fp_line
			(start 0.54991 -0.350012)
			(end -0.54991 -0.350012)
			(stroke
				(width 0.1)
				(type default)
			)
			(layer "F.Fab")
		)
		(fp_line
			(start 0.54991 0.350012)
			(end 0.54991 -0.350012)
			(stroke
				(width 0.1)
				(type default)
			)
			(layer "F.Fab")
		)
		(fp_text user "+"
			(at -0.635 0.09525 180)
			(unlocked yes)
			(layer "F.SilkS")
			(effects
				(font
					(size 1.905 1.4224)
					(thickness 0.1524)
				)
				(justify left)
			)
		)
		(fp_text user "-"
			(at 2.159 0.09525 180)
			(unlocked yes)
			(layer "F.SilkS")
			(effects
				(font
					(size 1.905 1.4224)
					(thickness 0.1524)
				)
				(justify left)
			)
		)
		(fp_text user "+"
			(at -0.808228 0.239014 180)
			(unlocked yes)
			(layer "F.Fab")
			(effects
				(font
					(size 1.905 1.4224)
					(thickness 0.1524)
				)
				(justify left)
			)
		)
		(fp_text user "-"
			(at 2.48539 0.239014 180)
			(unlocked yes)
			(layer "F.Fab")
			(effects
				(font
					(size 1.905 1.4224)
					(thickness 0.1524)
				)
				(justify left)
			)
		)
		(pad "A" smd rect
			(at -0.424942 0)
			(size 0.5588 0.6096)
			(layers "F.Cu" "F.Mask" "F.Paste")
			(net "GND")
		)
		(pad "C" smd rect
			(at 0.424942 0 180)
			(size 0.5588 0.6096)
			(layers "F.Cu" "F.Mask" "F.Paste")
			(net "FAN_3_FAIL_R_LED_N")
		)
	)
	(footprint ""
		(layer "F.Cu")
		(at 39.206932 -255.143 180)
		(property "Reference" "R5417"
			(at 0 0 180)
			(layer "F.SilkS")
			(hide yes)
			(effects
				(font
					(size 1.27 1.27)
				)
			)
		)
		(property "Value" ""
			(at 0 0 180)
			(layer "F.Fab")
			(effects
				(font
					(size 1.27 1.27)
				)
			)
		)
		(duplicate_pad_numbers_are_jumpers no)
		(fp_line
			(start 0.7874 0.4064)
			(end -0.7874 0.4064)
			(stroke
				(width 0.1524)
				(type default)
			)
			(layer "F.SilkS")
		)
		(fp_line
			(start 0.7874 -0.4064)
			(end 0.7874 0.4064)
			(stroke
				(width 0.1524)
				(type default)
			)
			(layer "F.SilkS")
		)
		(fp_line
			(start -0.7874 0.4064)
			(end -0.7874 -0.4064)
			(stroke
				(width 0.1524)
				(type default)
			)
			(layer "F.SilkS")
		)
		(fp_line
			(start -0.7874 -0.4064)
			(end 0.7874 -0.4064)
			(stroke
				(width 0.1524)
				(type default)
			)
			(layer "F.SilkS")
		)
		(fp_line
			(start 0.67945 0.3048)
			(end 0.120396 0.3048)
			(stroke
				(width 0.1)
				(type default)
			)
			(layer "F.Fab")
		)
		(fp_line
			(start 0.67945 -0.3048)
			(end 0.67945 0.3048)
			(stroke
				(width 0.1)
				(type default)
			)
			(layer "F.Fab")
		)
		(fp_line
			(start 0.12065 -0.2794)
			(end 0.12065 -0.3048)
			(stroke
				(width 0.1)
				(type default)
			)
			(layer "F.Fab")
		)
		(fp_line
			(start 0.12065 -0.3048)
			(end 0.67945 -0.3048)
			(stroke
				(width 0.1)
				(type default)
			)
			(layer "F.Fab")
		)
		(fp_line
			(start 0.120396 0.3048)
			(end 0.120396 0.2794)
			(stroke
				(width 0.1)
				(type default)
			)
			(layer "F.Fab")
		)
		(fp_line
			(start 0.120396 0.2794)
			(end -0.12065 0.2794)
			(stroke
				(width 0.1)
				(type default)
			)
			(layer "F.Fab")
		)
		(fp_line
			(start -0.12065 0.3048)
			(end -0.67945 0.3048)
			(stroke
				(width 0.1)
				(type default)
			)
			(layer "F.Fab")
		)
		(fp_line
			(start -0.12065 0.2794)
			(end -0.12065 0.3048)
			(stroke
				(width 0.1)
				(type default)
			)
			(layer "F.Fab")
		)
		(fp_line
			(start -0.12065 -0.2794)
			(end 0.12065 -0.2794)
			(stroke
				(width 0.1)
				(type default)
			)
			(layer "F.Fab")
		)
		(fp_line
			(start -0.12065 -0.305054)
			(end -0.12065 -0.2794)
			(stroke
				(width 0.1)
				(type default)
			)
			(layer "F.Fab")
		)
		(fp_line
			(start -0.67945 0.3048)
			(end -0.67945 -0.305054)
			(stroke
				(width 0.1)
				(type default)
			)
			(layer "F.Fab")
		)
		(fp_line
			(start -0.67945 -0.305054)
			(end -0.12065 -0.305054)
			(stroke
				(width 0.1)
				(type default)
			)
			(layer "F.Fab")
		)
		(pad "1" smd circle
			(at -0.40005 0 180)
			(size 0 0)
			(layers "F.Cu" "F.Mask" "F.Paste")
			(net "FAN_0_ON")
		)
		(pad "2" smd circle
			(at 0.40005 0 180)
			(size 0 0)
			(layers "F.Cu" "F.Mask" "F.Paste")
			(net "P52V_FAN_0_EN")
		)
	)
	(footprint ""
		(layer "F.Cu")
		(at 21.59 -143.891 -90)
		(property "Reference" "R4785"
			(at 0 0 270)
			(layer "F.SilkS")
			(hide yes)
			(effects
				(font
					(size 1.27 1.27)
				)
			)
		)
		(property "Value" ""
			(at 0 0 270)
			(layer "F.Fab")
			(effects
				(font
					(size 1.27 1.27)
				)
			)
		)
		(duplicate_pad_numbers_are_jumpers no)
		(fp_line
			(start -0.7874 0.4064)
			(end -0.7874 -0.4064)
			(stroke
				(width 0.1524)
				(type default)
			)
			(layer "F.SilkS")
		)
		(fp_line
			(start 0.7874 0.4064)
			(end -0.7874 0.4064)
			(stroke
				(width 0.1524)
				(type default)
			)
			(layer "F.SilkS")
		)
		(fp_line
			(start -0.7874 -0.4064)
			(end 0.7874 -0.4064)
			(stroke
				(width 0.1524)
				(type default)
			)
			(layer "F.SilkS")
		)
		(fp_line
			(start 0.7874 -0.4064)
			(end 0.7874 0.4064)
			(stroke
				(width 0.1524)
				(type default)
			)
			(layer "F.SilkS")
		)
		(fp_line
			(start -0.67945 0.3048)
			(end -0.67945 -0.305054)
			(stroke
				(width 0.1)
				(type default)
			)
			(layer "F.Fab")
		)
		(fp_line
			(start -0.12065 0.3048)
			(end -0.67945 0.3048)
			(stroke
				(width 0.1)
				(type default)
			)
			(layer "F.Fab")
		)
		(fp_line
			(start 0.120396 0.3048)
			(end 0.120396 0.2794)
			(stroke
				(width 0.1)
				(type default)
			)
			(layer "F.Fab")
		)
		(fp_line
			(start 0.67945 0.3048)
			(end 0.120396 0.3048)
			(stroke
				(width 0.1)
				(type default)
			)
			(layer "F.Fab")
		)
		(fp_line
			(start -0.12065 0.2794)
			(end -0.12065 0.3048)
			(stroke
				(width 0.1)
				(type default)
			)
			(layer "F.Fab")
		)
		(fp_line
			(start 0.120396 0.2794)
			(end -0.12065 0.2794)
			(stroke
				(width 0.1)
				(type default)
			)
			(layer "F.Fab")
		)
		(fp_line
			(start -0.12065 -0.2794)
			(end 0.12065 -0.2794)
			(stroke
				(width 0.1)
				(type default)
			)
			(layer "F.Fab")
		)
		(fp_line
			(start 0.12065 -0.2794)
			(end 0.12065 -0.3048)
			(stroke
				(width 0.1)
				(type default)
			)
			(layer "F.Fab")
		)
		(fp_line
			(start 0.12065 -0.3048)
			(end 0.67945 -0.3048)
			(stroke
				(width 0.1)
				(type default)
			)
			(layer "F.Fab")
		)
		(fp_line
			(start 0.67945 -0.3048)
			(end 0.67945 0.3048)
			(stroke
				(width 0.1)
				(type default)
			)
			(layer "F.Fab")
		)
		(fp_line
			(start -0.67945 -0.305054)
			(end -0.12065 -0.305054)
			(stroke
				(width 0.1)
				(type default)
			)
			(layer "F.Fab")
		)
		(fp_line
			(start -0.12065 -0.305054)
			(end -0.12065 -0.2794)
			(stroke
				(width 0.1)
				(type default)
			)
			(layer "F.Fab")
		)
		(pad "1" smd circle
			(at -0.40005 0 270)
			(size 0 0)
			(layers "F.Cu" "F.Mask" "F.Paste")
			(net "SMB_FAN0_R_SDA")
		)
		(pad "2" smd circle
			(at 0.40005 0 270)
			(size 0 0)
			(layers "F.Cu" "F.Mask" "F.Paste")
			(net "SMB_FAN0_SDA")
		)
	)
	(footprint ""
		(layer "F.Cu")
		(at 19.05 -146.05 90)
		(property "Reference" "R5473"
			(at 0 0 90)
			(layer "F.SilkS")
			(hide yes)
			(effects
				(font
					(size 1.27 1.27)
				)
			)
		)
		(property "Value" ""
			(at 0 0 90)
			(layer "F.Fab")
			(effects
				(font
					(size 1.27 1.27)
				)
			)
		)
		(duplicate_pad_numbers_are_jumpers no)
		(fp_line
			(start 0.7874 -0.4064)
			(end 0.7874 0.4064)
			(stroke
				(width 0.1524)
				(type default)
			)
			(layer "F.SilkS")
		)
		(fp_line
			(start -0.7874 -0.4064)
			(end 0.7874 -0.4064)
			(stroke
				(width 0.1524)
				(type default)
			)
			(layer "F.SilkS")
		)
		(fp_line
			(start 0.7874 0.4064)
			(end -0.7874 0.4064)
			(stroke
				(width 0.1524)
				(type default)
			)
			(layer "F.SilkS")
		)
		(fp_line
			(start -0.7874 0.4064)
			(end -0.7874 -0.4064)
			(stroke
				(width 0.1524)
				(type default)
			)
			(layer "F.SilkS")
		)
		(fp_line
			(start -0.12065 -0.305054)
			(end -0.12065 -0.2794)
			(stroke
				(width 0.1)
				(type default)
			)
			(layer "F.Fab")
		)
		(fp_line
			(start -0.67945 -0.305054)
			(end -0.12065 -0.305054)
			(stroke
				(width 0.1)
				(type default)
			)
			(layer "F.Fab")
		)
		(fp_line
			(start 0.67945 -0.3048)
			(end 0.67945 0.3048)
			(stroke
				(width 0.1)
				(type default)
			)
			(layer "F.Fab")
		)
		(fp_line
			(start 0.12065 -0.3048)
			(end 0.67945 -0.3048)
			(stroke
				(width 0.1)
				(type default)
			)
			(layer "F.Fab")
		)
		(fp_line
			(start 0.12065 -0.2794)
			(end 0.12065 -0.3048)
			(stroke
				(width 0.1)
				(type default)
			)
			(layer "F.Fab")
		)
		(fp_line
			(start -0.12065 -0.2794)
			(end 0.12065 -0.2794)
			(stroke
				(width 0.1)
				(type default)
			)
			(layer "F.Fab")
		)
		(fp_line
			(start 0.120396 0.2794)
			(end -0.12065 0.2794)
			(stroke
				(width 0.1)
				(type default)
			)
			(layer "F.Fab")
		)
		(fp_line
			(start -0.12065 0.2794)
			(end -0.12065 0.3048)
			(stroke
				(width 0.1)
				(type default)
			)
			(layer "F.Fab")
		)
		(fp_line
			(start 0.67945 0.3048)
			(end 0.120396 0.3048)
			(stroke
				(width 0.1)
				(type default)
			)
			(layer "F.Fab")
		)
		(fp_line
			(start 0.120396 0.3048)
			(end 0.120396 0.2794)
			(stroke
				(width 0.1)
				(type default)
			)
			(layer "F.Fab")
		)
		(fp_line
			(start -0.12065 0.3048)
			(end -0.67945 0.3048)
			(stroke
				(width 0.1)
				(type default)
			)
			(layer "F.Fab")
		)
		(fp_line
			(start -0.67945 0.3048)
			(end -0.67945 -0.305054)
			(stroke
				(width 0.1)
				(type default)
			)
			(layer "F.Fab")
		)
		(pad "1" smd circle
			(at -0.40005 0 90)
			(size 0 0)
			(layers "F.Cu" "F.Mask" "F.Paste")
			(net "P3V3_AUX")
		)
		(pad "2" smd circle
			(at 0.40005 0 90)
			(size 0 0)
			(layers "F.Cu" "F.Mask" "F.Paste")
			(net "PD_TCA9548_SML1_U321_A1")
		)
	)
	(footprint ""
		(layer "F.Cu")
		(at 35.306 -211.864956 180)
		(property "Reference" "C2028"
			(at 0 0 180)
			(layer "F.SilkS")
			(hide yes)
			(effects
				(font
					(size 1.27 1.27)
				)
			)
		)
		(property "Value" ""
			(at 0 0 180)
			(layer "F.Fab")
			(effects
				(font
					(size 1.27 1.27)
				)
			)
		)
		(duplicate_pad_numbers_are_jumpers no)
		(fp_line
			(start 0.7874 0.4064)
			(end -0.7874 0.4064)
			(stroke
				(width 0.1524)
				(type default)
			)
			(layer "F.SilkS")
		)
		(fp_line
			(start 0.7874 -0.4064)
			(end 0.7874 0.4064)
			(stroke
				(width 0.1524)
				(type default)
			)
			(layer "F.SilkS")
		)
		(fp_line
			(start -0.7874 0.4064)
			(end -0.7874 -0.4064)
			(stroke
				(width 0.1524)
				(type default)
			)
			(layer "F.SilkS")
		)
		(fp_line
			(start -0.7874 -0.4064)
			(end 0.7874 -0.4064)
			(stroke
				(width 0.1524)
				(type default)
			)
			(layer "F.SilkS")
		)
		(fp_line
			(start 0.67945 0.3048)
			(end 0.120396 0.3048)
			(stroke
				(width 0.1)
				(type default)
			)
			(layer "F.Fab")
		)
		(fp_line
			(start 0.67945 -0.3048)
			(end 0.67945 0.3048)
			(stroke
				(width 0.1)
				(type default)
			)
			(layer "F.Fab")
		)
		(fp_line
			(start 0.12065 -0.2794)
			(end 0.12065 -0.3048)
			(stroke
				(width 0.1)
				(type default)
			)
			(layer "F.Fab")
		)
		(fp_line
			(start 0.12065 -0.3048)
			(end 0.67945 -0.3048)
			(stroke
				(width 0.1)
				(type default)
			)
			(layer "F.Fab")
		)
		(fp_line
			(start 0.120396 0.3048)
			(end 0.120396 0.2794)
			(stroke
				(width 0.1)
				(type default)
			)
			(layer "F.Fab")
		)
		(fp_line
			(start 0.120396 0.2794)
			(end -0.12065 0.2794)
			(stroke
				(width 0.1)
				(type default)
			)
			(layer "F.Fab")
		)
		(fp_line
			(start -0.12065 0.3048)
			(end -0.67945 0.3048)
			(stroke
				(width 0.1)
				(type default)
			)
			(layer "F.Fab")
		)
		(fp_line
			(start -0.12065 0.2794)
			(end -0.12065 0.3048)
			(stroke
				(width 0.1)
				(type default)
			)
			(layer "F.Fab")
		)
		(fp_line
			(start -0.12065 -0.2794)
			(end 0.12065 -0.2794)
			(stroke
				(width 0.1)
				(type default)
			)
			(layer "F.Fab")
		)
		(fp_line
			(start -0.12065 -0.305054)
			(end -0.12065 -0.2794)
			(stroke
				(width 0.1)
				(type default)
			)
			(layer "F.Fab")
		)
		(fp_line
			(start -0.67945 0.3048)
			(end -0.67945 -0.305054)
			(stroke
				(width 0.1)
				(type default)
			)
			(layer "F.Fab")
		)
		(fp_line
			(start -0.67945 -0.305054)
			(end -0.12065 -0.305054)
			(stroke
				(width 0.1)
				(type default)
			)
			(layer "F.Fab")
		)
		(pad "1" smd circle
			(at -0.40005 0 180)
			(size 0 0)
			(layers "F.Cu" "F.Mask" "F.Paste")
			(net "FAN_1_PWM_OL_R")
		)
		(pad "2" smd circle
			(at 0.40005 0 180)
			(size 0 0)
			(layers "F.Cu" "F.Mask" "F.Paste")
			(net "GND")
		)
	)
	(footprint ""
		(layer "F.Cu")
		(at 23.241 -28.194 -90)
		(property "Reference" "R5514"
			(at 0 0 270)
			(layer "F.SilkS")
			(hide yes)
			(effects
				(font
					(size 1.27 1.27)
				)
			)
		)
		(property "Value" ""
			(at 0 0 270)
			(layer "F.Fab")
			(effects
				(font
					(size 1.27 1.27)
				)
			)
		)
		(duplicate_pad_numbers_are_jumpers no)
		(fp_line
			(start -0.7874 0.4064)
			(end -0.7874 -0.4064)
			(stroke
				(width 0.1524)
				(type default)
			)
			(layer "F.SilkS")
		)
		(fp_line
			(start 0.7874 0.4064)
			(end -0.7874 0.4064)
			(stroke
				(width 0.1524)
				(type default)
			)
			(layer "F.SilkS")
		)
		(fp_line
			(start -0.7874 -0.4064)
			(end 0.7874 -0.4064)
			(stroke
				(width 0.1524)
				(type default)
			)
			(layer "F.SilkS")
		)
		(fp_line
			(start 0.7874 -0.4064)
			(end 0.7874 0.4064)
			(stroke
				(width 0.1524)
				(type default)
			)
			(layer "F.SilkS")
		)
		(fp_line
			(start -0.67945 0.3048)
			(end -0.67945 -0.305054)
			(stroke
				(width 0.1)
				(type default)
			)
			(layer "F.Fab")
		)
		(fp_line
			(start -0.12065 0.3048)
			(end -0.67945 0.3048)
			(stroke
				(width 0.1)
				(type default)
			)
			(layer "F.Fab")
		)
		(fp_line
			(start 0.120396 0.3048)
			(end 0.120396 0.2794)
			(stroke
				(width 0.1)
				(type default)
			)
			(layer "F.Fab")
		)
		(fp_line
			(start 0.67945 0.3048)
			(end 0.120396 0.3048)
			(stroke
				(width 0.1)
				(type default)
			)
			(layer "F.Fab")
		)
		(fp_line
			(start -0.12065 0.2794)
			(end -0.12065 0.3048)
			(stroke
				(width 0.1)
				(type default)
			)
			(layer "F.Fab")
		)
		(fp_line
			(start 0.120396 0.2794)
			(end -0.12065 0.2794)
			(stroke
				(width 0.1)
				(type default)
			)
			(layer "F.Fab")
		)
		(fp_line
			(start -0.12065 -0.2794)
			(end 0.12065 -0.2794)
			(stroke
				(width 0.1)
				(type default)
			)
			(layer "F.Fab")
		)
		(fp_line
			(start 0.12065 -0.2794)
			(end 0.12065 -0.3048)
			(stroke
				(width 0.1)
				(type default)
			)
			(layer "F.Fab")
		)
		(fp_line
			(start 0.12065 -0.3048)
			(end 0.67945 -0.3048)
			(stroke
				(width 0.1)
				(type default)
			)
			(layer "F.Fab")
		)
		(fp_line
			(start 0.67945 -0.3048)
			(end 0.67945 0.3048)
			(stroke
				(width 0.1)
				(type default)
			)
			(layer "F.Fab")
		)
		(fp_line
			(start -0.67945 -0.305054)
			(end -0.12065 -0.305054)
			(stroke
				(width 0.1)
				(type default)
			)
			(layer "F.Fab")
		)
		(fp_line
			(start -0.12065 -0.305054)
			(end -0.12065 -0.2794)
			(stroke
				(width 0.1)
				(type default)
			)
			(layer "F.Fab")
		)
		(pad "1" smd circle
			(at -0.40005 0 270)
			(size 0 0)
			(layers "F.Cu" "F.Mask" "F.Paste")
			(net "P3V3_AUX")
		)
		(pad "2" smd circle
			(at 0.40005 0 270)
			(size 0 0)
			(layers "F.Cu" "F.Mask" "F.Paste")
			(net "FAN_3_PWM_BUF")
		)
	)
	(footprint ""
		(layer "F.Cu")
		(at 22.098 -160.02 90)
		(property "Reference" "R4883"
			(at 0 0 90)
			(layer "F.SilkS")
			(hide yes)
			(effects
				(font
					(size 1.27 1.27)
				)
			)
		)
		(property "Value" ""
			(at 0 0 90)
			(layer "F.Fab")
			(effects
				(font
					(size 1.27 1.27)
				)
			)
		)
		(duplicate_pad_numbers_are_jumpers no)
		(fp_line
			(start 0.7874 -0.4064)
			(end 0.7874 0.4064)
			(stroke
				(width 0.1524)
				(type default)
			)
			(layer "F.SilkS")
		)
		(fp_line
			(start -0.7874 -0.4064)
			(end 0.7874 -0.4064)
			(stroke
				(width 0.1524)
				(type default)
			)
			(layer "F.SilkS")
		)
		(fp_line
			(start 0.7874 0.4064)
			(end -0.7874 0.4064)
			(stroke
				(width 0.1524)
				(type default)
			)
			(layer "F.SilkS")
		)
		(fp_line
			(start -0.7874 0.4064)
			(end -0.7874 -0.4064)
			(stroke
				(width 0.1524)
				(type default)
			)
			(layer "F.SilkS")
		)
		(fp_line
			(start -0.12065 -0.305054)
			(end -0.12065 -0.2794)
			(stroke
				(width 0.1)
				(type default)
			)
			(layer "F.Fab")
		)
		(fp_line
			(start -0.67945 -0.305054)
			(end -0.12065 -0.305054)
			(stroke
				(width 0.1)
				(type default)
			)
			(layer "F.Fab")
		)
		(fp_line
			(start 0.67945 -0.3048)
			(end 0.67945 0.3048)
			(stroke
				(width 0.1)
				(type default)
			)
			(layer "F.Fab")
		)
		(fp_line
			(start 0.12065 -0.3048)
			(end 0.67945 -0.3048)
			(stroke
				(width 0.1)
				(type default)
			)
			(layer "F.Fab")
		)
		(fp_line
			(start 0.12065 -0.2794)
			(end 0.12065 -0.3048)
			(stroke
				(width 0.1)
				(type default)
			)
			(layer "F.Fab")
		)
		(fp_line
			(start -0.12065 -0.2794)
			(end 0.12065 -0.2794)
			(stroke
				(width 0.1)
				(type default)
			)
			(layer "F.Fab")
		)
		(fp_line
			(start 0.120396 0.2794)
			(end -0.12065 0.2794)
			(stroke
				(width 0.1)
				(type default)
			)
			(layer "F.Fab")
		)
		(fp_line
			(start -0.12065 0.2794)
			(end -0.12065 0.3048)
			(stroke
				(width 0.1)
				(type default)
			)
			(layer "F.Fab")
		)
		(fp_line
			(start 0.67945 0.3048)
			(end 0.120396 0.3048)
			(stroke
				(width 0.1)
				(type default)
			)
			(layer "F.Fab")
		)
		(fp_line
			(start 0.120396 0.3048)
			(end 0.120396 0.2794)
			(stroke
				(width 0.1)
				(type default)
			)
			(layer "F.Fab")
		)
		(fp_line
			(start -0.12065 0.3048)
			(end -0.67945 0.3048)
			(stroke
				(width 0.1)
				(type default)
			)
			(layer "F.Fab")
		)
		(fp_line
			(start -0.67945 0.3048)
			(end -0.67945 -0.305054)
			(stroke
				(width 0.1)
				(type default)
			)
			(layer "F.Fab")
		)
		(pad "1" smd circle
			(at -0.40005 0 90)
			(size 0 0)
			(layers "F.Cu" "F.Mask" "F.Paste")
			(net "SMB_FAN7_R_SCL")
		)
		(pad "2" smd circle
			(at 0.40005 0 90)
			(size 0 0)
			(layers "F.Cu" "F.Mask" "F.Paste")
			(net "SMB_FAN7_SCL")
		)
	)
	(footprint ""
		(layer "F.Cu")
		(at 25.527 -131.445 180)
		(property "Reference" "R4941"
			(at 0 0 180)
			(layer "F.SilkS")
			(hide yes)
			(effects
				(font
					(size 1.27 1.27)
				)
			)
		)
		(property "Value" ""
			(at 0 0 180)
			(layer "F.Fab")
			(effects
				(font
					(size 1.27 1.27)
				)
			)
		)
		(duplicate_pad_numbers_are_jumpers no)
		(fp_line
			(start 0.7874 0.4064)
			(end -0.7874 0.4064)
			(stroke
				(width 0.1524)
				(type default)
			)
			(layer "F.SilkS")
		)
		(fp_line
			(start 0.7874 -0.4064)
			(end 0.7874 0.4064)
			(stroke
				(width 0.1524)
				(type default)
			)
			(layer "F.SilkS")
		)
		(fp_line
			(start -0.7874 0.4064)
			(end -0.7874 -0.4064)
			(stroke
				(width 0.1524)
				(type default)
			)
			(layer "F.SilkS")
		)
		(fp_line
			(start -0.7874 -0.4064)
			(end 0.7874 -0.4064)
			(stroke
				(width 0.1524)
				(type default)
			)
			(layer "F.SilkS")
		)
		(fp_line
			(start 0.67945 0.3048)
			(end 0.120396 0.3048)
			(stroke
				(width 0.1)
				(type default)
			)
			(layer "F.Fab")
		)
		(fp_line
			(start 0.67945 -0.3048)
			(end 0.67945 0.3048)
			(stroke
				(width 0.1)
				(type default)
			)
			(layer "F.Fab")
		)
		(fp_line
			(start 0.12065 -0.2794)
			(end 0.12065 -0.3048)
			(stroke
				(width 0.1)
				(type default)
			)
			(layer "F.Fab")
		)
		(fp_line
			(start 0.12065 -0.3048)
			(end 0.67945 -0.3048)
			(stroke
				(width 0.1)
				(type default)
			)
			(layer "F.Fab")
		)
		(fp_line
			(start 0.120396 0.3048)
			(end 0.120396 0.2794)
			(stroke
				(width 0.1)
				(type default)
			)
			(layer "F.Fab")
		)
		(fp_line
			(start 0.120396 0.2794)
			(end -0.12065 0.2794)
			(stroke
				(width 0.1)
				(type default)
			)
			(layer "F.Fab")
		)
		(fp_line
			(start -0.12065 0.3048)
			(end -0.67945 0.3048)
			(stroke
				(width 0.1)
				(type default)
			)
			(layer "F.Fab")
		)
		(fp_line
			(start -0.12065 0.2794)
			(end -0.12065 0.3048)
			(stroke
				(width 0.1)
				(type default)
			)
			(layer "F.Fab")
		)
		(fp_line
			(start -0.12065 -0.2794)
			(end 0.12065 -0.2794)
			(stroke
				(width 0.1)
				(type default)
			)
			(layer "F.Fab")
		)
		(fp_line
			(start -0.12065 -0.305054)
			(end -0.12065 -0.2794)
			(stroke
				(width 0.1)
				(type default)
			)
			(layer "F.Fab")
		)
		(fp_line
			(start -0.67945 0.3048)
			(end -0.67945 -0.305054)
			(stroke
				(width 0.1)
				(type default)
			)
			(layer "F.Fab")
		)
		(fp_line
			(start -0.67945 -0.305054)
			(end -0.12065 -0.305054)
			(stroke
				(width 0.1)
				(type default)
			)
			(layer "F.Fab")
		)
		(pad "1" smd circle
			(at -0.40005 0 180)
			(size 0 0)
			(layers "F.Cu" "F.Mask" "F.Paste")
			(net "MAX31790_U317_PWM_START0")
		)
		(pad "2" smd circle
			(at 0.40005 0 180)
			(size 0 0)
			(layers "F.Cu" "F.Mask" "F.Paste")
			(net "P3V3_AUX")
		)
	)
	(footprint ""
		(layer "F.Cu")
		(at 11.43 -223.52 180)
		(property "Reference" "PC48"
			(at 5.334 -5.99567 0)
			(unlocked yes)
			(layer "F.SilkS")
			(effects
				(font
					(size 0.7874 0.5842)
					(thickness 0.1524)
				)
				(justify left)
			)
		)
		(property "Value" ""
			(at 0 0 180)
			(layer "F.Fab")
			(effects
				(font
					(size 1.27 1.27)
				)
			)
		)
		(duplicate_pad_numbers_are_jumpers no)
		(fp_line
			(start 5.249926 5.249926)
			(end 5.249926 1.2446)
			(stroke
				(width 0.1524)
				(type default)
			)
			(layer "F.SilkS")
		)
		(fp_line
			(start 5.249926 -1.2446)
			(end 5.249926 -5.249926)
			(stroke
				(width 0.1524)
				(type default)
			)
			(layer "F.SilkS")
		)
		(fp_line
			(start 5.249926 -5.249926)
			(end -3.979926 -5.249926)
			(stroke
				(width 0.1524)
				(type default)
			)
			(layer "F.SilkS")
		)
		(fp_line
			(start -3.979926 5.249926)
			(end 5.249926 5.249926)
			(stroke
				(width 0.1524)
				(type default)
			)
			(layer "F.SilkS")
		)
		(fp_line
			(start -3.979926 -5.249926)
			(end -5.249926 -3.979926)
			(stroke
				(width 0.1524)
				(type default)
			)
			(layer "F.SilkS")
		)
		(fp_line
			(start -5.249926 3.979926)
			(end -3.979926 5.249926)
			(stroke
				(width 0.1524)
				(type default)
			)
			(layer "F.SilkS")
		)
		(fp_line
			(start -5.249926 1.2446)
			(end -5.249926 3.979926)
			(stroke
				(width 0.1524)
				(type default)
			)
			(layer "F.SilkS")
		)
		(fp_line
			(start -5.249926 -3.979926)
			(end -5.249926 -1.2446)
			(stroke
				(width 0.1524)
				(type default)
			)
			(layer "F.SilkS")
		)
		(fp_line
			(start 5.249926 5.249926)
			(end 5.249926 -5.249926)
			(stroke
				(width 0.1)
				(type default)
			)
			(layer "F.Fab")
		)
		(fp_line
			(start 5.249926 -5.249926)
			(end -5.249926 -5.249926)
			(stroke
				(width 0.1)
				(type default)
			)
			(layer "F.Fab")
		)
		(fp_line
			(start -5.249926 5.249926)
			(end 5.249926 5.249926)
			(stroke
				(width 0.1)
				(type default)
			)
			(layer "F.Fab")
		)
		(fp_line
			(start -5.249926 -5.249926)
			(end -5.249926 5.249926)
			(stroke
				(width 0.1)
				(type default)
			)
			(layer "F.Fab")
		)
		(pad "1" smd rect
			(at -4.45008 0 270)
			(size 2.2098 4.4196)
			(layers "F.Cu" "F.Mask" "F.Paste")
			(net "P52V_FAN_6")
		)
		(pad "2" smd rect
			(at 4.45008 0 270)
			(size 2.2098 4.4196)
			(layers "F.Cu" "F.Mask" "F.Paste")
			(net "GND")
		)
	)
	(footprint ""
		(layer "F.Cu")
		(at 5.280914 -66.732912 180)
		(property "Reference" "R5353"
			(at 0 0 180)
			(layer "F.SilkS")
			(hide yes)
			(effects
				(font
					(size 1.27 1.27)
				)
			)
		)
		(property "Value" ""
			(at 0 0 180)
			(layer "F.Fab")
			(effects
				(font
					(size 1.27 1.27)
				)
			)
		)
		(duplicate_pad_numbers_are_jumpers no)
		(fp_line
			(start 0.7874 0.4064)
			(end -0.7874 0.4064)
			(stroke
				(width 0.1524)
				(type default)
			)
			(layer "F.SilkS")
		)
		(fp_line
			(start 0.7874 -0.4064)
			(end 0.7874 0.4064)
			(stroke
				(width 0.1524)
				(type default)
			)
			(layer "F.SilkS")
		)
		(fp_line
			(start -0.7874 0.4064)
			(end -0.7874 -0.4064)
			(stroke
				(width 0.1524)
				(type default)
			)
			(layer "F.SilkS")
		)
		(fp_line
			(start -0.7874 -0.4064)
			(end 0.7874 -0.4064)
			(stroke
				(width 0.1524)
				(type default)
			)
			(layer "F.SilkS")
		)
		(fp_line
			(start 0.67945 0.3048)
			(end 0.120396 0.3048)
			(stroke
				(width 0.1)
				(type default)
			)
			(layer "F.Fab")
		)
		(fp_line
			(start 0.67945 -0.3048)
			(end 0.67945 0.3048)
			(stroke
				(width 0.1)
				(type default)
			)
			(layer "F.Fab")
		)
		(fp_line
			(start 0.12065 -0.2794)
			(end 0.12065 -0.3048)
			(stroke
				(width 0.1)
				(type default)
			)
			(layer "F.Fab")
		)
		(fp_line
			(start 0.12065 -0.3048)
			(end 0.67945 -0.3048)
			(stroke
				(width 0.1)
				(type default)
			)
			(layer "F.Fab")
		)
		(fp_line
			(start 0.120396 0.3048)
			(end 0.120396 0.2794)
			(stroke
				(width 0.1)
				(type default)
			)
			(layer "F.Fab")
		)
		(fp_line
			(start 0.120396 0.2794)
			(end -0.12065 0.2794)
			(stroke
				(width 0.1)
				(type default)
			)
			(layer "F.Fab")
		)
		(fp_line
			(start -0.12065 0.3048)
			(end -0.67945 0.3048)
			(stroke
				(width 0.1)
				(type default)
			)
			(layer "F.Fab")
		)
		(fp_line
			(start -0.12065 0.2794)
			(end -0.12065 0.3048)
			(stroke
				(width 0.1)
				(type default)
			)
			(layer "F.Fab")
		)
		(fp_line
			(start -0.12065 -0.2794)
			(end 0.12065 -0.2794)
			(stroke
				(width 0.1)
				(type default)
			)
			(layer "F.Fab")
		)
		(fp_line
			(start -0.12065 -0.305054)
			(end -0.12065 -0.2794)
			(stroke
				(width 0.1)
				(type default)
			)
			(layer "F.Fab")
		)
		(fp_line
			(start -0.67945 0.3048)
			(end -0.67945 -0.305054)
			(stroke
				(width 0.1)
				(type default)
			)
			(layer "F.Fab")
		)
		(fp_line
			(start -0.67945 -0.305054)
			(end -0.12065 -0.305054)
			(stroke
				(width 0.1)
				(type default)
			)
			(layer "F.Fab")
		)
		(pad "1" smd circle
			(at -0.40005 0 180)
			(size 0 0)
			(layers "F.Cu" "F.Mask" "F.Paste")
			(net "FAN_4_PRESENT_R")
		)
		(pad "2" smd circle
			(at 0.40005 0 180)
			(size 0 0)
			(layers "F.Cu" "F.Mask" "F.Paste")
			(net "FAN_4_PRESENT")
		)
	)
	(footprint ""
		(layer "F.Cu")
		(at 10.850118 -157.661102)
		(property "Reference" "H3"
			(at -0.563118 17.225772 0)
			(unlocked yes)
			(layer "F.SilkS")
			(effects
				(font
					(size 0.7874 0.5842)
					(thickness 0.1524)
				)
				(justify left)
			)
		)
		(property "Value" ""
			(at 0 0 0)
			(layer "F.Fab")
			(effects
				(font
					(size 1.27 1.27)
				)
			)
		)
		(duplicate_pad_numbers_are_jumpers no)
		(pad "1" thru_hole oval
			(at 0 0)
			(size 9.017 21.0058)
			(drill 3.0226
				(offset 0 5.999988)
			)
			(layers "*.Cu" "*.Mask")
			(remove_unused_layers no)
			(net "GND")
			(clearance -1.500378)
			(padstack
				(mode front_inner_back)
				(layer "Inner"
					(shape circle)
					(size 0 0)
					(clearance 0)
				)
				(layer "B.Cu"
					(shape oval)
					(size 9.017 21.0058)
					(offset 0 5.999988)
					(clearance -1.500378)
				)
			)
		)
	)
	(footprint ""
		(layer "F.Cu")
		(at 48.26 -130.937 180)
		(property "Reference" "R5559"
			(at 0 0 180)
			(layer "F.SilkS")
			(hide yes)
			(effects
				(font
					(size 1.27 1.27)
				)
			)
		)
		(property "Value" ""
			(at 0 0 180)
			(layer "F.Fab")
			(effects
				(font
					(size 1.27 1.27)
				)
			)
		)
		(duplicate_pad_numbers_are_jumpers no)
		(fp_line
			(start 0.7874 0.4064)
			(end -0.7874 0.4064)
			(stroke
				(width 0.1524)
				(type default)
			)
			(layer "F.SilkS")
		)
		(fp_line
			(start 0.7874 -0.4064)
			(end 0.7874 0.4064)
			(stroke
				(width 0.1524)
				(type default)
			)
			(layer "F.SilkS")
		)
		(fp_line
			(start -0.7874 0.4064)
			(end -0.7874 -0.4064)
			(stroke
				(width 0.1524)
				(type default)
			)
			(layer "F.SilkS")
		)
		(fp_line
			(start -0.7874 -0.4064)
			(end 0.7874 -0.4064)
			(stroke
				(width 0.1524)
				(type default)
			)
			(layer "F.SilkS")
		)
		(fp_line
			(start 0.67945 0.3048)
			(end 0.120396 0.3048)
			(stroke
				(width 0.1)
				(type default)
			)
			(layer "F.Fab")
		)
		(fp_line
			(start 0.67945 -0.3048)
			(end 0.67945 0.3048)
			(stroke
				(width 0.1)
				(type default)
			)
			(layer "F.Fab")
		)
		(fp_line
			(start 0.12065 -0.2794)
			(end 0.12065 -0.3048)
			(stroke
				(width 0.1)
				(type default)
			)
			(layer "F.Fab")
		)
		(fp_line
			(start 0.12065 -0.3048)
			(end 0.67945 -0.3048)
			(stroke
				(width 0.1)
				(type default)
			)
			(layer "F.Fab")
		)
		(fp_line
			(start 0.120396 0.3048)
			(end 0.120396 0.2794)
			(stroke
				(width 0.1)
				(type default)
			)
			(layer "F.Fab")
		)
		(fp_line
			(start 0.120396 0.2794)
			(end -0.12065 0.2794)
			(stroke
				(width 0.1)
				(type default)
			)
			(layer "F.Fab")
		)
		(fp_line
			(start -0.12065 0.3048)
			(end -0.67945 0.3048)
			(stroke
				(width 0.1)
				(type default)
			)
			(layer "F.Fab")
		)
		(fp_line
			(start -0.12065 0.2794)
			(end -0.12065 0.3048)
			(stroke
				(width 0.1)
				(type default)
			)
			(layer "F.Fab")
		)
		(fp_line
			(start -0.12065 -0.2794)
			(end 0.12065 -0.2794)
			(stroke
				(width 0.1)
				(type default)
			)
			(layer "F.Fab")
		)
		(fp_line
			(start -0.12065 -0.305054)
			(end -0.12065 -0.2794)
			(stroke
				(width 0.1)
				(type default)
			)
			(layer "F.Fab")
		)
		(fp_line
			(start -0.67945 0.3048)
			(end -0.67945 -0.305054)
			(stroke
				(width 0.1)
				(type default)
			)
			(layer "F.Fab")
		)
		(fp_line
			(start -0.67945 -0.305054)
			(end -0.12065 -0.305054)
			(stroke
				(width 0.1)
				(type default)
			)
			(layer "F.Fab")
		)
		(pad "1" smd circle
			(at -0.40005 0 180)
			(size 0 0)
			(layers "F.Cu" "F.Mask" "F.Paste")
			(net "P3V3_AUX")
		)
		(pad "2" smd circle
			(at 0.40005 0 180)
			(size 0 0)
			(layers "F.Cu" "F.Mask" "F.Paste")
			(net "U403_ADD0")
		)
	)
	(footprint ""
		(layer "F.Cu")
		(at 29.464 -19.05 -90)
		(property "Reference" "U399"
			(at 1.3462 -1.77927 90)
			(unlocked yes)
			(layer "F.SilkS")
			(effects
				(font
					(size 0.7874 0.5842)
					(thickness 0.1524)
				)
				(justify left)
			)
		)
		(property "Value" ""
			(at 0 0 270)
			(layer "F.Fab")
			(effects
				(font
					(size 1.27 1.27)
				)
			)
		)
		(duplicate_pad_numbers_are_jumpers no)
		(fp_line
			(start -1.33096 1.100074)
			(end -1.33096 -1.100074)
			(stroke
				(width 0.1524)
				(type default)
			)
			(layer "F.SilkS")
		)
		(fp_line
			(start 1.33096 1.100074)
			(end -1.33096 1.100074)
			(stroke
				(width 0.1524)
				(type default)
			)
			(layer "F.SilkS")
		)
		(fp_line
			(start 0 -0.649986)
			(end 0.381 -1.100074)
			(stroke
				(width 0.1524)
				(type default)
			)
			(layer "F.SilkS")
		)
		(fp_line
			(start -1.33096 -1.100074)
			(end -0.381 -1.100074)
			(stroke
				(width 0.1524)
				(type default)
			)
			(layer "F.SilkS")
		)
		(fp_line
			(start -0.381 -1.100074)
			(end 0 -0.649986)
			(stroke
				(width 0.1524)
				(type default)
			)
			(layer "F.SilkS")
		)
		(fp_line
			(start 0.381 -1.100074)
			(end 1.33096 -1.100074)
			(stroke
				(width 0.1524)
				(type default)
			)
			(layer "F.SilkS")
		)
		(fp_line
			(start 1.33096 -1.100074)
			(end 1.33096 1.100074)
			(stroke
				(width 0.1524)
				(type default)
			)
			(layer "F.SilkS")
		)
		(fp_poly
			(pts
				(xy -1.92659 -1.45669) (xy -2.285746 -1.097534) (xy -1.56718 -0.738124)
			)
			(stroke
				(width 0)
				(type default)
			)
			(fill yes)
			(layer "F.SilkS")
		)
		(fp_line
			(start -0.674878 1.100074)
			(end -0.674878 -1.100074)
			(stroke
				(width 0.1)
				(type default)
			)
			(layer "F.Fab")
		)
		(fp_line
			(start 0.674878 1.100074)
			(end -0.674878 1.100074)
			(stroke
				(width 0.1)
				(type default)
			)
			(layer "F.Fab")
		)
		(fp_line
			(start -0.674878 -1.100074)
			(end 0.674878 -1.100074)
			(stroke
				(width 0.1)
				(type default)
			)
			(layer "F.Fab")
		)
		(fp_line
			(start 0.674878 -1.100074)
			(end 0.674878 1.100074)
			(stroke
				(width 0.1)
				(type default)
			)
			(layer "F.Fab")
		)
		(fp_poly
			(pts
				(xy -2.209292 -0.902462) (xy -2.209292 -0.394462) (xy -1.447292 -0.648462)
			)
			(stroke
				(width 0)
				(type default)
			)
			(fill yes)
			(layer "F.Fab")
		)
		(pad "1" smd rect
			(at -0.94996 -0.649986)
			(size 0.4064 0.508)
			(layers "F.Cu" "F.Mask" "F.Paste")
			(net "NC_U399_P1")
		)
		(pad "2" smd rect
			(at -0.94996 0)
			(size 0.4064 0.508)
			(layers "F.Cu" "F.Mask" "F.Paste")
			(net "FAN_4_PWM")
		)
		(pad "3" smd rect
			(at -0.94996 0.649986)
			(size 0.4064 0.508)
			(layers "F.Cu" "F.Mask" "F.Paste")
			(net "GND")
		)
		(pad "4" smd rect
			(at 0.94996 0.649986)
			(size 0.4064 0.508)
			(layers "F.Cu" "F.Mask" "F.Paste")
			(net "FAN_4_PWM_BUF")
		)
		(pad "5" smd rect
			(at 0.94996 -0.649986)
			(size 0.4064 0.508)
			(layers "F.Cu" "F.Mask" "F.Paste")
			(net "P3V3_AUX")
		)
	)
	(footprint ""
		(layer "F.Cu")
		(at 36.703 -63.246)
		(property "Reference" "PR43"
			(at 0 0 0)
			(layer "F.SilkS")
			(hide yes)
			(effects
				(font
					(size 1.27 1.27)
				)
			)
		)
		(property "Value" ""
			(at 0 0 0)
			(layer "F.Fab")
			(effects
				(font
					(size 1.27 1.27)
				)
			)
		)
		(duplicate_pad_numbers_are_jumpers no)
		(fp_line
			(start -0.7874 -0.4064)
			(end 0.7874 -0.4064)
			(stroke
				(width 0.1524)
				(type default)
			)
			(layer "F.SilkS")
		)
		(fp_line
			(start -0.7874 0.4064)
			(end -0.7874 -0.4064)
			(stroke
				(width 0.1524)
				(type default)
			)
			(layer "F.SilkS")
		)
		(fp_line
			(start 0.7874 -0.4064)
			(end 0.7874 0.4064)
			(stroke
				(width 0.1524)
				(type default)
			)
			(layer "F.SilkS")
		)
		(fp_line
			(start 0.7874 0.4064)
			(end -0.7874 0.4064)
			(stroke
				(width 0.1524)
				(type default)
			)
			(layer "F.SilkS")
		)
		(fp_line
			(start -0.67945 -0.305054)
			(end -0.12065 -0.305054)
			(stroke
				(width 0.1)
				(type default)
			)
			(layer "F.Fab")
		)
		(fp_line
			(start -0.67945 0.3048)
			(end -0.67945 -0.305054)
			(stroke
				(width 0.1)
				(type default)
			)
			(layer "F.Fab")
		)
		(fp_line
			(start -0.12065 -0.305054)
			(end -0.12065 -0.2794)
			(stroke
				(width 0.1)
				(type default)
			)
			(layer "F.Fab")
		)
		(fp_line
			(start -0.12065 -0.2794)
			(end 0.12065 -0.2794)
			(stroke
				(width 0.1)
				(type default)
			)
			(layer "F.Fab")
		)
		(fp_line
			(start -0.12065 0.2794)
			(end -0.12065 0.3048)
			(stroke
				(width 0.1)
				(type default)
			)
			(layer "F.Fab")
		)
		(fp_line
			(start -0.12065 0.3048)
			(end -0.67945 0.3048)
			(stroke
				(width 0.1)
				(type default)
			)
			(layer "F.Fab")
		)
		(fp_line
			(start 0.120396 0.2794)
			(end -0.12065 0.2794)
			(stroke
				(width 0.1)
				(type default)
			)
			(layer "F.Fab")
		)
		(fp_line
			(start 0.120396 0.3048)
			(end 0.120396 0.2794)
			(stroke
				(width 0.1)
				(type default)
			)
			(layer "F.Fab")
		)
		(fp_line
			(start 0.12065 -0.3048)
			(end 0.67945 -0.3048)
			(stroke
				(width 0.1)
				(type default)
			)
			(layer "F.Fab")
		)
		(fp_line
			(start 0.12065 -0.2794)
			(end 0.12065 -0.3048)
			(stroke
				(width 0.1)
				(type default)
			)
			(layer "F.Fab")
		)
		(fp_line
			(start 0.67945 -0.3048)
			(end 0.67945 0.3048)
			(stroke
				(width 0.1)
				(type default)
			)
			(layer "F.Fab")
		)
		(fp_line
			(start 0.67945 0.3048)
			(end 0.120396 0.3048)
			(stroke
				(width 0.1)
				(type default)
			)
			(layer "F.Fab")
		)
		(pad "1" smd circle
			(at -0.40005 0)
			(size 0 0)
			(layers "F.Cu" "F.Mask" "F.Paste")
			(net "FAN_3_MODE")
		)
		(pad "2" smd circle
			(at 0.40005 0)
			(size 0 0)
			(layers "F.Cu" "F.Mask" "F.Paste")
			(net "GND")
		)
	)
	(footprint ""
		(layer "F.Cu")
		(at 32.258 -18.542 90)
		(property "Reference" "R5395"
			(at 0 0 90)
			(layer "F.SilkS")
			(hide yes)
			(effects
				(font
					(size 1.27 1.27)
				)
			)
		)
		(property "Value" ""
			(at 0 0 90)
			(layer "F.Fab")
			(effects
				(font
					(size 1.27 1.27)
				)
			)
		)
		(duplicate_pad_numbers_are_jumpers no)
		(fp_line
			(start 0.7874 -0.4064)
			(end 0.7874 0.4064)
			(stroke
				(width 0.1524)
				(type default)
			)
			(layer "F.SilkS")
		)
		(fp_line
			(start -0.7874 -0.4064)
			(end 0.7874 -0.4064)
			(stroke
				(width 0.1524)
				(type default)
			)
			(layer "F.SilkS")
		)
		(fp_line
			(start 0.7874 0.4064)
			(end -0.7874 0.4064)
			(stroke
				(width 0.1524)
				(type default)
			)
			(layer "F.SilkS")
		)
		(fp_line
			(start -0.7874 0.4064)
			(end -0.7874 -0.4064)
			(stroke
				(width 0.1524)
				(type default)
			)
			(layer "F.SilkS")
		)
		(fp_line
			(start -0.12065 -0.305054)
			(end -0.12065 -0.2794)
			(stroke
				(width 0.1)
				(type default)
			)
			(layer "F.Fab")
		)
		(fp_line
			(start -0.67945 -0.305054)
			(end -0.12065 -0.305054)
			(stroke
				(width 0.1)
				(type default)
			)
			(layer "F.Fab")
		)
		(fp_line
			(start 0.67945 -0.3048)
			(end 0.67945 0.3048)
			(stroke
				(width 0.1)
				(type default)
			)
			(layer "F.Fab")
		)
		(fp_line
			(start 0.12065 -0.3048)
			(end 0.67945 -0.3048)
			(stroke
				(width 0.1)
				(type default)
			)
			(layer "F.Fab")
		)
		(fp_line
			(start 0.12065 -0.2794)
			(end 0.12065 -0.3048)
			(stroke
				(width 0.1)
				(type default)
			)
			(layer "F.Fab")
		)
		(fp_line
			(start -0.12065 -0.2794)
			(end 0.12065 -0.2794)
			(stroke
				(width 0.1)
				(type default)
			)
			(layer "F.Fab")
		)
		(fp_line
			(start 0.120396 0.2794)
			(end -0.12065 0.2794)
			(stroke
				(width 0.1)
				(type default)
			)
			(layer "F.Fab")
		)
		(fp_line
			(start -0.12065 0.2794)
			(end -0.12065 0.3048)
			(stroke
				(width 0.1)
				(type default)
			)
			(layer "F.Fab")
		)
		(fp_line
			(start 0.67945 0.3048)
			(end 0.120396 0.3048)
			(stroke
				(width 0.1)
				(type default)
			)
			(layer "F.Fab")
		)
		(fp_line
			(start 0.120396 0.3048)
			(end 0.120396 0.2794)
			(stroke
				(width 0.1)
				(type default)
			)
			(layer "F.Fab")
		)
		(fp_line
			(start -0.12065 0.3048)
			(end -0.67945 0.3048)
			(stroke
				(width 0.1)
				(type default)
			)
			(layer "F.Fab")
		)
		(fp_line
			(start -0.67945 0.3048)
			(end -0.67945 -0.305054)
			(stroke
				(width 0.1)
				(type default)
			)
			(layer "F.Fab")
		)
		(pad "1" smd circle
			(at -0.40005 0 90)
			(size 0 0)
			(layers "F.Cu" "F.Mask" "F.Paste")
			(net "P3V3_AUX")
		)
		(pad "2" smd circle
			(at 0.40005 0 90)
			(size 0 0)
			(layers "F.Cu" "F.Mask" "F.Paste")
			(net "FAN_3_OK_R_LED")
		)
	)
	(footprint ""
		(layer "F.Cu")
		(at 33.274 -160.02 90)
		(property "Reference" "R4874"
			(at 0 0 90)
			(layer "F.SilkS")
			(hide yes)
			(effects
				(font
					(size 1.27 1.27)
				)
			)
		)
		(property "Value" ""
			(at 0 0 90)
			(layer "F.Fab")
			(effects
				(font
					(size 1.27 1.27)
				)
			)
		)
		(duplicate_pad_numbers_are_jumpers no)
		(fp_line
			(start 0.7874 -0.4064)
			(end 0.7874 0.4064)
			(stroke
				(width 0.1524)
				(type default)
			)
			(layer "F.SilkS")
		)
		(fp_line
			(start -0.7874 -0.4064)
			(end 0.7874 -0.4064)
			(stroke
				(width 0.1524)
				(type default)
			)
			(layer "F.SilkS")
		)
		(fp_line
			(start 0.7874 0.4064)
			(end -0.7874 0.4064)
			(stroke
				(width 0.1524)
				(type default)
			)
			(layer "F.SilkS")
		)
		(fp_line
			(start -0.7874 0.4064)
			(end -0.7874 -0.4064)
			(stroke
				(width 0.1524)
				(type default)
			)
			(layer "F.SilkS")
		)
		(fp_line
			(start -0.12065 -0.305054)
			(end -0.12065 -0.2794)
			(stroke
				(width 0.1)
				(type default)
			)
			(layer "F.Fab")
		)
		(fp_line
			(start -0.67945 -0.305054)
			(end -0.12065 -0.305054)
			(stroke
				(width 0.1)
				(type default)
			)
			(layer "F.Fab")
		)
		(fp_line
			(start 0.67945 -0.3048)
			(end 0.67945 0.3048)
			(stroke
				(width 0.1)
				(type default)
			)
			(layer "F.Fab")
		)
		(fp_line
			(start 0.12065 -0.3048)
			(end 0.67945 -0.3048)
			(stroke
				(width 0.1)
				(type default)
			)
			(layer "F.Fab")
		)
		(fp_line
			(start 0.12065 -0.2794)
			(end 0.12065 -0.3048)
			(stroke
				(width 0.1)
				(type default)
			)
			(layer "F.Fab")
		)
		(fp_line
			(start -0.12065 -0.2794)
			(end 0.12065 -0.2794)
			(stroke
				(width 0.1)
				(type default)
			)
			(layer "F.Fab")
		)
		(fp_line
			(start 0.120396 0.2794)
			(end -0.12065 0.2794)
			(stroke
				(width 0.1)
				(type default)
			)
			(layer "F.Fab")
		)
		(fp_line
			(start -0.12065 0.2794)
			(end -0.12065 0.3048)
			(stroke
				(width 0.1)
				(type default)
			)
			(layer "F.Fab")
		)
		(fp_line
			(start 0.67945 0.3048)
			(end 0.120396 0.3048)
			(stroke
				(width 0.1)
				(type default)
			)
			(layer "F.Fab")
		)
		(fp_line
			(start 0.120396 0.3048)
			(end 0.120396 0.2794)
			(stroke
				(width 0.1)
				(type default)
			)
			(layer "F.Fab")
		)
		(fp_line
			(start -0.12065 0.3048)
			(end -0.67945 0.3048)
			(stroke
				(width 0.1)
				(type default)
			)
			(layer "F.Fab")
		)
		(fp_line
			(start -0.67945 0.3048)
			(end -0.67945 -0.305054)
			(stroke
				(width 0.1)
				(type default)
			)
			(layer "F.Fab")
		)
		(pad "1" smd circle
			(at -0.40005 0 90)
			(size 0 0)
			(layers "F.Cu" "F.Mask" "F.Paste")
			(net "SMB_FAN4_R_SCL")
		)
		(pad "2" smd circle
			(at 0.40005 0 90)
			(size 0 0)
			(layers "F.Cu" "F.Mask" "F.Paste")
			(net "SMB_FAN4_SCL")
		)
	)
	(footprint ""
		(layer "F.Cu")
		(at 25.781 -208.788 180)
		(property "Reference" "U63"
			(at 1.13538 1.98247 0)
			(unlocked yes)
			(layer "F.SilkS")
			(effects
				(font
					(size 0.7874 0.5842)
					(thickness 0.1524)
				)
				(justify left)
			)
		)
		(property "Value" ""
			(at 0 0 180)
			(layer "F.Fab")
			(effects
				(font
					(size 1.27 1.27)
				)
			)
		)
		(duplicate_pad_numbers_are_jumpers no)
		(fp_line
			(start 1.538478 1.150874)
			(end 1.538478 -1.150874)
			(stroke
				(width 0.1524)
				(type default)
			)
			(layer "F.SilkS")
		)
		(fp_line
			(start 1.538478 -1.150874)
			(end -1.538478 -1.150874)
			(stroke
				(width 0.1524)
				(type default)
			)
			(layer "F.SilkS")
		)
		(fp_line
			(start -1.538478 1.150874)
			(end 1.538478 1.150874)
			(stroke
				(width 0.1524)
				(type default)
			)
			(layer "F.SilkS")
		)
		(fp_line
			(start -1.538478 -1.150874)
			(end -1.538478 1.150874)
			(stroke
				(width 0.1524)
				(type default)
			)
			(layer "F.SilkS")
		)
		(fp_line
			(start 0.674878 1.100074)
			(end 0.674878 -1.100074)
			(stroke
				(width 0.1)
				(type default)
			)
			(layer "F.Fab")
		)
		(fp_line
			(start 0.674878 -1.100074)
			(end -0.674878 -1.100074)
			(stroke
				(width 0.1)
				(type default)
			)
			(layer "F.Fab")
		)
		(fp_line
			(start -0.674878 1.100074)
			(end 0.674878 1.100074)
			(stroke
				(width 0.1)
				(type default)
			)
			(layer "F.Fab")
		)
		(fp_line
			(start -0.674878 -1.100074)
			(end -0.674878 1.100074)
			(stroke
				(width 0.1)
				(type default)
			)
			(layer "F.Fab")
		)
		(pad "1" smd rect
			(at -0.94996 -0.649986 270)
			(size 0.7112 0.9144)
			(layers "F.Cu" "F.Mask" "F.Paste")
			(net "FAN_1_PWM_IL")
		)
		(pad "2" smd rect
			(at -0.94996 0.649986 270)
			(size 0.7112 0.9144)
			(layers "F.Cu" "F.Mask" "F.Paste")
			(net "FAN_1_PWM_OL")
		)
		(pad "3" smd rect
			(at 0.94996 0 270)
			(size 0.7112 0.9144)
			(layers "F.Cu" "F.Mask" "F.Paste")
			(net "FAN_1_PWM_BUF")
		)
	)
	(footprint ""
		(layer "F.Cu")
		(at 32.893 -15.113)
		(property "Reference" "R5325"
			(at 0 0 0)
			(layer "F.SilkS")
			(hide yes)
			(effects
				(font
					(size 1.27 1.27)
				)
			)
		)
		(property "Value" ""
			(at 0 0 0)
			(layer "F.Fab")
			(effects
				(font
					(size 1.27 1.27)
				)
			)
		)
		(duplicate_pad_numbers_are_jumpers no)
		(fp_line
			(start -1.2954 -0.5842)
			(end 1.2954 -0.5842)
			(stroke
				(width 0.1524)
				(type default)
			)
			(layer "F.SilkS")
		)
		(fp_line
			(start -1.2954 0.5842)
			(end -1.2954 -0.5842)
			(stroke
				(width 0.1524)
				(type default)
			)
			(layer "F.SilkS")
		)
		(fp_line
			(start 1.2954 -0.5842)
			(end 1.2954 0.5842)
			(stroke
				(width 0.1524)
				(type default)
			)
			(layer "F.SilkS")
		)
		(fp_line
			(start 1.2954 0.5842)
			(end -1.2954 0.5842)
			(stroke
				(width 0.1524)
				(type default)
			)
			(layer "F.SilkS")
		)
		(fp_line
			(start -1.1938 -0.406654)
			(end -0.8636 -0.406654)
			(stroke
				(width 0.1)
				(type default)
			)
			(layer "F.Fab")
		)
		(fp_line
			(start -1.1938 0.4064)
			(end -1.1938 -0.406654)
			(stroke
				(width 0.1)
				(type default)
			)
			(layer "F.Fab")
		)
		(fp_line
			(start -0.8636 -0.4572)
			(end 0.8636 -0.4572)
			(stroke
				(width 0.1)
				(type default)
			)
			(layer "F.Fab")
		)
		(fp_line
			(start -0.8636 -0.406654)
			(end -0.8636 -0.4572)
			(stroke
				(width 0.1)
				(type default)
			)
			(layer "F.Fab")
		)
		(fp_line
			(start -0.8636 0.4064)
			(end -1.1938 0.4064)
			(stroke
				(width 0.1)
				(type default)
			)
			(layer "F.Fab")
		)
		(fp_line
			(start -0.8636 0.4318)
			(end -0.8636 0.4064)
			(stroke
				(width 0.1)
				(type default)
			)
			(layer "F.Fab")
		)
		(fp_line
			(start -0.8636 0.4572)
			(end -0.8636 0.4318)
			(stroke
				(width 0.1)
				(type default)
			)
			(layer "F.Fab")
		)
		(fp_line
			(start 0.8636 -0.4572)
			(end 0.8636 -0.406654)
			(stroke
				(width 0.1)
				(type default)
			)
			(layer "F.Fab")
		)
		(fp_line
			(start 0.8636 -0.406654)
			(end 1.1938 -0.406654)
			(stroke
				(width 0.1)
				(type default)
			)
			(layer "F.Fab")
		)
		(fp_line
			(start 0.8636 0.4064)
			(end 0.8636 0.4572)
			(stroke
				(width 0.1)
				(type default)
			)
			(layer "F.Fab")
		)
		(fp_line
			(start 0.8636 0.4572)
			(end -0.8636 0.4572)
			(stroke
				(width 0.1)
				(type default)
			)
			(layer "F.Fab")
		)
		(fp_line
			(start 1.1938 -0.406654)
			(end 1.1938 0.4064)
			(stroke
				(width 0.1)
				(type default)
			)
			(layer "F.Fab")
		)
		(fp_line
			(start 1.1938 0.4064)
			(end 0.8636 0.4064)
			(stroke
				(width 0.1)
				(type default)
			)
			(layer "F.Fab")
		)
		(pad "1" smd rect
			(at -0.7366 0 270)
			(size 0.7112 0.8128)
			(layers "F.Cu" "F.Mask" "F.Paste")
			(net "P52V_FAN_3")
		)
		(pad "2" smd rect
			(at 0.7366 0 270)
			(size 0.7112 0.8128)
			(layers "F.Cu" "F.Mask" "F.Paste")
			(net "FAN_3_TACH_OL_R")
		)
	)
	(footprint ""
		(layer "F.Cu")
		(at 26.945336 -20.713954 180)
		(property "Reference" "R5515"
			(at 0 0 180)
			(layer "F.SilkS")
			(hide yes)
			(effects
				(font
					(size 1.27 1.27)
				)
			)
		)
		(property "Value" ""
			(at 0 0 180)
			(layer "F.Fab")
			(effects
				(font
					(size 1.27 1.27)
				)
			)
		)
		(duplicate_pad_numbers_are_jumpers no)
		(fp_line
			(start 0.7874 0.4064)
			(end -0.7874 0.4064)
			(stroke
				(width 0.1524)
				(type default)
			)
			(layer "F.SilkS")
		)
		(fp_line
			(start 0.7874 -0.4064)
			(end 0.7874 0.4064)
			(stroke
				(width 0.1524)
				(type default)
			)
			(layer "F.SilkS")
		)
		(fp_line
			(start -0.7874 0.4064)
			(end -0.7874 -0.4064)
			(stroke
				(width 0.1524)
				(type default)
			)
			(layer "F.SilkS")
		)
		(fp_line
			(start -0.7874 -0.4064)
			(end 0.7874 -0.4064)
			(stroke
				(width 0.1524)
				(type default)
			)
			(layer "F.SilkS")
		)
		(fp_line
			(start 0.67945 0.3048)
			(end 0.120396 0.3048)
			(stroke
				(width 0.1)
				(type default)
			)
			(layer "F.Fab")
		)
		(fp_line
			(start 0.67945 -0.3048)
			(end 0.67945 0.3048)
			(stroke
				(width 0.1)
				(type default)
			)
			(layer "F.Fab")
		)
		(fp_line
			(start 0.12065 -0.2794)
			(end 0.12065 -0.3048)
			(stroke
				(width 0.1)
				(type default)
			)
			(layer "F.Fab")
		)
		(fp_line
			(start 0.12065 -0.3048)
			(end 0.67945 -0.3048)
			(stroke
				(width 0.1)
				(type default)
			)
			(layer "F.Fab")
		)
		(fp_line
			(start 0.120396 0.3048)
			(end 0.120396 0.2794)
			(stroke
				(width 0.1)
				(type default)
			)
			(layer "F.Fab")
		)
		(fp_line
			(start 0.120396 0.2794)
			(end -0.12065 0.2794)
			(stroke
				(width 0.1)
				(type default)
			)
			(layer "F.Fab")
		)
		(fp_line
			(start -0.12065 0.3048)
			(end -0.67945 0.3048)
			(stroke
				(width 0.1)
				(type default)
			)
			(layer "F.Fab")
		)
		(fp_line
			(start -0.12065 0.2794)
			(end -0.12065 0.3048)
			(stroke
				(width 0.1)
				(type default)
			)
			(layer "F.Fab")
		)
		(fp_line
			(start -0.12065 -0.2794)
			(end 0.12065 -0.2794)
			(stroke
				(width 0.1)
				(type default)
			)
			(layer "F.Fab")
		)
		(fp_line
			(start -0.12065 -0.305054)
			(end -0.12065 -0.2794)
			(stroke
				(width 0.1)
				(type default)
			)
			(layer "F.Fab")
		)
		(fp_line
			(start -0.67945 0.3048)
			(end -0.67945 -0.305054)
			(stroke
				(width 0.1)
				(type default)
			)
			(layer "F.Fab")
		)
		(fp_line
			(start -0.67945 -0.305054)
			(end -0.12065 -0.305054)
			(stroke
				(width 0.1)
				(type default)
			)
			(layer "F.Fab")
		)
		(pad "1" smd circle
			(at -0.40005 0 180)
			(size 0 0)
			(layers "F.Cu" "F.Mask" "F.Paste")
			(net "P3V3_AUX")
		)
		(pad "2" smd circle
			(at 0.40005 0 180)
			(size 0 0)
			(layers "F.Cu" "F.Mask" "F.Paste")
			(net "FAN_4_PWM_BUF")
		)
	)
	(footprint ""
		(layer "F.Cu")
		(at 32.258 -203.962 90)
		(property "Reference" "R5527"
			(at 0 0 90)
			(layer "F.SilkS")
			(hide yes)
			(effects
				(font
					(size 1.27 1.27)
				)
			)
		)
		(property "Value" ""
			(at 0 0 90)
			(layer "F.Fab")
			(effects
				(font
					(size 1.27 1.27)
				)
			)
		)
		(duplicate_pad_numbers_are_jumpers no)
		(fp_line
			(start 0.7874 -0.4064)
			(end 0.7874 0.4064)
			(stroke
				(width 0.1524)
				(type default)
			)
			(layer "F.SilkS")
		)
		(fp_line
			(start -0.7874 -0.4064)
			(end 0.7874 -0.4064)
			(stroke
				(width 0.1524)
				(type default)
			)
			(layer "F.SilkS")
		)
		(fp_line
			(start 0.7874 0.4064)
			(end -0.7874 0.4064)
			(stroke
				(width 0.1524)
				(type default)
			)
			(layer "F.SilkS")
		)
		(fp_line
			(start -0.7874 0.4064)
			(end -0.7874 -0.4064)
			(stroke
				(width 0.1524)
				(type default)
			)
			(layer "F.SilkS")
		)
		(fp_line
			(start -0.12065 -0.305054)
			(end -0.12065 -0.2794)
			(stroke
				(width 0.1)
				(type default)
			)
			(layer "F.Fab")
		)
		(fp_line
			(start -0.67945 -0.305054)
			(end -0.12065 -0.305054)
			(stroke
				(width 0.1)
				(type default)
			)
			(layer "F.Fab")
		)
		(fp_line
			(start 0.67945 -0.3048)
			(end 0.67945 0.3048)
			(stroke
				(width 0.1)
				(type default)
			)
			(layer "F.Fab")
		)
		(fp_line
			(start 0.12065 -0.3048)
			(end 0.67945 -0.3048)
			(stroke
				(width 0.1)
				(type default)
			)
			(layer "F.Fab")
		)
		(fp_line
			(start 0.12065 -0.2794)
			(end 0.12065 -0.3048)
			(stroke
				(width 0.1)
				(type default)
			)
			(layer "F.Fab")
		)
		(fp_line
			(start -0.12065 -0.2794)
			(end 0.12065 -0.2794)
			(stroke
				(width 0.1)
				(type default)
			)
			(layer "F.Fab")
		)
		(fp_line
			(start 0.120396 0.2794)
			(end -0.12065 0.2794)
			(stroke
				(width 0.1)
				(type default)
			)
			(layer "F.Fab")
		)
		(fp_line
			(start -0.12065 0.2794)
			(end -0.12065 0.3048)
			(stroke
				(width 0.1)
				(type default)
			)
			(layer "F.Fab")
		)
		(fp_line
			(start 0.67945 0.3048)
			(end 0.120396 0.3048)
			(stroke
				(width 0.1)
				(type default)
			)
			(layer "F.Fab")
		)
		(fp_line
			(start 0.120396 0.3048)
			(end 0.120396 0.2794)
			(stroke
				(width 0.1)
				(type default)
			)
			(layer "F.Fab")
		)
		(fp_line
			(start -0.12065 0.3048)
			(end -0.67945 0.3048)
			(stroke
				(width 0.1)
				(type default)
			)
			(layer "F.Fab")
		)
		(fp_line
			(start -0.67945 0.3048)
			(end -0.67945 -0.305054)
			(stroke
				(width 0.1)
				(type default)
			)
			(layer "F.Fab")
		)
		(pad "1" smd rect
			(at -0.40005 0 270)
			(size 0.4572 0.508)
			(layers "F.Cu" "F.Mask" "F.Paste")
			(net "P12V_LED_FAN1")
		)
		(pad "2" smd rect
			(at 0.40005 0 270)
			(size 0.4572 0.508)
			(layers "F.Cu" "F.Mask" "F.Paste")
			(net "FAN_1_FAIL_LED_R_N")
		)
	)
	(footprint ""
		(layer "F.Cu")
		(at 21.336 -215.519 180)
		(property "Reference" "U411"
			(at 1.40462 -1.83515 0)
			(unlocked yes)
			(layer "F.SilkS")
			(effects
				(font
					(size 0.7874 0.5842)
					(thickness 0.1524)
				)
				(justify left)
			)
		)
		(property "Value" ""
			(at 0 0 180)
			(layer "F.Fab")
			(effects
				(font
					(size 1.27 1.27)
				)
			)
		)
		(duplicate_pad_numbers_are_jumpers no)
		(fp_line
			(start 1.335278 1.100074)
			(end 1.335278 -1.100074)
			(stroke
				(width 0.1524)
				(type default)
			)
			(layer "F.SilkS")
		)
		(fp_line
			(start 1.335278 -1.100074)
			(end -1.335278 -1.100074)
			(stroke
				(width 0.1524)
				(type default)
			)
			(layer "F.SilkS")
		)
		(fp_line
			(start -1.335278 1.100074)
			(end 1.335278 1.100074)
			(stroke
				(width 0.1524)
				(type default)
			)
			(layer "F.SilkS")
		)
		(fp_line
			(start -1.335278 -1.100074)
			(end -1.335278 1.100074)
			(stroke
				(width 0.1524)
				(type default)
			)
			(layer "F.SilkS")
		)
		(fp_line
			(start 0.674878 1.100074)
			(end 0.674878 -1.100074)
			(stroke
				(width 0.1)
				(type default)
			)
			(layer "F.Fab")
		)
		(fp_line
			(start 0.674878 -1.100074)
			(end -0.674878 -1.100074)
			(stroke
				(width 0.1)
				(type default)
			)
			(layer "F.Fab")
		)
		(fp_line
			(start -0.674878 1.100074)
			(end 0.674878 1.100074)
			(stroke
				(width 0.1)
				(type default)
			)
			(layer "F.Fab")
		)
		(fp_line
			(start -0.674878 -1.100074)
			(end -0.674878 1.100074)
			(stroke
				(width 0.1)
				(type default)
			)
			(layer "F.Fab")
		)
		(pad "D" smd rect
			(at 0.8001 0 90)
			(size 0.6096 0.8128)
			(layers "F.Cu" "F.Mask" "F.Paste")
			(net "U411_D1")
		)
		(pad "G" smd rect
			(at -0.8001 -0.649986 90)
			(size 0.6096 0.8128)
			(layers "F.Cu" "F.Mask" "F.Paste")
			(net "FAN_6_PRESENT")
		)
		(pad "S" smd rect
			(at -0.8001 0.649986 90)
			(size 0.6096 0.8128)
			(layers "F.Cu" "F.Mask" "F.Paste")
			(net "GND")
		)
	)
	(footprint ""
		(layer "F.Cu")
		(at 32.893 -29.972 180)
		(property "Reference" "C2054"
			(at 0 0 180)
			(layer "F.SilkS")
			(hide yes)
			(effects
				(font
					(size 1.27 1.27)
				)
			)
		)
		(property "Value" ""
			(at 0 0 180)
			(layer "F.Fab")
			(effects
				(font
					(size 1.27 1.27)
				)
			)
		)
		(duplicate_pad_numbers_are_jumpers no)
		(fp_line
			(start 0.7874 0.4064)
			(end -0.7874 0.4064)
			(stroke
				(width 0.1524)
				(type default)
			)
			(layer "F.SilkS")
		)
		(fp_line
			(start 0.7874 -0.4064)
			(end 0.7874 0.4064)
			(stroke
				(width 0.1524)
				(type default)
			)
			(layer "F.SilkS")
		)
		(fp_line
			(start -0.7874 0.4064)
			(end -0.7874 -0.4064)
			(stroke
				(width 0.1524)
				(type default)
			)
			(layer "F.SilkS")
		)
		(fp_line
			(start -0.7874 -0.4064)
			(end 0.7874 -0.4064)
			(stroke
				(width 0.1524)
				(type default)
			)
			(layer "F.SilkS")
		)
		(fp_line
			(start 0.67945 0.3048)
			(end 0.120396 0.3048)
			(stroke
				(width 0.1)
				(type default)
			)
			(layer "F.Fab")
		)
		(fp_line
			(start 0.67945 -0.3048)
			(end 0.67945 0.3048)
			(stroke
				(width 0.1)
				(type default)
			)
			(layer "F.Fab")
		)
		(fp_line
			(start 0.12065 -0.2794)
			(end 0.12065 -0.3048)
			(stroke
				(width 0.1)
				(type default)
			)
			(layer "F.Fab")
		)
		(fp_line
			(start 0.12065 -0.3048)
			(end 0.67945 -0.3048)
			(stroke
				(width 0.1)
				(type default)
			)
			(layer "F.Fab")
		)
		(fp_line
			(start 0.120396 0.3048)
			(end 0.120396 0.2794)
			(stroke
				(width 0.1)
				(type default)
			)
			(layer "F.Fab")
		)
		(fp_line
			(start 0.120396 0.2794)
			(end -0.12065 0.2794)
			(stroke
				(width 0.1)
				(type default)
			)
			(layer "F.Fab")
		)
		(fp_line
			(start -0.12065 0.3048)
			(end -0.67945 0.3048)
			(stroke
				(width 0.1)
				(type default)
			)
			(layer "F.Fab")
		)
		(fp_line
			(start -0.12065 0.2794)
			(end -0.12065 0.3048)
			(stroke
				(width 0.1)
				(type default)
			)
			(layer "F.Fab")
		)
		(fp_line
			(start -0.12065 -0.2794)
			(end 0.12065 -0.2794)
			(stroke
				(width 0.1)
				(type default)
			)
			(layer "F.Fab")
		)
		(fp_line
			(start -0.12065 -0.305054)
			(end -0.12065 -0.2794)
			(stroke
				(width 0.1)
				(type default)
			)
			(layer "F.Fab")
		)
		(fp_line
			(start -0.67945 0.3048)
			(end -0.67945 -0.305054)
			(stroke
				(width 0.1)
				(type default)
			)
			(layer "F.Fab")
		)
		(fp_line
			(start -0.67945 -0.305054)
			(end -0.12065 -0.305054)
			(stroke
				(width 0.1)
				(type default)
			)
			(layer "F.Fab")
		)
		(pad "1" smd circle
			(at -0.40005 0 180)
			(size 0 0)
			(layers "F.Cu" "F.Mask" "F.Paste")
			(net "FAN_3_TACH_IL_R")
		)
		(pad "2" smd circle
			(at 0.40005 0 180)
			(size 0 0)
			(layers "F.Cu" "F.Mask" "F.Paste")
			(net "GND")
		)
	)
	(footprint ""
		(layer "F.Cu")
		(at 26.289 -116.84 180)
		(property "Reference" "U65"
			(at 1.4732 -2.05867 0)
			(unlocked yes)
			(layer "F.SilkS")
			(effects
				(font
					(size 0.7874 0.5842)
					(thickness 0.1524)
				)
				(justify left)
			)
		)
		(property "Value" ""
			(at 0 0 180)
			(layer "F.Fab")
			(effects
				(font
					(size 1.27 1.27)
				)
			)
		)
		(duplicate_pad_numbers_are_jumpers no)
		(fp_line
			(start 1.538478 1.150874)
			(end 1.538478 -1.150874)
			(stroke
				(width 0.1524)
				(type default)
			)
			(layer "F.SilkS")
		)
		(fp_line
			(start 1.538478 -1.150874)
			(end -1.538478 -1.150874)
			(stroke
				(width 0.1524)
				(type default)
			)
			(layer "F.SilkS")
		)
		(fp_line
			(start -1.538478 1.150874)
			(end 1.538478 1.150874)
			(stroke
				(width 0.1524)
				(type default)
			)
			(layer "F.SilkS")
		)
		(fp_line
			(start -1.538478 -1.150874)
			(end -1.538478 1.150874)
			(stroke
				(width 0.1524)
				(type default)
			)
			(layer "F.SilkS")
		)
		(fp_line
			(start 0.674878 1.100074)
			(end 0.674878 -1.100074)
			(stroke
				(width 0.1)
				(type default)
			)
			(layer "F.Fab")
		)
		(fp_line
			(start 0.674878 -1.100074)
			(end -0.674878 -1.100074)
			(stroke
				(width 0.1)
				(type default)
			)
			(layer "F.Fab")
		)
		(fp_line
			(start -0.674878 1.100074)
			(end 0.674878 1.100074)
			(stroke
				(width 0.1)
				(type default)
			)
			(layer "F.Fab")
		)
		(fp_line
			(start -0.674878 -1.100074)
			(end -0.674878 1.100074)
			(stroke
				(width 0.1)
				(type default)
			)
			(layer "F.Fab")
		)
		(pad "1" smd rect
			(at -0.94996 -0.649986 270)
			(size 0.7112 0.9144)
			(layers "F.Cu" "F.Mask" "F.Paste")
			(net "FAN_2_PWM_IL")
		)
		(pad "2" smd rect
			(at -0.94996 0.649986 270)
			(size 0.7112 0.9144)
			(layers "F.Cu" "F.Mask" "F.Paste")
			(net "FAN_2_PWM_OL")
		)
		(pad "3" smd rect
			(at 0.94996 0 270)
			(size 0.7112 0.9144)
			(layers "F.Cu" "F.Mask" "F.Paste")
			(net "FAN_2_PWM_BUF")
		)
	)
	(footprint ""
		(layer "F.Cu")
		(at 18.669 -19.098768 180)
		(property "Reference" "D244"
			(at -1.69164 1.600962 0)
			(unlocked yes)
			(layer "F.SilkS")
			(effects
				(font
					(size 0.7874 0.5842)
					(thickness 0.1524)
				)
				(justify left)
			)
		)
		(property "Value" ""
			(at 0 0 180)
			(layer "F.Fab")
			(effects
				(font
					(size 1.27 1.27)
				)
			)
		)
		(duplicate_pad_numbers_are_jumpers no)
		(fp_line
			(start 0.94488 0.450088)
			(end 0.94488 -0.450088)
			(stroke
				(width 0.1524)
				(type default)
			)
			(layer "F.SilkS")
		)
		(fp_line
			(start 0.94488 -0.450088)
			(end -0.854964 -0.450088)
			(stroke
				(width 0.1524)
				(type default)
			)
			(layer "F.SilkS")
		)
		(fp_line
			(start 0.870458 -0.2794)
			(end 0.845058 0.4064)
			(stroke
				(width 0.1524)
				(type default)
			)
			(layer "F.SilkS")
		)
		(fp_line
			(start 0.845058 0.4064)
			(end 0.845058 -0.381)
			(stroke
				(width 0.1524)
				(type default)
			)
			(layer "F.SilkS")
		)
		(fp_line
			(start -0.854964 0.450088)
			(end 0.925068 0.450088)
			(stroke
				(width 0.1524)
				(type default)
			)
			(layer "F.SilkS")
		)
		(fp_line
			(start -0.854964 -0.450088)
			(end -0.854964 0.450088)
			(stroke
				(width 0.1524)
				(type default)
			)
			(layer "F.SilkS")
		)
		(fp_line
			(start 0.54991 0.350012)
			(end 0.54991 -0.350012)
			(stroke
				(width 0.1)
				(type default)
			)
			(layer "F.Fab")
		)
		(fp_line
			(start 0.54991 -0.350012)
			(end -0.54991 -0.350012)
			(stroke
				(width 0.1)
				(type default)
			)
			(layer "F.Fab")
		)
		(fp_line
			(start -0.54991 0.350012)
			(end 0.54991 0.350012)
			(stroke
				(width 0.1)
				(type default)
			)
			(layer "F.Fab")
		)
		(fp_line
			(start -0.54991 -0.350012)
			(end -0.54991 0.350012)
			(stroke
				(width 0.1)
				(type default)
			)
			(layer "F.Fab")
		)
		(fp_text user "-"
			(at 1.778 0.935482 0)
			(unlocked yes)
			(layer "F.SilkS")
			(effects
				(font
					(size 1.905 1.4224)
					(thickness 0.1524)
				)
				(justify left)
			)
		)
		(fp_text user "+"
			(at -0.508 0.935482 0)
			(unlocked yes)
			(layer "F.SilkS")
			(effects
				(font
					(size 1.905 1.4224)
					(thickness 0.1524)
				)
				(justify left)
			)
		)
		(fp_text user "-"
			(at 2.48539 0.239014 0)
			(unlocked yes)
			(layer "F.Fab")
			(effects
				(font
					(size 1.905 1.4224)
					(thickness 0.1524)
				)
				(justify left)
			)
		)
		(fp_text user "+"
			(at -0.808228 0.239014 0)
			(unlocked yes)
			(layer "F.Fab")
			(effects
				(font
					(size 1.905 1.4224)
					(thickness 0.1524)
				)
				(justify left)
			)
		)
		(pad "A" smd rect
			(at -0.424942 0 180)
			(size 0.5588 0.6096)
			(layers "F.Cu" "F.Mask" "F.Paste")
			(net "GND")
		)
		(pad "C" smd rect
			(at 0.424942 0)
			(size 0.5588 0.6096)
			(layers "F.Cu" "F.Mask" "F.Paste")
			(net "FAN_4_PWM_IL_R")
		)
	)
	(footprint ""
		(layer "F.Cu")
		(at 32.766 -287.147 -90)
		(property "Reference" "C2023"
			(at 0 0 270)
			(layer "F.SilkS")
			(hide yes)
			(effects
				(font
					(size 1.27 1.27)
				)
			)
		)
		(property "Value" ""
			(at 0 0 270)
			(layer "F.Fab")
			(effects
				(font
					(size 1.27 1.27)
				)
			)
		)
		(duplicate_pad_numbers_are_jumpers no)
		(fp_line
			(start -0.7874 0.4064)
			(end -0.7874 -0.4064)
			(stroke
				(width 0.1524)
				(type default)
			)
			(layer "F.SilkS")
		)
		(fp_line
			(start 0.7874 0.4064)
			(end -0.7874 0.4064)
			(stroke
				(width 0.1524)
				(type default)
			)
			(layer "F.SilkS")
		)
		(fp_line
			(start -0.7874 -0.4064)
			(end 0.7874 -0.4064)
			(stroke
				(width 0.1524)
				(type default)
			)
			(layer "F.SilkS")
		)
		(fp_line
			(start 0.7874 -0.4064)
			(end 0.7874 0.4064)
			(stroke
				(width 0.1524)
				(type default)
			)
			(layer "F.SilkS")
		)
		(fp_line
			(start -0.67945 0.3048)
			(end -0.67945 -0.305054)
			(stroke
				(width 0.1)
				(type default)
			)
			(layer "F.Fab")
		)
		(fp_line
			(start -0.12065 0.3048)
			(end -0.67945 0.3048)
			(stroke
				(width 0.1)
				(type default)
			)
			(layer "F.Fab")
		)
		(fp_line
			(start 0.120396 0.3048)
			(end 0.120396 0.2794)
			(stroke
				(width 0.1)
				(type default)
			)
			(layer "F.Fab")
		)
		(fp_line
			(start 0.67945 0.3048)
			(end 0.120396 0.3048)
			(stroke
				(width 0.1)
				(type default)
			)
			(layer "F.Fab")
		)
		(fp_line
			(start -0.12065 0.2794)
			(end -0.12065 0.3048)
			(stroke
				(width 0.1)
				(type default)
			)
			(layer "F.Fab")
		)
		(fp_line
			(start 0.120396 0.2794)
			(end -0.12065 0.2794)
			(stroke
				(width 0.1)
				(type default)
			)
			(layer "F.Fab")
		)
		(fp_line
			(start -0.12065 -0.2794)
			(end 0.12065 -0.2794)
			(stroke
				(width 0.1)
				(type default)
			)
			(layer "F.Fab")
		)
		(fp_line
			(start 0.12065 -0.2794)
			(end 0.12065 -0.3048)
			(stroke
				(width 0.1)
				(type default)
			)
			(layer "F.Fab")
		)
		(fp_line
			(start 0.12065 -0.3048)
			(end 0.67945 -0.3048)
			(stroke
				(width 0.1)
				(type default)
			)
			(layer "F.Fab")
		)
		(fp_line
			(start 0.67945 -0.3048)
			(end 0.67945 0.3048)
			(stroke
				(width 0.1)
				(type default)
			)
			(layer "F.Fab")
		)
		(fp_line
			(start -0.67945 -0.305054)
			(end -0.12065 -0.305054)
			(stroke
				(width 0.1)
				(type default)
			)
			(layer "F.Fab")
		)
		(fp_line
			(start -0.12065 -0.305054)
			(end -0.12065 -0.2794)
			(stroke
				(width 0.1)
				(type default)
			)
			(layer "F.Fab")
		)
		(pad "1" smd circle
			(at -0.40005 0 270)
			(size 0 0)
			(layers "F.Cu" "F.Mask" "F.Paste")
			(net "FAN_0_TACH_OL_R")
		)
		(pad "2" smd circle
			(at 0.40005 0 270)
			(size 0 0)
			(layers "F.Cu" "F.Mask" "F.Paste")
			(net "GND")
		)
	)
	(footprint ""
		(layer "F.Cu")
		(at 14.351 -205.74 180)
		(property "Reference" "D251"
			(at 4.064 0.48133 0)
			(unlocked yes)
			(layer "F.SilkS")
			(effects
				(font
					(size 0.7874 0.5842)
					(thickness 0.1524)
				)
				(justify left)
			)
		)
		(property "Value" ""
			(at 0 0 180)
			(layer "F.Fab")
			(effects
				(font
					(size 1.27 1.27)
				)
			)
		)
		(duplicate_pad_numbers_are_jumpers no)
		(fp_line
			(start 0.94488 0.450088)
			(end 0.94488 -0.450088)
			(stroke
				(width 0.1524)
				(type default)
			)
			(layer "F.SilkS")
		)
		(fp_line
			(start 0.94488 -0.450088)
			(end -0.854964 -0.450088)
			(stroke
				(width 0.1524)
				(type default)
			)
			(layer "F.SilkS")
		)
		(fp_line
			(start 0.870458 -0.2794)
			(end 0.845058 0.4064)
			(stroke
				(width 0.1524)
				(type default)
			)
			(layer "F.SilkS")
		)
		(fp_line
			(start 0.845058 0.4064)
			(end 0.845058 -0.381)
			(stroke
				(width 0.1524)
				(type default)
			)
			(layer "F.SilkS")
		)
		(fp_line
			(start -0.854964 0.450088)
			(end 0.925068 0.450088)
			(stroke
				(width 0.1524)
				(type default)
			)
			(layer "F.SilkS")
		)
		(fp_line
			(start -0.854964 -0.450088)
			(end -0.854964 0.450088)
			(stroke
				(width 0.1524)
				(type default)
			)
			(layer "F.SilkS")
		)
		(fp_line
			(start 0.54991 0.350012)
			(end 0.54991 -0.350012)
			(stroke
				(width 0.1)
				(type default)
			)
			(layer "F.Fab")
		)
		(fp_line
			(start 0.54991 -0.350012)
			(end -0.54991 -0.350012)
			(stroke
				(width 0.1)
				(type default)
			)
			(layer "F.Fab")
		)
		(fp_line
			(start -0.54991 0.350012)
			(end 0.54991 0.350012)
			(stroke
				(width 0.1)
				(type default)
			)
			(layer "F.Fab")
		)
		(fp_line
			(start -0.54991 -0.350012)
			(end -0.54991 0.350012)
			(stroke
				(width 0.1)
				(type default)
			)
			(layer "F.Fab")
		)
		(fp_text user "-"
			(at 2.286 -0.15875 0)
			(unlocked yes)
			(layer "F.SilkS")
			(effects
				(font
					(size 1.905 1.4224)
					(thickness 0.1524)
				)
				(justify left)
			)
		)
		(fp_text user "+"
			(at -0.635 -0.15875 0)
			(unlocked yes)
			(layer "F.SilkS")
			(effects
				(font
					(size 1.905 1.4224)
					(thickness 0.1524)
				)
				(justify left)
			)
		)
		(fp_text user "-"
			(at 2.48539 0.239014 0)
			(unlocked yes)
			(layer "F.Fab")
			(effects
				(font
					(size 1.905 1.4224)
					(thickness 0.1524)
				)
				(justify left)
			)
		)
		(fp_text user "+"
			(at -0.808228 0.239014 0)
			(unlocked yes)
			(layer "F.Fab")
			(effects
				(font
					(size 1.905 1.4224)
					(thickness 0.1524)
				)
				(justify left)
			)
		)
		(pad "A" smd rect
			(at -0.424942 0 180)
			(size 0.5588 0.6096)
			(layers "F.Cu" "F.Mask" "F.Paste")
			(net "GND")
		)
		(pad "C" smd rect
			(at 0.424942 0)
			(size 0.5588 0.6096)
			(layers "F.Cu" "F.Mask" "F.Paste")
			(net "FAN_6_FAIL_R_LED_N")
		)
	)
	(footprint ""
		(layer "F.Cu")
		(at 23.241 -13.8938 -90)
		(property "Reference" "R4989"
			(at 0 0 270)
			(layer "F.SilkS")
			(hide yes)
			(effects
				(font
					(size 1.27 1.27)
				)
			)
		)
		(property "Value" ""
			(at 0 0 270)
			(layer "F.Fab")
			(effects
				(font
					(size 1.27 1.27)
				)
			)
		)
		(duplicate_pad_numbers_are_jumpers no)
		(fp_line
			(start -0.7874 0.4064)
			(end -0.7874 -0.4064)
			(stroke
				(width 0.1524)
				(type default)
			)
			(layer "F.SilkS")
		)
		(fp_line
			(start 0.7874 0.4064)
			(end -0.7874 0.4064)
			(stroke
				(width 0.1524)
				(type default)
			)
			(layer "F.SilkS")
		)
		(fp_line
			(start -0.7874 -0.4064)
			(end 0.7874 -0.4064)
			(stroke
				(width 0.1524)
				(type default)
			)
			(layer "F.SilkS")
		)
		(fp_line
			(start 0.7874 -0.4064)
			(end 0.7874 0.4064)
			(stroke
				(width 0.1524)
				(type default)
			)
			(layer "F.SilkS")
		)
		(fp_line
			(start -0.67945 0.3048)
			(end -0.67945 -0.305054)
			(stroke
				(width 0.1)
				(type default)
			)
			(layer "F.Fab")
		)
		(fp_line
			(start -0.12065 0.3048)
			(end -0.67945 0.3048)
			(stroke
				(width 0.1)
				(type default)
			)
			(layer "F.Fab")
		)
		(fp_line
			(start 0.120396 0.3048)
			(end 0.120396 0.2794)
			(stroke
				(width 0.1)
				(type default)
			)
			(layer "F.Fab")
		)
		(fp_line
			(start 0.67945 0.3048)
			(end 0.120396 0.3048)
			(stroke
				(width 0.1)
				(type default)
			)
			(layer "F.Fab")
		)
		(fp_line
			(start -0.12065 0.2794)
			(end -0.12065 0.3048)
			(stroke
				(width 0.1)
				(type default)
			)
			(layer "F.Fab")
		)
		(fp_line
			(start 0.120396 0.2794)
			(end -0.12065 0.2794)
			(stroke
				(width 0.1)
				(type default)
			)
			(layer "F.Fab")
		)
		(fp_line
			(start -0.12065 -0.2794)
			(end 0.12065 -0.2794)
			(stroke
				(width 0.1)
				(type default)
			)
			(layer "F.Fab")
		)
		(fp_line
			(start 0.12065 -0.2794)
			(end 0.12065 -0.3048)
			(stroke
				(width 0.1)
				(type default)
			)
			(layer "F.Fab")
		)
		(fp_line
			(start 0.12065 -0.3048)
			(end 0.67945 -0.3048)
			(stroke
				(width 0.1)
				(type default)
			)
			(layer "F.Fab")
		)
		(fp_line
			(start 0.67945 -0.3048)
			(end 0.67945 0.3048)
			(stroke
				(width 0.1)
				(type default)
			)
			(layer "F.Fab")
		)
		(fp_line
			(start -0.67945 -0.305054)
			(end -0.12065 -0.305054)
			(stroke
				(width 0.1)
				(type default)
			)
			(layer "F.Fab")
		)
		(fp_line
			(start -0.12065 -0.305054)
			(end -0.12065 -0.2794)
			(stroke
				(width 0.1)
				(type default)
			)
			(layer "F.Fab")
		)
		(pad "1" smd circle
			(at -0.40005 0 270)
			(size 0 0)
			(layers "F.Cu" "F.Mask" "F.Paste")
			(net "P3V3_AUX")
		)
		(pad "2" smd circle
			(at 0.40005 0 270)
			(size 0 0)
			(layers "F.Cu" "F.Mask" "F.Paste")
			(net "SMB_PDBV_FAN_R_SCL")
		)
	)
	(footprint ""
		(layer "F.Cu")
		(at 14.361922 -199.076056)
		(property "Reference" "R5221"
			(at 0 0 0)
			(layer "F.SilkS")
			(hide yes)
			(effects
				(font
					(size 1.27 1.27)
				)
			)
		)
		(property "Value" ""
			(at 0 0 0)
			(layer "F.Fab")
			(effects
				(font
					(size 1.27 1.27)
				)
			)
		)
		(duplicate_pad_numbers_are_jumpers no)
		(fp_line
			(start -0.7874 -0.4064)
			(end 0.7874 -0.4064)
			(stroke
				(width 0.1524)
				(type default)
			)
			(layer "F.SilkS")
		)
		(fp_line
			(start -0.7874 0.4064)
			(end -0.7874 -0.4064)
			(stroke
				(width 0.1524)
				(type default)
			)
			(layer "F.SilkS")
		)
		(fp_line
			(start 0.7874 -0.4064)
			(end 0.7874 0.4064)
			(stroke
				(width 0.1524)
				(type default)
			)
			(layer "F.SilkS")
		)
		(fp_line
			(start 0.7874 0.4064)
			(end -0.7874 0.4064)
			(stroke
				(width 0.1524)
				(type default)
			)
			(layer "F.SilkS")
		)
		(fp_line
			(start -0.67945 -0.305054)
			(end -0.12065 -0.305054)
			(stroke
				(width 0.1)
				(type default)
			)
			(layer "F.Fab")
		)
		(fp_line
			(start -0.67945 0.3048)
			(end -0.67945 -0.305054)
			(stroke
				(width 0.1)
				(type default)
			)
			(layer "F.Fab")
		)
		(fp_line
			(start -0.12065 -0.305054)
			(end -0.12065 -0.2794)
			(stroke
				(width 0.1)
				(type default)
			)
			(layer "F.Fab")
		)
		(fp_line
			(start -0.12065 -0.2794)
			(end 0.12065 -0.2794)
			(stroke
				(width 0.1)
				(type default)
			)
			(layer "F.Fab")
		)
		(fp_line
			(start -0.12065 0.2794)
			(end -0.12065 0.3048)
			(stroke
				(width 0.1)
				(type default)
			)
			(layer "F.Fab")
		)
		(fp_line
			(start -0.12065 0.3048)
			(end -0.67945 0.3048)
			(stroke
				(width 0.1)
				(type default)
			)
			(layer "F.Fab")
		)
		(fp_line
			(start 0.120396 0.2794)
			(end -0.12065 0.2794)
			(stroke
				(width 0.1)
				(type default)
			)
			(layer "F.Fab")
		)
		(fp_line
			(start 0.120396 0.3048)
			(end 0.120396 0.2794)
			(stroke
				(width 0.1)
				(type default)
			)
			(layer "F.Fab")
		)
		(fp_line
			(start 0.12065 -0.3048)
			(end 0.67945 -0.3048)
			(stroke
				(width 0.1)
				(type default)
			)
			(layer "F.Fab")
		)
		(fp_line
			(start 0.12065 -0.2794)
			(end 0.12065 -0.3048)
			(stroke
				(width 0.1)
				(type default)
			)
			(layer "F.Fab")
		)
		(fp_line
			(start 0.67945 -0.3048)
			(end 0.67945 0.3048)
			(stroke
				(width 0.1)
				(type default)
			)
			(layer "F.Fab")
		)
		(fp_line
			(start 0.67945 0.3048)
			(end 0.120396 0.3048)
			(stroke
				(width 0.1)
				(type default)
			)
			(layer "F.Fab")
		)
		(pad "1" smd circle
			(at -0.40005 0)
			(size 0 0)
			(layers "F.Cu" "F.Mask" "F.Paste")
			(net "FAN_6_PWM_IL_R")
		)
		(pad "2" smd circle
			(at 0.40005 0)
			(size 0 0)
			(layers "F.Cu" "F.Mask" "F.Paste")
			(net "FAN_6_PWM_IL")
		)
	)
	(footprint ""
		(layer "F.Cu")
		(at 34.671 -198.8058)
		(property "Reference" "U370"
			(at -4.064 -1.62433 0)
			(unlocked yes)
			(layer "F.SilkS")
			(effects
				(font
					(size 0.7874 0.5842)
					(thickness 0.1524)
				)
				(justify left)
			)
		)
		(property "Value" ""
			(at 0 0 0)
			(layer "F.Fab")
			(effects
				(font
					(size 1.27 1.27)
				)
			)
		)
		(duplicate_pad_numbers_are_jumpers no)
		(fp_line
			(start -1.335278 -1.100074)
			(end -1.335278 1.100074)
			(stroke
				(width 0.1524)
				(type default)
			)
			(layer "F.SilkS")
		)
		(fp_line
			(start -1.335278 1.100074)
			(end 1.335278 1.100074)
			(stroke
				(width 0.1524)
				(type default)
			)
			(layer "F.SilkS")
		)
		(fp_line
			(start 1.335278 -1.100074)
			(end -1.335278 -1.100074)
			(stroke
				(width 0.1524)
				(type default)
			)
			(layer "F.SilkS")
		)
		(fp_line
			(start 1.335278 1.100074)
			(end 1.335278 -1.100074)
			(stroke
				(width 0.1524)
				(type default)
			)
			(layer "F.SilkS")
		)
		(fp_line
			(start -0.674878 -1.100074)
			(end -0.674878 1.100074)
			(stroke
				(width 0.1)
				(type default)
			)
			(layer "F.Fab")
		)
		(fp_line
			(start -0.674878 1.100074)
			(end 0.674878 1.100074)
			(stroke
				(width 0.1)
				(type default)
			)
			(layer "F.Fab")
		)
		(fp_line
			(start 0.674878 -1.100074)
			(end -0.674878 -1.100074)
			(stroke
				(width 0.1)
				(type default)
			)
			(layer "F.Fab")
		)
		(fp_line
			(start 0.674878 1.100074)
			(end 0.674878 -1.100074)
			(stroke
				(width 0.1)
				(type default)
			)
			(layer "F.Fab")
		)
		(pad "D" smd rect
			(at 0.8001 0 270)
			(size 0.6096 0.8128)
			(layers "F.Cu" "F.Mask" "F.Paste")
			(net "FAN_1_OK_LED_R_N")
		)
		(pad "G" smd rect
			(at -0.8001 -0.649986 270)
			(size 0.6096 0.8128)
			(layers "F.Cu" "F.Mask" "F.Paste")
			(net "FAN_1_OK_R_LED")
		)
		(pad "S" smd rect
			(at -0.8001 0.649986 270)
			(size 0.6096 0.8128)
			(layers "F.Cu" "F.Mask" "F.Paste")
			(net "GND")
		)
	)
	(footprint ""
		(layer "F.Cu")
		(at 43.942 -131.572)
		(property "Reference" "U403"
			(at 2.794 3.07467 0)
			(unlocked yes)
			(layer "F.SilkS")
			(effects
				(font
					(size 0.7874 0.5842)
					(thickness 0.1524)
				)
				(justify left)
			)
		)
		(property "Value" ""
			(at 0 0 0)
			(layer "F.Fab")
			(effects
				(font
					(size 1.27 1.27)
				)
			)
		)
		(duplicate_pad_numbers_are_jumpers no)
		(fp_line
			(start -2.6416 0.762)
			(end -3.1496 0.762)
			(stroke
				(width 0.1524)
				(type default)
			)
			(layer "F.SilkS")
		)
		(fp_line
			(start -1.999996 -1.999996)
			(end -1.524 -1.999996)
			(stroke
				(width 0.1524)
				(type default)
			)
			(layer "F.SilkS")
		)
		(fp_line
			(start -1.999996 -1.524)
			(end -1.999996 -1.999996)
			(stroke
				(width 0.1524)
				(type default)
			)
			(layer "F.SilkS")
		)
		(fp_line
			(start -1.999996 1.999996)
			(end -1.999996 1.524)
			(stroke
				(width 0.1524)
				(type default)
			)
			(layer "F.SilkS")
		)
		(fp_line
			(start -1.524 1.999996)
			(end -1.999996 1.999996)
			(stroke
				(width 0.1524)
				(type default)
			)
			(layer "F.SilkS")
		)
		(fp_line
			(start 0.254 2.6416)
			(end 0.254 3.6576)
			(stroke
				(width 0.1524)
				(type default)
			)
			(layer "F.SilkS")
		)
		(fp_line
			(start 0.762 -2.9464)
			(end 0.762 -2.6416)
			(stroke
				(width 0.1524)
				(type default)
			)
			(layer "F.SilkS")
		)
		(fp_line
			(start 1.524 -1.999996)
			(end 1.999996 -1.999996)
			(stroke
				(width 0.1524)
				(type default)
			)
			(layer "F.SilkS")
		)
		(fp_line
			(start 1.999996 -1.999996)
			(end 1.999996 -1.524)
			(stroke
				(width 0.1524)
				(type default)
			)
			(layer "F.SilkS")
		)
		(fp_line
			(start 1.999996 1.524)
			(end 1.999996 1.999996)
			(stroke
				(width 0.1524)
				(type default)
			)
			(layer "F.SilkS")
		)
		(fp_line
			(start 1.999996 1.999996)
			(end 1.524 1.999996)
			(stroke
				(width 0.1524)
				(type default)
			)
			(layer "F.SilkS")
		)
		(fp_line
			(start 3.1496 0.254)
			(end 2.6416 0.254)
			(stroke
				(width 0.1524)
				(type default)
			)
			(layer "F.SilkS")
		)
		(fp_poly
			(pts
				(xy -2.82067 -1.051814) (xy -3.59029 -0.667258) (xy -3.59029 -1.436624)
			)
			(stroke
				(width 0)
				(type default)
			)
			(fill yes)
			(layer "F.SilkS")
		)
		(fp_line
			(start -2.6416 0.762)
			(end -3.1496 0.762)
			(stroke
				(width 0.1)
				(type default)
			)
			(layer "F.Fab")
		)
		(fp_line
			(start -1.999996 -1.999996)
			(end 1.999996 -1.999996)
			(stroke
				(width 0.1)
				(type default)
			)
			(layer "F.Fab")
		)
		(fp_line
			(start -1.999996 1.999996)
			(end -1.999996 -1.999996)
			(stroke
				(width 0.1)
				(type default)
			)
			(layer "F.Fab")
		)
		(fp_line
			(start 0.254 2.6416)
			(end 0.254 3.6576)
			(stroke
				(width 0.1)
				(type default)
			)
			(layer "F.Fab")
		)
		(fp_line
			(start 0.762 -3.6576)
			(end 0.762 -2.6416)
			(stroke
				(width 0.1)
				(type default)
			)
			(layer "F.Fab")
		)
		(fp_line
			(start 1.999996 -1.999996)
			(end 1.999996 1.999996)
			(stroke
				(width 0.1)
				(type default)
			)
			(layer "F.Fab")
		)
		(fp_line
			(start 1.999996 1.999996)
			(end -1.999996 1.999996)
			(stroke
				(width 0.1)
				(type default)
			)
			(layer "F.Fab")
		)
		(fp_line
			(start 3.1496 0.254)
			(end 2.6416 0.254)
			(stroke
				(width 0.1)
				(type default)
			)
			(layer "F.Fab")
		)
		(fp_poly
			(pts
				(xy -2.63779 -1.249934) (xy -3.40741 -0.865378) (xy -3.40741 -1.634744)
			)
			(stroke
				(width 0)
				(type default)
			)
			(fill yes)
			(layer "F.Fab")
		)
		(fp_text user "6"
			(at -3.00355 1.5494 270)
			(unlocked yes)
			(layer "F.SilkS")
			(effects
				(font
					(size 0.635 0.4064)
					(thickness 0.1524)
				)
			)
		)
		(fp_text user "24"
			(at -2.1971 -2.51841 0)
			(unlocked yes)
			(layer "F.SilkS")
			(effects
				(font
					(size 0.635 0.4064)
					(thickness 0.1524)
				)
			)
		)
		(fp_text user "7"
			(at -1.27 3.10515 0)
			(unlocked yes)
			(layer "F.SilkS")
			(effects
				(font
					(size 0.635 0.4064)
					(thickness 0.1524)
				)
			)
		)
		(fp_text user "12"
			(at 1.5748 3.02895 0)
			(unlocked yes)
			(layer "F.SilkS")
			(effects
				(font
					(size 0.635 0.4064)
					(thickness 0.1524)
				)
			)
		)
		(fp_text user "19"
			(at 1.778 -2.95275 0)
			(unlocked yes)
			(layer "F.SilkS")
			(effects
				(font
					(size 0.635 0.4064)
					(thickness 0.1524)
				)
			)
		)
		(fp_text user "18"
			(at 2.89941 -1.95326 270)
			(unlocked yes)
			(layer "F.SilkS")
			(effects
				(font
					(size 0.635 0.4064)
					(thickness 0.1524)
				)
			)
		)
		(fp_text user "13"
			(at 3.01625 1.524 270)
			(unlocked yes)
			(layer "F.SilkS")
			(effects
				(font
					(size 0.635 0.4064)
					(thickness 0.1524)
				)
			)
		)
		(fp_text user "6"
			(at -3.00355 1.5494 270)
			(unlocked yes)
			(layer "F.Fab")
			(effects
				(font
					(size 0.635 0.4064)
					(thickness 0.1524)
				)
			)
		)
		(fp_text user "24"
			(at -1.6256 -3.01625 0)
			(unlocked yes)
			(layer "F.Fab")
			(effects
				(font
					(size 0.635 0.4064)
					(thickness 0.1524)
				)
			)
		)
		(fp_text user "7"
			(at -1.27 3.10515 0)
			(unlocked yes)
			(layer "F.Fab")
			(effects
				(font
					(size 0.635 0.4064)
					(thickness 0.1524)
				)
			)
		)
		(fp_text user "12"
			(at 1.5748 3.02895 0)
			(unlocked yes)
			(layer "F.Fab")
			(effects
				(font
					(size 0.635 0.4064)
					(thickness 0.1524)
				)
			)
		)
		(fp_text user "19"
			(at 1.7018 -3.09245 0)
			(unlocked yes)
			(layer "F.Fab")
			(effects
				(font
					(size 0.635 0.4064)
					(thickness 0.1524)
				)
			)
		)
		(fp_text user "13"
			(at 3.01625 1.524 270)
			(unlocked yes)
			(layer "F.Fab")
			(effects
				(font
					(size 0.635 0.4064)
					(thickness 0.1524)
				)
			)
		)
		(fp_text user "18"
			(at 3.04165 -1.6256 270)
			(unlocked yes)
			(layer "F.Fab")
			(effects
				(font
					(size 0.635 0.4064)
					(thickness 0.1524)
				)
			)
		)
		(pad "1" smd rect
			(at -2.050034 -1.249934 270)
			(size 0.2794 0.9144)
			(layers "F.Cu" "F.Mask" "F.Paste")
			(net "FAN_0_PWM_R2")
		)
		(pad "2" smd rect
			(at -2.050034 -0.750062 270)
			(size 0.2794 0.9144)
			(layers "F.Cu" "F.Mask" "F.Paste")
			(net "FAN_0_TACH_IL_R2")
		)
		(pad "3" smd rect
			(at -2.050034 -0.249936 270)
			(size 0.2794 0.9144)
			(layers "F.Cu" "F.Mask" "F.Paste")
			(net "FAN_1_TACH_IL_R2")
		)
		(pad "4" smd rect
			(at -2.050034 0.249936 270)
			(size 0.2794 0.9144)
			(layers "F.Cu" "F.Mask" "F.Paste")
			(net "FAN_0_TACH_OL_R2")
		)
		(pad "5" smd rect
			(at -2.050034 0.750062 270)
			(size 0.2794 0.9144)
			(layers "F.Cu" "F.Mask" "F.Paste")
			(net "FAN_1_PWM_R2")
		)
		(pad "6" smd rect
			(at -2.050034 1.249934 270)
			(size 0.2794 0.9144)
			(layers "F.Cu" "F.Mask" "F.Paste")
			(net "FAN_1_TACH_OL_R2")
		)
		(pad "7" smd rect
			(at -1.249934 2.050034)
			(size 0.2794 0.9144)
			(layers "F.Cu" "F.Mask" "F.Paste")
			(net "FAN_2_PWM_R2")
		)
		(pad "8" smd rect
			(at -0.750062 2.050034)
			(size 0.2794 0.9144)
			(layers "F.Cu" "F.Mask" "F.Paste")
			(net "FAN_2_TACH_IL_R2")
		)
		(pad "9" smd rect
			(at -0.249936 2.050034)
			(size 0.2794 0.9144)
			(layers "F.Cu" "F.Mask" "F.Paste")
			(net "GND")
		)
		(pad "10" smd rect
			(at 0.249936 2.050034)
			(size 0.2794 0.9144)
			(layers "F.Cu" "F.Mask" "F.Paste")
			(net "FAN_3_TACH_IL_R2")
		)
		(pad "11" smd rect
			(at 0.750062 2.050034)
			(size 0.2794 0.9144)
			(layers "F.Cu" "F.Mask" "F.Paste")
			(net "FAN_2_TACH_OL_R2")
		)
		(pad "12" smd rect
			(at 1.249934 2.050034)
			(size 0.2794 0.9144)
			(layers "F.Cu" "F.Mask" "F.Paste")
			(net "FAN_3_PWM_R2")
		)
		(pad "13" smd rect
			(at 2.050034 1.249934 270)
			(size 0.2794 0.9144)
			(layers "F.Cu" "F.Mask" "F.Paste")
			(net "FAN_3_TACH_OL_R2")
		)
		(pad "14" smd rect
			(at 2.050034 0.750062 270)
			(size 0.2794 0.9144)
			(layers "F.Cu" "F.Mask" "F.Paste")
			(net "NC_U403_P14")
		)
		(pad "15" smd rect
			(at 2.050034 0.249936 270)
			(size 0.2794 0.9144)
			(layers "F.Cu" "F.Mask" "F.Paste")
			(net "NC_U403_P15")
		)
		(pad "16" smd rect
			(at 2.050034 -0.249936 270)
			(size 0.2794 0.9144)
			(layers "F.Cu" "F.Mask" "F.Paste")
			(net "NC_U403_P16")
		)
		(pad "17" smd rect
			(at 2.050034 -0.750062 270)
			(size 0.2794 0.9144)
			(layers "F.Cu" "F.Mask" "F.Paste")
			(net "NC_U403_P17")
		)
		(pad "18" smd rect
			(at 2.050034 -1.249934 270)
			(size 0.2794 0.9144)
			(layers "F.Cu" "F.Mask" "F.Paste")
			(net "U403_ADD0")
		)
		(pad "19" smd rect
			(at 1.249934 -2.050034)
			(size 0.2794 0.9144)
			(layers "F.Cu" "F.Mask" "F.Paste")
			(net "SMB_PDBV_FAN_R_U403_SCL")
		)
		(pad "20" smd rect
			(at 0.750062 -2.050034)
			(size 0.2794 0.9144)
			(layers "F.Cu" "F.Mask" "F.Paste")
			(net "SMB_PDBV_FAN_R_U403_SDA")
		)
		(pad "21" smd rect
			(at 0.249936 -2.050034)
			(size 0.2794 0.9144)
			(layers "F.Cu" "F.Mask" "F.Paste")
			(net "P3V3_AUX")
		)
		(pad "22" smd rect
			(at -0.249936 -2.050034)
			(size 0.2794 0.9144)
			(layers "F.Cu" "F.Mask" "F.Paste")
			(net "NC_U403_P22")
		)
		(pad "23" smd rect
			(at -0.750062 -2.050034)
			(size 0.2794 0.9144)
			(layers "F.Cu" "F.Mask" "F.Paste")
			(net "U403_ADD1")
		)
		(pad "24" smd rect
			(at -1.249934 -2.050034)
			(size 0.2794 0.9144)
			(layers "F.Cu" "F.Mask" "F.Paste")
			(net "U403_ADD2")
		)
		(pad "TH" smd rect
			(at 0 0)
			(size 2.7686 2.7686)
			(layers "F.Cu" "F.Mask" "F.Paste")
			(net "GND")
		)
		(zone
			(layer "F.Cu")
			(hatch none 0.5)
			(connect_pads
				(clearance 0)
			)
			(min_thickness 0.25)
			(keepout
				(tracks not_allowed)
				(vias allowed)
				(pads allowed)
				(copperpour not_allowed)
				(footprints allowed)
			)
			(placement
				(enabled no)
				(sheetname "")
			)
			(fill
				(thermal_gap 0.5)
				(thermal_bridge_width 0.5)
				(island_removal_mode 0)
			)
			(polygon
				(pts
					(xy 42.418 -130.048) (xy 42.418 -133.096) (xy 45.466 -133.096) (xy 45.466 -133.0198) (xy 42.4942 -133.0198)
					(xy 42.4942 -130.1242) (xy 45.3898 -130.1242) (xy 45.3898 -132.9944) (xy 45.466 -132.9944) (xy 45.466 -130.048)
				)
			)
		)
	)
	(footprint ""
		(layer "F.Cu")
		(at 33.02 -116.008912 180)
		(property "Reference" "C2042"
			(at 0 0 180)
			(layer "F.SilkS")
			(hide yes)
			(effects
				(font
					(size 1.27 1.27)
				)
			)
		)
		(property "Value" ""
			(at 0 0 180)
			(layer "F.Fab")
			(effects
				(font
					(size 1.27 1.27)
				)
			)
		)
		(duplicate_pad_numbers_are_jumpers no)
		(fp_line
			(start 0.7874 0.4064)
			(end -0.7874 0.4064)
			(stroke
				(width 0.1524)
				(type default)
			)
			(layer "F.SilkS")
		)
		(fp_line
			(start 0.7874 -0.4064)
			(end 0.7874 0.4064)
			(stroke
				(width 0.1524)
				(type default)
			)
			(layer "F.SilkS")
		)
		(fp_line
			(start -0.7874 0.4064)
			(end -0.7874 -0.4064)
			(stroke
				(width 0.1524)
				(type default)
			)
			(layer "F.SilkS")
		)
		(fp_line
			(start -0.7874 -0.4064)
			(end 0.7874 -0.4064)
			(stroke
				(width 0.1524)
				(type default)
			)
			(layer "F.SilkS")
		)
		(fp_line
			(start 0.67945 0.3048)
			(end 0.120396 0.3048)
			(stroke
				(width 0.1)
				(type default)
			)
			(layer "F.Fab")
		)
		(fp_line
			(start 0.67945 -0.3048)
			(end 0.67945 0.3048)
			(stroke
				(width 0.1)
				(type default)
			)
			(layer "F.Fab")
		)
		(fp_line
			(start 0.12065 -0.2794)
			(end 0.12065 -0.3048)
			(stroke
				(width 0.1)
				(type default)
			)
			(layer "F.Fab")
		)
		(fp_line
			(start 0.12065 -0.3048)
			(end 0.67945 -0.3048)
			(stroke
				(width 0.1)
				(type default)
			)
			(layer "F.Fab")
		)
		(fp_line
			(start 0.120396 0.3048)
			(end 0.120396 0.2794)
			(stroke
				(width 0.1)
				(type default)
			)
			(layer "F.Fab")
		)
		(fp_line
			(start 0.120396 0.2794)
			(end -0.12065 0.2794)
			(stroke
				(width 0.1)
				(type default)
			)
			(layer "F.Fab")
		)
		(fp_line
			(start -0.12065 0.3048)
			(end -0.67945 0.3048)
			(stroke
				(width 0.1)
				(type default)
			)
			(layer "F.Fab")
		)
		(fp_line
			(start -0.12065 0.2794)
			(end -0.12065 0.3048)
			(stroke
				(width 0.1)
				(type default)
			)
			(layer "F.Fab")
		)
		(fp_line
			(start -0.12065 -0.2794)
			(end 0.12065 -0.2794)
			(stroke
				(width 0.1)
				(type default)
			)
			(layer "F.Fab")
		)
		(fp_line
			(start -0.12065 -0.305054)
			(end -0.12065 -0.2794)
			(stroke
				(width 0.1)
				(type default)
			)
			(layer "F.Fab")
		)
		(fp_line
			(start -0.67945 0.3048)
			(end -0.67945 -0.305054)
			(stroke
				(width 0.1)
				(type default)
			)
			(layer "F.Fab")
		)
		(fp_line
			(start -0.67945 -0.305054)
			(end -0.12065 -0.305054)
			(stroke
				(width 0.1)
				(type default)
			)
			(layer "F.Fab")
		)
		(pad "1" smd circle
			(at -0.40005 0 180)
			(size 0 0)
			(layers "F.Cu" "F.Mask" "F.Paste")
			(net "FAN_2_TACH_IL_R")
		)
		(pad "2" smd circle
			(at 0.40005 0 180)
			(size 0 0)
			(layers "F.Cu" "F.Mask" "F.Paste")
			(net "GND")
		)
	)
	(footprint ""
		(layer "F.Cu")
		(at 37.846 -130.048 180)
		(property "Reference" "R5603"
			(at 0 0 180)
			(layer "F.SilkS")
			(hide yes)
			(effects
				(font
					(size 1.27 1.27)
				)
			)
		)
		(property "Value" ""
			(at 0 0 180)
			(layer "F.Fab")
			(effects
				(font
					(size 1.27 1.27)
				)
			)
		)
		(duplicate_pad_numbers_are_jumpers no)
		(fp_line
			(start 0.7874 0.4064)
			(end -0.7874 0.4064)
			(stroke
				(width 0.1524)
				(type default)
			)
			(layer "F.SilkS")
		)
		(fp_line
			(start 0.7874 -0.4064)
			(end 0.7874 0.4064)
			(stroke
				(width 0.1524)
				(type default)
			)
			(layer "F.SilkS")
		)
		(fp_line
			(start -0.7874 0.4064)
			(end -0.7874 -0.4064)
			(stroke
				(width 0.1524)
				(type default)
			)
			(layer "F.SilkS")
		)
		(fp_line
			(start -0.7874 -0.4064)
			(end 0.7874 -0.4064)
			(stroke
				(width 0.1524)
				(type default)
			)
			(layer "F.SilkS")
		)
		(fp_line
			(start 0.67945 0.3048)
			(end 0.120396 0.3048)
			(stroke
				(width 0.1)
				(type default)
			)
			(layer "F.Fab")
		)
		(fp_line
			(start 0.67945 -0.3048)
			(end 0.67945 0.3048)
			(stroke
				(width 0.1)
				(type default)
			)
			(layer "F.Fab")
		)
		(fp_line
			(start 0.12065 -0.2794)
			(end 0.12065 -0.3048)
			(stroke
				(width 0.1)
				(type default)
			)
			(layer "F.Fab")
		)
		(fp_line
			(start 0.12065 -0.3048)
			(end 0.67945 -0.3048)
			(stroke
				(width 0.1)
				(type default)
			)
			(layer "F.Fab")
		)
		(fp_line
			(start 0.120396 0.3048)
			(end 0.120396 0.2794)
			(stroke
				(width 0.1)
				(type default)
			)
			(layer "F.Fab")
		)
		(fp_line
			(start 0.120396 0.2794)
			(end -0.12065 0.2794)
			(stroke
				(width 0.1)
				(type default)
			)
			(layer "F.Fab")
		)
		(fp_line
			(start -0.12065 0.3048)
			(end -0.67945 0.3048)
			(stroke
				(width 0.1)
				(type default)
			)
			(layer "F.Fab")
		)
		(fp_line
			(start -0.12065 0.2794)
			(end -0.12065 0.3048)
			(stroke
				(width 0.1)
				(type default)
			)
			(layer "F.Fab")
		)
		(fp_line
			(start -0.12065 -0.2794)
			(end 0.12065 -0.2794)
			(stroke
				(width 0.1)
				(type default)
			)
			(layer "F.Fab")
		)
		(fp_line
			(start -0.12065 -0.305054)
			(end -0.12065 -0.2794)
			(stroke
				(width 0.1)
				(type default)
			)
			(layer "F.Fab")
		)
		(fp_line
			(start -0.67945 0.3048)
			(end -0.67945 -0.305054)
			(stroke
				(width 0.1)
				(type default)
			)
			(layer "F.Fab")
		)
		(fp_line
			(start -0.67945 -0.305054)
			(end -0.12065 -0.305054)
			(stroke
				(width 0.1)
				(type default)
			)
			(layer "F.Fab")
		)
		(pad "1" smd rect
			(at -0.40005 0)
			(size 0.4572 0.508)
			(layers "F.Cu" "F.Mask" "F.Paste")
			(net "FAN_2_PWM")
		)
		(pad "2" smd rect
			(at 0.40005 0)
			(size 0.4572 0.508)
			(layers "F.Cu" "F.Mask" "F.Paste")
			(net "FAN_2_PWM_R1")
		)
	)
	(footprint ""
		(layer "F.Cu")
		(at 20.828 -176.784)
		(property "Reference" "R5686"
			(at 0 0 0)
			(layer "F.SilkS")
			(hide yes)
			(effects
				(font
					(size 1.27 1.27)
				)
			)
		)
		(property "Value" ""
			(at 0 0 0)
			(layer "F.Fab")
			(effects
				(font
					(size 1.27 1.27)
				)
			)
		)
		(duplicate_pad_numbers_are_jumpers no)
		(fp_line
			(start -0.7874 -0.4064)
			(end 0.7874 -0.4064)
			(stroke
				(width 0.1524)
				(type default)
			)
			(layer "F.SilkS")
		)
		(fp_line
			(start -0.7874 0.4064)
			(end -0.7874 -0.4064)
			(stroke
				(width 0.1524)
				(type default)
			)
			(layer "F.SilkS")
		)
		(fp_line
			(start 0.7874 -0.4064)
			(end 0.7874 0.4064)
			(stroke
				(width 0.1524)
				(type default)
			)
			(layer "F.SilkS")
		)
		(fp_line
			(start 0.7874 0.4064)
			(end -0.7874 0.4064)
			(stroke
				(width 0.1524)
				(type default)
			)
			(layer "F.SilkS")
		)
		(fp_line
			(start -0.67945 -0.305054)
			(end -0.12065 -0.305054)
			(stroke
				(width 0.1)
				(type default)
			)
			(layer "F.Fab")
		)
		(fp_line
			(start -0.67945 0.3048)
			(end -0.67945 -0.305054)
			(stroke
				(width 0.1)
				(type default)
			)
			(layer "F.Fab")
		)
		(fp_line
			(start -0.12065 -0.305054)
			(end -0.12065 -0.2794)
			(stroke
				(width 0.1)
				(type default)
			)
			(layer "F.Fab")
		)
		(fp_line
			(start -0.12065 -0.2794)
			(end 0.12065 -0.2794)
			(stroke
				(width 0.1)
				(type default)
			)
			(layer "F.Fab")
		)
		(fp_line
			(start -0.12065 0.2794)
			(end -0.12065 0.3048)
			(stroke
				(width 0.1)
				(type default)
			)
			(layer "F.Fab")
		)
		(fp_line
			(start -0.12065 0.3048)
			(end -0.67945 0.3048)
			(stroke
				(width 0.1)
				(type default)
			)
			(layer "F.Fab")
		)
		(fp_line
			(start 0.120396 0.2794)
			(end -0.12065 0.2794)
			(stroke
				(width 0.1)
				(type default)
			)
			(layer "F.Fab")
		)
		(fp_line
			(start 0.120396 0.3048)
			(end 0.120396 0.2794)
			(stroke
				(width 0.1)
				(type default)
			)
			(layer "F.Fab")
		)
		(fp_line
			(start 0.12065 -0.3048)
			(end 0.67945 -0.3048)
			(stroke
				(width 0.1)
				(type default)
			)
			(layer "F.Fab")
		)
		(fp_line
			(start 0.12065 -0.2794)
			(end 0.12065 -0.3048)
			(stroke
				(width 0.1)
				(type default)
			)
			(layer "F.Fab")
		)
		(fp_line
			(start 0.67945 -0.3048)
			(end 0.67945 0.3048)
			(stroke
				(width 0.1)
				(type default)
			)
			(layer "F.Fab")
		)
		(fp_line
			(start 0.67945 0.3048)
			(end 0.120396 0.3048)
			(stroke
				(width 0.1)
				(type default)
			)
			(layer "F.Fab")
		)
		(pad "1" smd circle
			(at -0.40005 0)
			(size 0 0)
			(layers "F.Cu" "F.Mask" "F.Paste")
			(net "FM_BOARD_ID0")
		)
		(pad "2" smd circle
			(at 0.40005 0)
			(size 0 0)
			(layers "F.Cu" "F.Mask" "F.Paste")
			(net "GND")
		)
	)
	(footprint ""
		(layer "F.Cu")
		(at 4.318 -251.714 -90)
		(property "Reference" "R5422"
			(at 0 0 270)
			(layer "F.SilkS")
			(hide yes)
			(effects
				(font
					(size 1.27 1.27)
				)
			)
		)
		(property "Value" ""
			(at 0 0 270)
			(layer "F.Fab")
			(effects
				(font
					(size 1.27 1.27)
				)
			)
		)
		(duplicate_pad_numbers_are_jumpers no)
		(fp_line
			(start -0.7874 0.4064)
			(end -0.7874 -0.4064)
			(stroke
				(width 0.1524)
				(type default)
			)
			(layer "F.SilkS")
		)
		(fp_line
			(start 0.7874 0.4064)
			(end -0.7874 0.4064)
			(stroke
				(width 0.1524)
				(type default)
			)
			(layer "F.SilkS")
		)
		(fp_line
			(start -0.7874 -0.4064)
			(end 0.7874 -0.4064)
			(stroke
				(width 0.1524)
				(type default)
			)
			(layer "F.SilkS")
		)
		(fp_line
			(start 0.7874 -0.4064)
			(end 0.7874 0.4064)
			(stroke
				(width 0.1524)
				(type default)
			)
			(layer "F.SilkS")
		)
		(fp_line
			(start -0.67945 0.3048)
			(end -0.67945 -0.305054)
			(stroke
				(width 0.1)
				(type default)
			)
			(layer "F.Fab")
		)
		(fp_line
			(start -0.12065 0.3048)
			(end -0.67945 0.3048)
			(stroke
				(width 0.1)
				(type default)
			)
			(layer "F.Fab")
		)
		(fp_line
			(start 0.120396 0.3048)
			(end 0.120396 0.2794)
			(stroke
				(width 0.1)
				(type default)
			)
			(layer "F.Fab")
		)
		(fp_line
			(start 0.67945 0.3048)
			(end 0.120396 0.3048)
			(stroke
				(width 0.1)
				(type default)
			)
			(layer "F.Fab")
		)
		(fp_line
			(start -0.12065 0.2794)
			(end -0.12065 0.3048)
			(stroke
				(width 0.1)
				(type default)
			)
			(layer "F.Fab")
		)
		(fp_line
			(start 0.120396 0.2794)
			(end -0.12065 0.2794)
			(stroke
				(width 0.1)
				(type default)
			)
			(layer "F.Fab")
		)
		(fp_line
			(start -0.12065 -0.2794)
			(end 0.12065 -0.2794)
			(stroke
				(width 0.1)
				(type default)
			)
			(layer "F.Fab")
		)
		(fp_line
			(start 0.12065 -0.2794)
			(end 0.12065 -0.3048)
			(stroke
				(width 0.1)
				(type default)
			)
			(layer "F.Fab")
		)
		(fp_line
			(start 0.12065 -0.3048)
			(end 0.67945 -0.3048)
			(stroke
				(width 0.1)
				(type default)
			)
			(layer "F.Fab")
		)
		(fp_line
			(start 0.67945 -0.3048)
			(end 0.67945 0.3048)
			(stroke
				(width 0.1)
				(type default)
			)
			(layer "F.Fab")
		)
		(fp_line
			(start -0.67945 -0.305054)
			(end -0.12065 -0.305054)
			(stroke
				(width 0.1)
				(type default)
			)
			(layer "F.Fab")
		)
		(fp_line
			(start -0.12065 -0.305054)
			(end -0.12065 -0.2794)
			(stroke
				(width 0.1)
				(type default)
			)
			(layer "F.Fab")
		)
		(pad "1" smd circle
			(at -0.40005 0 270)
			(size 0 0)
			(layers "F.Cu" "F.Mask" "F.Paste")
			(net "FAN_6_PRESENT_R")
		)
		(pad "2" smd circle
			(at 0.40005 0 270)
			(size 0 0)
			(layers "F.Cu" "F.Mask" "F.Paste")
			(net "FAN_6_PRESENT")
		)
	)
	(footprint ""
		(layer "F.Cu")
		(at 14.859 -127.127)
		(property "Reference" "R5613"
			(at 0 0 0)
			(layer "F.SilkS")
			(hide yes)
			(effects
				(font
					(size 1.27 1.27)
				)
			)
		)
		(property "Value" ""
			(at 0 0 0)
			(layer "F.Fab")
			(effects
				(font
					(size 1.27 1.27)
				)
			)
		)
		(duplicate_pad_numbers_are_jumpers no)
		(fp_line
			(start -0.7874 -0.4064)
			(end 0.7874 -0.4064)
			(stroke
				(width 0.1524)
				(type default)
			)
			(layer "F.SilkS")
		)
		(fp_line
			(start -0.7874 0.4064)
			(end -0.7874 -0.4064)
			(stroke
				(width 0.1524)
				(type default)
			)
			(layer "F.SilkS")
		)
		(fp_line
			(start 0.7874 -0.4064)
			(end 0.7874 0.4064)
			(stroke
				(width 0.1524)
				(type default)
			)
			(layer "F.SilkS")
		)
		(fp_line
			(start 0.7874 0.4064)
			(end -0.7874 0.4064)
			(stroke
				(width 0.1524)
				(type default)
			)
			(layer "F.SilkS")
		)
		(fp_line
			(start -0.67945 -0.305054)
			(end -0.12065 -0.305054)
			(stroke
				(width 0.1)
				(type default)
			)
			(layer "F.Fab")
		)
		(fp_line
			(start -0.67945 0.3048)
			(end -0.67945 -0.305054)
			(stroke
				(width 0.1)
				(type default)
			)
			(layer "F.Fab")
		)
		(fp_line
			(start -0.12065 -0.305054)
			(end -0.12065 -0.2794)
			(stroke
				(width 0.1)
				(type default)
			)
			(layer "F.Fab")
		)
		(fp_line
			(start -0.12065 -0.2794)
			(end 0.12065 -0.2794)
			(stroke
				(width 0.1)
				(type default)
			)
			(layer "F.Fab")
		)
		(fp_line
			(start -0.12065 0.2794)
			(end -0.12065 0.3048)
			(stroke
				(width 0.1)
				(type default)
			)
			(layer "F.Fab")
		)
		(fp_line
			(start -0.12065 0.3048)
			(end -0.67945 0.3048)
			(stroke
				(width 0.1)
				(type default)
			)
			(layer "F.Fab")
		)
		(fp_line
			(start 0.120396 0.2794)
			(end -0.12065 0.2794)
			(stroke
				(width 0.1)
				(type default)
			)
			(layer "F.Fab")
		)
		(fp_line
			(start 0.120396 0.3048)
			(end 0.120396 0.2794)
			(stroke
				(width 0.1)
				(type default)
			)
			(layer "F.Fab")
		)
		(fp_line
			(start 0.12065 -0.3048)
			(end 0.67945 -0.3048)
			(stroke
				(width 0.1)
				(type default)
			)
			(layer "F.Fab")
		)
		(fp_line
			(start 0.12065 -0.2794)
			(end 0.12065 -0.3048)
			(stroke
				(width 0.1)
				(type default)
			)
			(layer "F.Fab")
		)
		(fp_line
			(start 0.67945 -0.3048)
			(end 0.67945 0.3048)
			(stroke
				(width 0.1)
				(type default)
			)
			(layer "F.Fab")
		)
		(fp_line
			(start 0.67945 0.3048)
			(end 0.120396 0.3048)
			(stroke
				(width 0.1)
				(type default)
			)
			(layer "F.Fab")
		)
		(pad "1" smd rect
			(at -0.40005 0 180)
			(size 0.4572 0.508)
			(layers "F.Cu" "F.Mask" "F.Paste")
			(net "FAN_5_PWM")
		)
		(pad "2" smd rect
			(at 0.40005 0 180)
			(size 0.4572 0.508)
			(layers "F.Cu" "F.Mask" "F.Paste")
			(net "FAN_5_PWM_R1")
		)
	)
	(footprint ""
		(layer "F.Cu")
		(at 38.6461 -131.318)
		(property "Reference" "R5578"
			(at 0 0 0)
			(layer "F.SilkS")
			(hide yes)
			(effects
				(font
					(size 1.27 1.27)
				)
			)
		)
		(property "Value" ""
			(at 0 0 0)
			(layer "F.Fab")
			(effects
				(font
					(size 1.27 1.27)
				)
			)
		)
		(duplicate_pad_numbers_are_jumpers no)
		(fp_line
			(start -0.7874 -0.4064)
			(end 0.7874 -0.4064)
			(stroke
				(width 0.1524)
				(type default)
			)
			(layer "F.SilkS")
		)
		(fp_line
			(start -0.7874 0.4064)
			(end -0.7874 -0.4064)
			(stroke
				(width 0.1524)
				(type default)
			)
			(layer "F.SilkS")
		)
		(fp_line
			(start 0.7874 -0.4064)
			(end 0.7874 0.4064)
			(stroke
				(width 0.1524)
				(type default)
			)
			(layer "F.SilkS")
		)
		(fp_line
			(start 0.7874 0.4064)
			(end -0.7874 0.4064)
			(stroke
				(width 0.1524)
				(type default)
			)
			(layer "F.SilkS")
		)
		(fp_line
			(start -0.67945 -0.305054)
			(end -0.12065 -0.305054)
			(stroke
				(width 0.1)
				(type default)
			)
			(layer "F.Fab")
		)
		(fp_line
			(start -0.67945 0.3048)
			(end -0.67945 -0.305054)
			(stroke
				(width 0.1)
				(type default)
			)
			(layer "F.Fab")
		)
		(fp_line
			(start -0.12065 -0.305054)
			(end -0.12065 -0.2794)
			(stroke
				(width 0.1)
				(type default)
			)
			(layer "F.Fab")
		)
		(fp_line
			(start -0.12065 -0.2794)
			(end 0.12065 -0.2794)
			(stroke
				(width 0.1)
				(type default)
			)
			(layer "F.Fab")
		)
		(fp_line
			(start -0.12065 0.2794)
			(end -0.12065 0.3048)
			(stroke
				(width 0.1)
				(type default)
			)
			(layer "F.Fab")
		)
		(fp_line
			(start -0.12065 0.3048)
			(end -0.67945 0.3048)
			(stroke
				(width 0.1)
				(type default)
			)
			(layer "F.Fab")
		)
		(fp_line
			(start 0.120396 0.2794)
			(end -0.12065 0.2794)
			(stroke
				(width 0.1)
				(type default)
			)
			(layer "F.Fab")
		)
		(fp_line
			(start 0.120396 0.3048)
			(end 0.120396 0.2794)
			(stroke
				(width 0.1)
				(type default)
			)
			(layer "F.Fab")
		)
		(fp_line
			(start 0.12065 -0.3048)
			(end 0.67945 -0.3048)
			(stroke
				(width 0.1)
				(type default)
			)
			(layer "F.Fab")
		)
		(fp_line
			(start 0.12065 -0.2794)
			(end 0.12065 -0.3048)
			(stroke
				(width 0.1)
				(type default)
			)
			(layer "F.Fab")
		)
		(fp_line
			(start 0.67945 -0.3048)
			(end 0.67945 0.3048)
			(stroke
				(width 0.1)
				(type default)
			)
			(layer "F.Fab")
		)
		(fp_line
			(start 0.67945 0.3048)
			(end 0.120396 0.3048)
			(stroke
				(width 0.1)
				(type default)
			)
			(layer "F.Fab")
		)
		(pad "1" smd rect
			(at -0.40005 0 180)
			(size 0.4572 0.508)
			(layers "F.Cu" "F.Mask" "F.Paste")
			(net "FAN_1_TACH_OL")
		)
		(pad "2" smd rect
			(at 0.40005 0 180)
			(size 0.4572 0.508)
			(layers "F.Cu" "F.Mask" "F.Paste")
			(net "FAN_1_TACH_OL_R2")
		)
	)
	(footprint ""
		(layer "F.Cu")
		(at 33.782 -166.751)
		(property "Reference" "C2010"
			(at 0 0 0)
			(layer "F.SilkS")
			(hide yes)
			(effects
				(font
					(size 1.27 1.27)
				)
			)
		)
		(property "Value" ""
			(at 0 0 0)
			(layer "F.Fab")
			(effects
				(font
					(size 1.27 1.27)
				)
			)
		)
		(duplicate_pad_numbers_are_jumpers no)
		(fp_line
			(start -0.7874 -0.4064)
			(end 0.7874 -0.4064)
			(stroke
				(width 0.1524)
				(type default)
			)
			(layer "F.SilkS")
		)
		(fp_line
			(start -0.7874 0.4064)
			(end -0.7874 -0.4064)
			(stroke
				(width 0.1524)
				(type default)
			)
			(layer "F.SilkS")
		)
		(fp_line
			(start 0.7874 -0.4064)
			(end 0.7874 0.4064)
			(stroke
				(width 0.1524)
				(type default)
			)
			(layer "F.SilkS")
		)
		(fp_line
			(start 0.7874 0.4064)
			(end -0.7874 0.4064)
			(stroke
				(width 0.1524)
				(type default)
			)
			(layer "F.SilkS")
		)
		(fp_line
			(start -0.67945 -0.305054)
			(end -0.12065 -0.305054)
			(stroke
				(width 0.1)
				(type default)
			)
			(layer "F.Fab")
		)
		(fp_line
			(start -0.67945 0.3048)
			(end -0.67945 -0.305054)
			(stroke
				(width 0.1)
				(type default)
			)
			(layer "F.Fab")
		)
		(fp_line
			(start -0.12065 -0.305054)
			(end -0.12065 -0.2794)
			(stroke
				(width 0.1)
				(type default)
			)
			(layer "F.Fab")
		)
		(fp_line
			(start -0.12065 -0.2794)
			(end 0.12065 -0.2794)
			(stroke
				(width 0.1)
				(type default)
			)
			(layer "F.Fab")
		)
		(fp_line
			(start -0.12065 0.2794)
			(end -0.12065 0.3048)
			(stroke
				(width 0.1)
				(type default)
			)
			(layer "F.Fab")
		)
		(fp_line
			(start -0.12065 0.3048)
			(end -0.67945 0.3048)
			(stroke
				(width 0.1)
				(type default)
			)
			(layer "F.Fab")
		)
		(fp_line
			(start 0.120396 0.2794)
			(end -0.12065 0.2794)
			(stroke
				(width 0.1)
				(type default)
			)
			(layer "F.Fab")
		)
		(fp_line
			(start 0.120396 0.3048)
			(end 0.120396 0.2794)
			(stroke
				(width 0.1)
				(type default)
			)
			(layer "F.Fab")
		)
		(fp_line
			(start 0.12065 -0.3048)
			(end 0.67945 -0.3048)
			(stroke
				(width 0.1)
				(type default)
			)
			(layer "F.Fab")
		)
		(fp_line
			(start 0.12065 -0.2794)
			(end 0.12065 -0.3048)
			(stroke
				(width 0.1)
				(type default)
			)
			(layer "F.Fab")
		)
		(fp_line
			(start 0.67945 -0.3048)
			(end 0.67945 0.3048)
			(stroke
				(width 0.1)
				(type default)
			)
			(layer "F.Fab")
		)
		(fp_line
			(start 0.67945 0.3048)
			(end 0.120396 0.3048)
			(stroke
				(width 0.1)
				(type default)
			)
			(layer "F.Fab")
		)
		(pad "1" smd circle
			(at -0.40005 0)
			(size 0 0)
			(layers "F.Cu" "F.Mask" "F.Paste")
			(net "P3V3_AUX")
		)
		(pad "2" smd circle
			(at 0.40005 0)
			(size 0 0)
			(layers "F.Cu" "F.Mask" "F.Paste")
			(net "GND")
		)
	)
	(footprint ""
		(layer "F.Cu")
		(at 37.82695 -137.668 180)
		(property "Reference" "R5597"
			(at 0 0 180)
			(layer "F.SilkS")
			(hide yes)
			(effects
				(font
					(size 1.27 1.27)
				)
			)
		)
		(property "Value" ""
			(at 0 0 180)
			(layer "F.Fab")
			(effects
				(font
					(size 1.27 1.27)
				)
			)
		)
		(duplicate_pad_numbers_are_jumpers no)
		(fp_line
			(start 0.7874 0.4064)
			(end -0.7874 0.4064)
			(stroke
				(width 0.1524)
				(type default)
			)
			(layer "F.SilkS")
		)
		(fp_line
			(start 0.7874 -0.4064)
			(end 0.7874 0.4064)
			(stroke
				(width 0.1524)
				(type default)
			)
			(layer "F.SilkS")
		)
		(fp_line
			(start -0.7874 0.4064)
			(end -0.7874 -0.4064)
			(stroke
				(width 0.1524)
				(type default)
			)
			(layer "F.SilkS")
		)
		(fp_line
			(start -0.7874 -0.4064)
			(end 0.7874 -0.4064)
			(stroke
				(width 0.1524)
				(type default)
			)
			(layer "F.SilkS")
		)
		(fp_line
			(start 0.67945 0.3048)
			(end 0.120396 0.3048)
			(stroke
				(width 0.1)
				(type default)
			)
			(layer "F.Fab")
		)
		(fp_line
			(start 0.67945 -0.3048)
			(end 0.67945 0.3048)
			(stroke
				(width 0.1)
				(type default)
			)
			(layer "F.Fab")
		)
		(fp_line
			(start 0.12065 -0.2794)
			(end 0.12065 -0.3048)
			(stroke
				(width 0.1)
				(type default)
			)
			(layer "F.Fab")
		)
		(fp_line
			(start 0.12065 -0.3048)
			(end 0.67945 -0.3048)
			(stroke
				(width 0.1)
				(type default)
			)
			(layer "F.Fab")
		)
		(fp_line
			(start 0.120396 0.3048)
			(end 0.120396 0.2794)
			(stroke
				(width 0.1)
				(type default)
			)
			(layer "F.Fab")
		)
		(fp_line
			(start 0.120396 0.2794)
			(end -0.12065 0.2794)
			(stroke
				(width 0.1)
				(type default)
			)
			(layer "F.Fab")
		)
		(fp_line
			(start -0.12065 0.3048)
			(end -0.67945 0.3048)
			(stroke
				(width 0.1)
				(type default)
			)
			(layer "F.Fab")
		)
		(fp_line
			(start -0.12065 0.2794)
			(end -0.12065 0.3048)
			(stroke
				(width 0.1)
				(type default)
			)
			(layer "F.Fab")
		)
		(fp_line
			(start -0.12065 -0.2794)
			(end 0.12065 -0.2794)
			(stroke
				(width 0.1)
				(type default)
			)
			(layer "F.Fab")
		)
		(fp_line
			(start -0.12065 -0.305054)
			(end -0.12065 -0.2794)
			(stroke
				(width 0.1)
				(type default)
			)
			(layer "F.Fab")
		)
		(fp_line
			(start -0.67945 0.3048)
			(end -0.67945 -0.305054)
			(stroke
				(width 0.1)
				(type default)
			)
			(layer "F.Fab")
		)
		(fp_line
			(start -0.67945 -0.305054)
			(end -0.12065 -0.305054)
			(stroke
				(width 0.1)
				(type default)
			)
			(layer "F.Fab")
		)
		(pad "1" smd rect
			(at -0.40005 0)
			(size 0.4572 0.508)
			(layers "F.Cu" "F.Mask" "F.Paste")
			(net "FAN_0_PWM")
		)
		(pad "2" smd rect
			(at 0.40005 0)
			(size 0.4572 0.508)
			(layers "F.Cu" "F.Mask" "F.Paste")
			(net "FAN_0_PWM_R1")
		)
	)
	(footprint ""
		(layer "F.Cu")
		(at 15.621 -170.815)
		(property "Reference" "C1942"
			(at 0 0 0)
			(layer "F.SilkS")
			(hide yes)
			(effects
				(font
					(size 1.27 1.27)
				)
			)
		)
		(property "Value" ""
			(at 0 0 0)
			(layer "F.Fab")
			(effects
				(font
					(size 1.27 1.27)
				)
			)
		)
		(duplicate_pad_numbers_are_jumpers no)
		(fp_line
			(start -0.7874 -0.4064)
			(end 0.7874 -0.4064)
			(stroke
				(width 0.1524)
				(type default)
			)
			(layer "F.SilkS")
		)
		(fp_line
			(start -0.7874 0.4064)
			(end -0.7874 -0.4064)
			(stroke
				(width 0.1524)
				(type default)
			)
			(layer "F.SilkS")
		)
		(fp_line
			(start 0.7874 -0.4064)
			(end 0.7874 0.4064)
			(stroke
				(width 0.1524)
				(type default)
			)
			(layer "F.SilkS")
		)
		(fp_line
			(start 0.7874 0.4064)
			(end -0.7874 0.4064)
			(stroke
				(width 0.1524)
				(type default)
			)
			(layer "F.SilkS")
		)
		(fp_line
			(start -0.67945 -0.305054)
			(end -0.12065 -0.305054)
			(stroke
				(width 0.1)
				(type default)
			)
			(layer "F.Fab")
		)
		(fp_line
			(start -0.67945 0.3048)
			(end -0.67945 -0.305054)
			(stroke
				(width 0.1)
				(type default)
			)
			(layer "F.Fab")
		)
		(fp_line
			(start -0.12065 -0.305054)
			(end -0.12065 -0.2794)
			(stroke
				(width 0.1)
				(type default)
			)
			(layer "F.Fab")
		)
		(fp_line
			(start -0.12065 -0.2794)
			(end 0.12065 -0.2794)
			(stroke
				(width 0.1)
				(type default)
			)
			(layer "F.Fab")
		)
		(fp_line
			(start -0.12065 0.2794)
			(end -0.12065 0.3048)
			(stroke
				(width 0.1)
				(type default)
			)
			(layer "F.Fab")
		)
		(fp_line
			(start -0.12065 0.3048)
			(end -0.67945 0.3048)
			(stroke
				(width 0.1)
				(type default)
			)
			(layer "F.Fab")
		)
		(fp_line
			(start 0.120396 0.2794)
			(end -0.12065 0.2794)
			(stroke
				(width 0.1)
				(type default)
			)
			(layer "F.Fab")
		)
		(fp_line
			(start 0.120396 0.3048)
			(end 0.120396 0.2794)
			(stroke
				(width 0.1)
				(type default)
			)
			(layer "F.Fab")
		)
		(fp_line
			(start 0.12065 -0.3048)
			(end 0.67945 -0.3048)
			(stroke
				(width 0.1)
				(type default)
			)
			(layer "F.Fab")
		)
		(fp_line
			(start 0.12065 -0.2794)
			(end 0.12065 -0.3048)
			(stroke
				(width 0.1)
				(type default)
			)
			(layer "F.Fab")
		)
		(fp_line
			(start 0.67945 -0.3048)
			(end 0.67945 0.3048)
			(stroke
				(width 0.1)
				(type default)
			)
			(layer "F.Fab")
		)
		(fp_line
			(start 0.67945 0.3048)
			(end 0.120396 0.3048)
			(stroke
				(width 0.1)
				(type default)
			)
			(layer "F.Fab")
		)
		(pad "1" smd circle
			(at -0.40005 0)
			(size 0 0)
			(layers "F.Cu" "F.Mask" "F.Paste")
			(net "FAN_5_PRESENT_N")
		)
		(pad "2" smd circle
			(at 0.40005 0)
			(size 0 0)
			(layers "F.Cu" "F.Mask" "F.Paste")
			(net "GND")
		)
	)
	(footprint ""
		(layer "F.Cu")
		(at 25.850088 -51.90998)
		(property "Reference" "H1"
			(at -3.9878 -4.435348 0)
			(unlocked yes)
			(layer "F.SilkS")
			(effects
				(font
					(size 0.7874 0.5842)
					(thickness 0.1524)
				)
				(justify left)
			)
		)
		(property "Value" ""
			(at 0 0 0)
			(layer "F.Fab")
			(effects
				(font
					(size 1.27 1.27)
				)
			)
		)
		(duplicate_pad_numbers_are_jumpers no)
		(pad "1" thru_hole oval
			(at 0 0)
			(size 9.017 21.0058)
			(drill 3.0226
				(offset 0 5.999988)
			)
			(layers "*.Cu" "*.Mask")
			(remove_unused_layers no)
			(net "GND")
			(clearance -1.500378)
			(padstack
				(mode front_inner_back)
				(layer "Inner"
					(shape circle)
					(size 0 0)
					(clearance 0)
				)
				(layer "B.Cu"
					(shape oval)
					(size 9.017 21.0058)
					(offset 0 5.999988)
					(clearance -1.500378)
				)
			)
		)
	)
	(footprint ""
		(layer "F.Cu")
		(at 14.859 -129.794)
		(property "Reference" "R5615"
			(at 0 0 0)
			(layer "F.SilkS")
			(hide yes)
			(effects
				(font
					(size 1.27 1.27)
				)
			)
		)
		(property "Value" ""
			(at 0 0 0)
			(layer "F.Fab")
			(effects
				(font
					(size 1.27 1.27)
				)
			)
		)
		(duplicate_pad_numbers_are_jumpers no)
		(fp_line
			(start -0.7874 -0.4064)
			(end 0.7874 -0.4064)
			(stroke
				(width 0.1524)
				(type default)
			)
			(layer "F.SilkS")
		)
		(fp_line
			(start -0.7874 0.4064)
			(end -0.7874 -0.4064)
			(stroke
				(width 0.1524)
				(type default)
			)
			(layer "F.SilkS")
		)
		(fp_line
			(start 0.7874 -0.4064)
			(end 0.7874 0.4064)
			(stroke
				(width 0.1524)
				(type default)
			)
			(layer "F.SilkS")
		)
		(fp_line
			(start 0.7874 0.4064)
			(end -0.7874 0.4064)
			(stroke
				(width 0.1524)
				(type default)
			)
			(layer "F.SilkS")
		)
		(fp_line
			(start -0.67945 -0.305054)
			(end -0.12065 -0.305054)
			(stroke
				(width 0.1)
				(type default)
			)
			(layer "F.Fab")
		)
		(fp_line
			(start -0.67945 0.3048)
			(end -0.67945 -0.305054)
			(stroke
				(width 0.1)
				(type default)
			)
			(layer "F.Fab")
		)
		(fp_line
			(start -0.12065 -0.305054)
			(end -0.12065 -0.2794)
			(stroke
				(width 0.1)
				(type default)
			)
			(layer "F.Fab")
		)
		(fp_line
			(start -0.12065 -0.2794)
			(end 0.12065 -0.2794)
			(stroke
				(width 0.1)
				(type default)
			)
			(layer "F.Fab")
		)
		(fp_line
			(start -0.12065 0.2794)
			(end -0.12065 0.3048)
			(stroke
				(width 0.1)
				(type default)
			)
			(layer "F.Fab")
		)
		(fp_line
			(start -0.12065 0.3048)
			(end -0.67945 0.3048)
			(stroke
				(width 0.1)
				(type default)
			)
			(layer "F.Fab")
		)
		(fp_line
			(start 0.120396 0.2794)
			(end -0.12065 0.2794)
			(stroke
				(width 0.1)
				(type default)
			)
			(layer "F.Fab")
		)
		(fp_line
			(start 0.120396 0.3048)
			(end 0.120396 0.2794)
			(stroke
				(width 0.1)
				(type default)
			)
			(layer "F.Fab")
		)
		(fp_line
			(start 0.12065 -0.3048)
			(end 0.67945 -0.3048)
			(stroke
				(width 0.1)
				(type default)
			)
			(layer "F.Fab")
		)
		(fp_line
			(start 0.12065 -0.2794)
			(end 0.12065 -0.3048)
			(stroke
				(width 0.1)
				(type default)
			)
			(layer "F.Fab")
		)
		(fp_line
			(start 0.67945 -0.3048)
			(end 0.67945 0.3048)
			(stroke
				(width 0.1)
				(type default)
			)
			(layer "F.Fab")
		)
		(fp_line
			(start 0.67945 0.3048)
			(end 0.120396 0.3048)
			(stroke
				(width 0.1)
				(type default)
			)
			(layer "F.Fab")
		)
		(pad "1" smd rect
			(at -0.40005 0 180)
			(size 0.4572 0.508)
			(layers "F.Cu" "F.Mask" "F.Paste")
			(net "FAN_6_PWM")
		)
		(pad "2" smd rect
			(at 0.40005 0 180)
			(size 0.4572 0.508)
			(layers "F.Cu" "F.Mask" "F.Paste")
			(net "FAN_6_PWM_R1")
		)
	)
	(footprint ""
		(layer "F.Cu")
		(at 27.305 -141.605 -90)
		(property "Reference" "R5278"
			(at 0 0 270)
			(layer "F.SilkS")
			(hide yes)
			(effects
				(font
					(size 1.27 1.27)
				)
			)
		)
		(property "Value" ""
			(at 0 0 270)
			(layer "F.Fab")
			(effects
				(font
					(size 1.27 1.27)
				)
			)
		)
		(duplicate_pad_numbers_are_jumpers no)
		(fp_line
			(start -0.7874 0.4064)
			(end -0.7874 -0.4064)
			(stroke
				(width 0.1524)
				(type default)
			)
			(layer "F.SilkS")
		)
		(fp_line
			(start 0.7874 0.4064)
			(end -0.7874 0.4064)
			(stroke
				(width 0.1524)
				(type default)
			)
			(layer "F.SilkS")
		)
		(fp_line
			(start -0.7874 -0.4064)
			(end 0.7874 -0.4064)
			(stroke
				(width 0.1524)
				(type default)
			)
			(layer "F.SilkS")
		)
		(fp_line
			(start 0.7874 -0.4064)
			(end 0.7874 0.4064)
			(stroke
				(width 0.1524)
				(type default)
			)
			(layer "F.SilkS")
		)
		(fp_line
			(start -0.67945 0.3048)
			(end -0.67945 -0.305054)
			(stroke
				(width 0.1)
				(type default)
			)
			(layer "F.Fab")
		)
		(fp_line
			(start -0.12065 0.3048)
			(end -0.67945 0.3048)
			(stroke
				(width 0.1)
				(type default)
			)
			(layer "F.Fab")
		)
		(fp_line
			(start 0.120396 0.3048)
			(end 0.120396 0.2794)
			(stroke
				(width 0.1)
				(type default)
			)
			(layer "F.Fab")
		)
		(fp_line
			(start 0.67945 0.3048)
			(end 0.120396 0.3048)
			(stroke
				(width 0.1)
				(type default)
			)
			(layer "F.Fab")
		)
		(fp_line
			(start -0.12065 0.2794)
			(end -0.12065 0.3048)
			(stroke
				(width 0.1)
				(type default)
			)
			(layer "F.Fab")
		)
		(fp_line
			(start 0.120396 0.2794)
			(end -0.12065 0.2794)
			(stroke
				(width 0.1)
				(type default)
			)
			(layer "F.Fab")
		)
		(fp_line
			(start -0.12065 -0.2794)
			(end 0.12065 -0.2794)
			(stroke
				(width 0.1)
				(type default)
			)
			(layer "F.Fab")
		)
		(fp_line
			(start 0.12065 -0.2794)
			(end 0.12065 -0.3048)
			(stroke
				(width 0.1)
				(type default)
			)
			(layer "F.Fab")
		)
		(fp_line
			(start 0.12065 -0.3048)
			(end 0.67945 -0.3048)
			(stroke
				(width 0.1)
				(type default)
			)
			(layer "F.Fab")
		)
		(fp_line
			(start 0.67945 -0.3048)
			(end 0.67945 0.3048)
			(stroke
				(width 0.1)
				(type default)
			)
			(layer "F.Fab")
		)
		(fp_line
			(start -0.67945 -0.305054)
			(end -0.12065 -0.305054)
			(stroke
				(width 0.1)
				(type default)
			)
			(layer "F.Fab")
		)
		(fp_line
			(start -0.12065 -0.305054)
			(end -0.12065 -0.2794)
			(stroke
				(width 0.1)
				(type default)
			)
			(layer "F.Fab")
		)
		(pad "1" smd circle
			(at -0.40005 0 270)
			(size 0 0)
			(layers "F.Cu" "F.Mask" "F.Paste")
			(net "SMB_FAN1_R_SCL")
		)
		(pad "2" smd circle
			(at 0.40005 0 270)
			(size 0 0)
			(layers "F.Cu" "F.Mask" "F.Paste")
			(net "P3V3_AUX")
		)
	)
	(footprint ""
		(layer "F.Cu")
		(at 43.561 -137.287 -90)
		(property "Reference" "R5563"
			(at 0 0 270)
			(layer "F.SilkS")
			(hide yes)
			(effects
				(font
					(size 1.27 1.27)
				)
			)
		)
		(property "Value" ""
			(at 0 0 270)
			(layer "F.Fab")
			(effects
				(font
					(size 1.27 1.27)
				)
			)
		)
		(duplicate_pad_numbers_are_jumpers no)
		(fp_line
			(start -0.7874 0.4064)
			(end -0.7874 -0.4064)
			(stroke
				(width 0.1524)
				(type default)
			)
			(layer "F.SilkS")
		)
		(fp_line
			(start 0.7874 0.4064)
			(end -0.7874 0.4064)
			(stroke
				(width 0.1524)
				(type default)
			)
			(layer "F.SilkS")
		)
		(fp_line
			(start -0.7874 -0.4064)
			(end 0.7874 -0.4064)
			(stroke
				(width 0.1524)
				(type default)
			)
			(layer "F.SilkS")
		)
		(fp_line
			(start 0.7874 -0.4064)
			(end 0.7874 0.4064)
			(stroke
				(width 0.1524)
				(type default)
			)
			(layer "F.SilkS")
		)
		(fp_line
			(start -0.67945 0.3048)
			(end -0.67945 -0.305054)
			(stroke
				(width 0.1)
				(type default)
			)
			(layer "F.Fab")
		)
		(fp_line
			(start -0.12065 0.3048)
			(end -0.67945 0.3048)
			(stroke
				(width 0.1)
				(type default)
			)
			(layer "F.Fab")
		)
		(fp_line
			(start 0.120396 0.3048)
			(end 0.120396 0.2794)
			(stroke
				(width 0.1)
				(type default)
			)
			(layer "F.Fab")
		)
		(fp_line
			(start 0.67945 0.3048)
			(end 0.120396 0.3048)
			(stroke
				(width 0.1)
				(type default)
			)
			(layer "F.Fab")
		)
		(fp_line
			(start -0.12065 0.2794)
			(end -0.12065 0.3048)
			(stroke
				(width 0.1)
				(type default)
			)
			(layer "F.Fab")
		)
		(fp_line
			(start 0.120396 0.2794)
			(end -0.12065 0.2794)
			(stroke
				(width 0.1)
				(type default)
			)
			(layer "F.Fab")
		)
		(fp_line
			(start -0.12065 -0.2794)
			(end 0.12065 -0.2794)
			(stroke
				(width 0.1)
				(type default)
			)
			(layer "F.Fab")
		)
		(fp_line
			(start 0.12065 -0.2794)
			(end 0.12065 -0.3048)
			(stroke
				(width 0.1)
				(type default)
			)
			(layer "F.Fab")
		)
		(fp_line
			(start 0.12065 -0.3048)
			(end 0.67945 -0.3048)
			(stroke
				(width 0.1)
				(type default)
			)
			(layer "F.Fab")
		)
		(fp_line
			(start 0.67945 -0.3048)
			(end 0.67945 0.3048)
			(stroke
				(width 0.1)
				(type default)
			)
			(layer "F.Fab")
		)
		(fp_line
			(start -0.67945 -0.305054)
			(end -0.12065 -0.305054)
			(stroke
				(width 0.1)
				(type default)
			)
			(layer "F.Fab")
		)
		(fp_line
			(start -0.12065 -0.305054)
			(end -0.12065 -0.2794)
			(stroke
				(width 0.1)
				(type default)
			)
			(layer "F.Fab")
		)
		(pad "1" smd circle
			(at -0.40005 0 270)
			(size 0 0)
			(layers "F.Cu" "F.Mask" "F.Paste")
			(net "GND")
		)
		(pad "2" smd circle
			(at 0.40005 0 270)
			(size 0 0)
			(layers "F.Cu" "F.Mask" "F.Paste")
			(net "U403_ADD1")
		)
	)
	(footprint ""
		(layer "F.Cu")
		(at 23.114 -160.02 90)
		(property "Reference" "R4884"
			(at 0 0 90)
			(layer "F.SilkS")
			(hide yes)
			(effects
				(font
					(size 1.27 1.27)
				)
			)
		)
		(property "Value" ""
			(at 0 0 90)
			(layer "F.Fab")
			(effects
				(font
					(size 1.27 1.27)
				)
			)
		)
		(duplicate_pad_numbers_are_jumpers no)
		(fp_line
			(start 0.7874 -0.4064)
			(end 0.7874 0.4064)
			(stroke
				(width 0.1524)
				(type default)
			)
			(layer "F.SilkS")
		)
		(fp_line
			(start -0.7874 -0.4064)
			(end 0.7874 -0.4064)
			(stroke
				(width 0.1524)
				(type default)
			)
			(layer "F.SilkS")
		)
		(fp_line
			(start 0.7874 0.4064)
			(end -0.7874 0.4064)
			(stroke
				(width 0.1524)
				(type default)
			)
			(layer "F.SilkS")
		)
		(fp_line
			(start -0.7874 0.4064)
			(end -0.7874 -0.4064)
			(stroke
				(width 0.1524)
				(type default)
			)
			(layer "F.SilkS")
		)
		(fp_line
			(start -0.12065 -0.305054)
			(end -0.12065 -0.2794)
			(stroke
				(width 0.1)
				(type default)
			)
			(layer "F.Fab")
		)
		(fp_line
			(start -0.67945 -0.305054)
			(end -0.12065 -0.305054)
			(stroke
				(width 0.1)
				(type default)
			)
			(layer "F.Fab")
		)
		(fp_line
			(start 0.67945 -0.3048)
			(end 0.67945 0.3048)
			(stroke
				(width 0.1)
				(type default)
			)
			(layer "F.Fab")
		)
		(fp_line
			(start 0.12065 -0.3048)
			(end 0.67945 -0.3048)
			(stroke
				(width 0.1)
				(type default)
			)
			(layer "F.Fab")
		)
		(fp_line
			(start 0.12065 -0.2794)
			(end 0.12065 -0.3048)
			(stroke
				(width 0.1)
				(type default)
			)
			(layer "F.Fab")
		)
		(fp_line
			(start -0.12065 -0.2794)
			(end 0.12065 -0.2794)
			(stroke
				(width 0.1)
				(type default)
			)
			(layer "F.Fab")
		)
		(fp_line
			(start 0.120396 0.2794)
			(end -0.12065 0.2794)
			(stroke
				(width 0.1)
				(type default)
			)
			(layer "F.Fab")
		)
		(fp_line
			(start -0.12065 0.2794)
			(end -0.12065 0.3048)
			(stroke
				(width 0.1)
				(type default)
			)
			(layer "F.Fab")
		)
		(fp_line
			(start 0.67945 0.3048)
			(end 0.120396 0.3048)
			(stroke
				(width 0.1)
				(type default)
			)
			(layer "F.Fab")
		)
		(fp_line
			(start 0.120396 0.3048)
			(end 0.120396 0.2794)
			(stroke
				(width 0.1)
				(type default)
			)
			(layer "F.Fab")
		)
		(fp_line
			(start -0.12065 0.3048)
			(end -0.67945 0.3048)
			(stroke
				(width 0.1)
				(type default)
			)
			(layer "F.Fab")
		)
		(fp_line
			(start -0.67945 0.3048)
			(end -0.67945 -0.305054)
			(stroke
				(width 0.1)
				(type default)
			)
			(layer "F.Fab")
		)
		(pad "1" smd circle
			(at -0.40005 0 90)
			(size 0 0)
			(layers "F.Cu" "F.Mask" "F.Paste")
			(net "SMB_FAN7_R_SDA")
		)
		(pad "2" smd circle
			(at 0.40005 0 90)
			(size 0 0)
			(layers "F.Cu" "F.Mask" "F.Paste")
			(net "SMB_FAN7_SDA")
		)
	)
	(footprint ""
		(layer "F.Cu")
		(at 43.561 -169.799)
		(property "Reference" "R5094"
			(at 0 0 0)
			(layer "F.SilkS")
			(hide yes)
			(effects
				(font
					(size 1.27 1.27)
				)
			)
		)
		(property "Value" ""
			(at 0 0 0)
			(layer "F.Fab")
			(effects
				(font
					(size 1.27 1.27)
				)
			)
		)
		(duplicate_pad_numbers_are_jumpers no)
		(fp_line
			(start -0.7874 -0.4064)
			(end 0.7874 -0.4064)
			(stroke
				(width 0.1524)
				(type default)
			)
			(layer "F.SilkS")
		)
		(fp_line
			(start -0.7874 0.4064)
			(end -0.7874 -0.4064)
			(stroke
				(width 0.1524)
				(type default)
			)
			(layer "F.SilkS")
		)
		(fp_line
			(start 0.7874 -0.4064)
			(end 0.7874 0.4064)
			(stroke
				(width 0.1524)
				(type default)
			)
			(layer "F.SilkS")
		)
		(fp_line
			(start 0.7874 0.4064)
			(end -0.7874 0.4064)
			(stroke
				(width 0.1524)
				(type default)
			)
			(layer "F.SilkS")
		)
		(fp_line
			(start -0.67945 -0.305054)
			(end -0.12065 -0.305054)
			(stroke
				(width 0.1)
				(type default)
			)
			(layer "F.Fab")
		)
		(fp_line
			(start -0.67945 0.3048)
			(end -0.67945 -0.305054)
			(stroke
				(width 0.1)
				(type default)
			)
			(layer "F.Fab")
		)
		(fp_line
			(start -0.12065 -0.305054)
			(end -0.12065 -0.2794)
			(stroke
				(width 0.1)
				(type default)
			)
			(layer "F.Fab")
		)
		(fp_line
			(start -0.12065 -0.2794)
			(end 0.12065 -0.2794)
			(stroke
				(width 0.1)
				(type default)
			)
			(layer "F.Fab")
		)
		(fp_line
			(start -0.12065 0.2794)
			(end -0.12065 0.3048)
			(stroke
				(width 0.1)
				(type default)
			)
			(layer "F.Fab")
		)
		(fp_line
			(start -0.12065 0.3048)
			(end -0.67945 0.3048)
			(stroke
				(width 0.1)
				(type default)
			)
			(layer "F.Fab")
		)
		(fp_line
			(start 0.120396 0.2794)
			(end -0.12065 0.2794)
			(stroke
				(width 0.1)
				(type default)
			)
			(layer "F.Fab")
		)
		(fp_line
			(start 0.120396 0.3048)
			(end 0.120396 0.2794)
			(stroke
				(width 0.1)
				(type default)
			)
			(layer "F.Fab")
		)
		(fp_line
			(start 0.12065 -0.3048)
			(end 0.67945 -0.3048)
			(stroke
				(width 0.1)
				(type default)
			)
			(layer "F.Fab")
		)
		(fp_line
			(start 0.12065 -0.2794)
			(end 0.12065 -0.3048)
			(stroke
				(width 0.1)
				(type default)
			)
			(layer "F.Fab")
		)
		(fp_line
			(start 0.67945 -0.3048)
			(end 0.67945 0.3048)
			(stroke
				(width 0.1)
				(type default)
			)
			(layer "F.Fab")
		)
		(fp_line
			(start 0.67945 0.3048)
			(end 0.120396 0.3048)
			(stroke
				(width 0.1)
				(type default)
			)
			(layer "F.Fab")
		)
		(pad "1" smd circle
			(at -0.40005 0)
			(size 0 0)
			(layers "F.Cu" "F.Mask" "F.Paste")
			(net "FAN_0_OK_LED")
		)
		(pad "2" smd circle
			(at 0.40005 0)
			(size 0 0)
			(layers "F.Cu" "F.Mask" "F.Paste")
			(net "FAN_0_OK_R_LED")
		)
	)
	(footprint ""
		(layer "F.Cu")
		(at 41.441116 -39.403274)
		(property "Reference" "PC35"
			(at 2.373884 6.028944 0)
			(unlocked yes)
			(layer "F.SilkS")
			(effects
				(font
					(size 0.7874 0.5842)
					(thickness 0.1524)
				)
				(justify left)
			)
		)
		(property "Value" ""
			(at 0 0 0)
			(layer "F.Fab")
			(effects
				(font
					(size 1.27 1.27)
				)
			)
		)
		(duplicate_pad_numbers_are_jumpers no)
		(fp_line
			(start -5.249926 -3.979926)
			(end -5.249926 -1.2446)
			(stroke
				(width 0.1524)
				(type default)
			)
			(layer "F.SilkS")
		)
		(fp_line
			(start -5.249926 1.2446)
			(end -5.249926 3.979926)
			(stroke
				(width 0.1524)
				(type default)
			)
			(layer "F.SilkS")
		)
		(fp_line
			(start -5.249926 3.979926)
			(end -3.979926 5.249926)
			(stroke
				(width 0.1524)
				(type default)
			)
			(layer "F.SilkS")
		)
		(fp_line
			(start -3.979926 -5.249926)
			(end -5.249926 -3.979926)
			(stroke
				(width 0.1524)
				(type default)
			)
			(layer "F.SilkS")
		)
		(fp_line
			(start -3.979926 5.249926)
			(end 5.249926 5.249926)
			(stroke
				(width 0.1524)
				(type default)
			)
			(layer "F.SilkS")
		)
		(fp_line
			(start 5.249926 -5.249926)
			(end -3.979926 -5.249926)
			(stroke
				(width 0.1524)
				(type default)
			)
			(layer "F.SilkS")
		)
		(fp_line
			(start 5.249926 -1.2446)
			(end 5.249926 -5.249926)
			(stroke
				(width 0.1524)
				(type default)
			)
			(layer "F.SilkS")
		)
		(fp_line
			(start 5.249926 5.249926)
			(end 5.249926 1.2446)
			(stroke
				(width 0.1524)
				(type default)
			)
			(layer "F.SilkS")
		)
		(fp_line
			(start -5.249926 -5.249926)
			(end -5.249926 5.249926)
			(stroke
				(width 0.1)
				(type default)
			)
			(layer "F.Fab")
		)
		(fp_line
			(start -5.249926 5.249926)
			(end 5.249926 5.249926)
			(stroke
				(width 0.1)
				(type default)
			)
			(layer "F.Fab")
		)
		(fp_line
			(start 5.249926 -5.249926)
			(end -5.249926 -5.249926)
			(stroke
				(width 0.1)
				(type default)
			)
			(layer "F.Fab")
		)
		(fp_line
			(start 5.249926 5.249926)
			(end 5.249926 -5.249926)
			(stroke
				(width 0.1)
				(type default)
			)
			(layer "F.Fab")
		)
		(pad "1" smd rect
			(at -4.45008 0 90)
			(size 2.2098 4.4196)
			(layers "F.Cu" "F.Mask" "F.Paste")
			(net "P52V_FAN_3")
		)
		(pad "2" smd rect
			(at 4.45008 0 90)
			(size 2.2098 4.4196)
			(layers "F.Cu" "F.Mask" "F.Paste")
			(net "GND")
		)
	)
	(footprint ""
		(layer "F.Cu")
		(at 29.083 -21.209)
		(property "Reference" "R5519"
			(at 0 0 0)
			(layer "F.SilkS")
			(hide yes)
			(effects
				(font
					(size 1.27 1.27)
				)
			)
		)
		(property "Value" ""
			(at 0 0 0)
			(layer "F.Fab")
			(effects
				(font
					(size 1.27 1.27)
				)
			)
		)
		(duplicate_pad_numbers_are_jumpers no)
		(fp_line
			(start -0.7874 -0.4064)
			(end 0.7874 -0.4064)
			(stroke
				(width 0.1524)
				(type default)
			)
			(layer "F.SilkS")
		)
		(fp_line
			(start -0.7874 0.4064)
			(end -0.7874 -0.4064)
			(stroke
				(width 0.1524)
				(type default)
			)
			(layer "F.SilkS")
		)
		(fp_line
			(start 0.7874 -0.4064)
			(end 0.7874 0.4064)
			(stroke
				(width 0.1524)
				(type default)
			)
			(layer "F.SilkS")
		)
		(fp_line
			(start 0.7874 0.4064)
			(end -0.7874 0.4064)
			(stroke
				(width 0.1524)
				(type default)
			)
			(layer "F.SilkS")
		)
		(fp_line
			(start -0.67945 -0.305054)
			(end -0.12065 -0.305054)
			(stroke
				(width 0.1)
				(type default)
			)
			(layer "F.Fab")
		)
		(fp_line
			(start -0.67945 0.3048)
			(end -0.67945 -0.305054)
			(stroke
				(width 0.1)
				(type default)
			)
			(layer "F.Fab")
		)
		(fp_line
			(start -0.12065 -0.305054)
			(end -0.12065 -0.2794)
			(stroke
				(width 0.1)
				(type default)
			)
			(layer "F.Fab")
		)
		(fp_line
			(start -0.12065 -0.2794)
			(end 0.12065 -0.2794)
			(stroke
				(width 0.1)
				(type default)
			)
			(layer "F.Fab")
		)
		(fp_line
			(start -0.12065 0.2794)
			(end -0.12065 0.3048)
			(stroke
				(width 0.1)
				(type default)
			)
			(layer "F.Fab")
		)
		(fp_line
			(start -0.12065 0.3048)
			(end -0.67945 0.3048)
			(stroke
				(width 0.1)
				(type default)
			)
			(layer "F.Fab")
		)
		(fp_line
			(start 0.120396 0.2794)
			(end -0.12065 0.2794)
			(stroke
				(width 0.1)
				(type default)
			)
			(layer "F.Fab")
		)
		(fp_line
			(start 0.120396 0.3048)
			(end 0.120396 0.2794)
			(stroke
				(width 0.1)
				(type default)
			)
			(layer "F.Fab")
		)
		(fp_line
			(start 0.12065 -0.3048)
			(end 0.67945 -0.3048)
			(stroke
				(width 0.1)
				(type default)
			)
			(layer "F.Fab")
		)
		(fp_line
			(start 0.12065 -0.2794)
			(end 0.12065 -0.3048)
			(stroke
				(width 0.1)
				(type default)
			)
			(layer "F.Fab")
		)
		(fp_line
			(start 0.67945 -0.3048)
			(end 0.67945 0.3048)
			(stroke
				(width 0.1)
				(type default)
			)
			(layer "F.Fab")
		)
		(fp_line
			(start 0.67945 0.3048)
			(end 0.120396 0.3048)
			(stroke
				(width 0.1)
				(type default)
			)
			(layer "F.Fab")
		)
		(pad "1" smd circle
			(at -0.40005 0)
			(size 0 0)
			(layers "F.Cu" "F.Mask" "F.Paste")
			(net "P3V3_AUX")
		)
		(pad "2" smd circle
			(at 0.40005 0)
			(size 0 0)
			(layers "F.Cu" "F.Mask" "F.Paste")
			(net "FAN_4_PWM")
		)
	)
	(footprint ""
		(layer "F.Cu")
		(at 40.767 -73.152 180)
		(property "Reference" "PR35"
			(at 0 0 180)
			(layer "F.SilkS")
			(hide yes)
			(effects
				(font
					(size 1.27 1.27)
				)
			)
		)
		(property "Value" ""
			(at 0 0 180)
			(layer "F.Fab")
			(effects
				(font
					(size 1.27 1.27)
				)
			)
		)
		(duplicate_pad_numbers_are_jumpers no)
		(fp_line
			(start 0.7874 0.4064)
			(end -0.7874 0.4064)
			(stroke
				(width 0.1524)
				(type default)
			)
			(layer "F.SilkS")
		)
		(fp_line
			(start 0.7874 -0.4064)
			(end 0.7874 0.4064)
			(stroke
				(width 0.1524)
				(type default)
			)
			(layer "F.SilkS")
		)
		(fp_line
			(start -0.7874 0.4064)
			(end -0.7874 -0.4064)
			(stroke
				(width 0.1524)
				(type default)
			)
			(layer "F.SilkS")
		)
		(fp_line
			(start -0.7874 -0.4064)
			(end 0.7874 -0.4064)
			(stroke
				(width 0.1524)
				(type default)
			)
			(layer "F.SilkS")
		)
		(fp_line
			(start 0.67945 0.3048)
			(end 0.120396 0.3048)
			(stroke
				(width 0.1)
				(type default)
			)
			(layer "F.Fab")
		)
		(fp_line
			(start 0.67945 -0.3048)
			(end 0.67945 0.3048)
			(stroke
				(width 0.1)
				(type default)
			)
			(layer "F.Fab")
		)
		(fp_line
			(start 0.12065 -0.2794)
			(end 0.12065 -0.3048)
			(stroke
				(width 0.1)
				(type default)
			)
			(layer "F.Fab")
		)
		(fp_line
			(start 0.12065 -0.3048)
			(end 0.67945 -0.3048)
			(stroke
				(width 0.1)
				(type default)
			)
			(layer "F.Fab")
		)
		(fp_line
			(start 0.120396 0.3048)
			(end 0.120396 0.2794)
			(stroke
				(width 0.1)
				(type default)
			)
			(layer "F.Fab")
		)
		(fp_line
			(start 0.120396 0.2794)
			(end -0.12065 0.2794)
			(stroke
				(width 0.1)
				(type default)
			)
			(layer "F.Fab")
		)
		(fp_line
			(start -0.12065 0.3048)
			(end -0.67945 0.3048)
			(stroke
				(width 0.1)
				(type default)
			)
			(layer "F.Fab")
		)
		(fp_line
			(start -0.12065 0.2794)
			(end -0.12065 0.3048)
			(stroke
				(width 0.1)
				(type default)
			)
			(layer "F.Fab")
		)
		(fp_line
			(start -0.12065 -0.2794)
			(end 0.12065 -0.2794)
			(stroke
				(width 0.1)
				(type default)
			)
			(layer "F.Fab")
		)
		(fp_line
			(start -0.12065 -0.305054)
			(end -0.12065 -0.2794)
			(stroke
				(width 0.1)
				(type default)
			)
			(layer "F.Fab")
		)
		(fp_line
			(start -0.67945 0.3048)
			(end -0.67945 -0.305054)
			(stroke
				(width 0.1)
				(type default)
			)
			(layer "F.Fab")
		)
		(fp_line
			(start -0.67945 -0.305054)
			(end -0.12065 -0.305054)
			(stroke
				(width 0.1)
				(type default)
			)
			(layer "F.Fab")
		)
		(pad "1" smd circle
			(at -0.40005 0 180)
			(size 0 0)
			(layers "F.Cu" "F.Mask" "F.Paste")
			(net "FAN_2_FAULT_R")
		)
		(pad "2" smd circle
			(at 0.40005 0 180)
			(size 0 0)
			(layers "F.Cu" "F.Mask" "F.Paste")
			(net "FAN_2_P3V_R")
		)
	)
	(footprint ""
		(layer "F.Cu")
		(at 38.62705 -123.698)
		(property "Reference" "R5584"
			(at 0 0 0)
			(layer "F.SilkS")
			(hide yes)
			(effects
				(font
					(size 1.27 1.27)
				)
			)
		)
		(property "Value" ""
			(at 0 0 0)
			(layer "F.Fab")
			(effects
				(font
					(size 1.27 1.27)
				)
			)
		)
		(duplicate_pad_numbers_are_jumpers no)
		(fp_line
			(start -0.7874 -0.4064)
			(end 0.7874 -0.4064)
			(stroke
				(width 0.1524)
				(type default)
			)
			(layer "F.SilkS")
		)
		(fp_line
			(start -0.7874 0.4064)
			(end -0.7874 -0.4064)
			(stroke
				(width 0.1524)
				(type default)
			)
			(layer "F.SilkS")
		)
		(fp_line
			(start 0.7874 -0.4064)
			(end 0.7874 0.4064)
			(stroke
				(width 0.1524)
				(type default)
			)
			(layer "F.SilkS")
		)
		(fp_line
			(start 0.7874 0.4064)
			(end -0.7874 0.4064)
			(stroke
				(width 0.1524)
				(type default)
			)
			(layer "F.SilkS")
		)
		(fp_line
			(start -0.67945 -0.305054)
			(end -0.12065 -0.305054)
			(stroke
				(width 0.1)
				(type default)
			)
			(layer "F.Fab")
		)
		(fp_line
			(start -0.67945 0.3048)
			(end -0.67945 -0.305054)
			(stroke
				(width 0.1)
				(type default)
			)
			(layer "F.Fab")
		)
		(fp_line
			(start -0.12065 -0.305054)
			(end -0.12065 -0.2794)
			(stroke
				(width 0.1)
				(type default)
			)
			(layer "F.Fab")
		)
		(fp_line
			(start -0.12065 -0.2794)
			(end 0.12065 -0.2794)
			(stroke
				(width 0.1)
				(type default)
			)
			(layer "F.Fab")
		)
		(fp_line
			(start -0.12065 0.2794)
			(end -0.12065 0.3048)
			(stroke
				(width 0.1)
				(type default)
			)
			(layer "F.Fab")
		)
		(fp_line
			(start -0.12065 0.3048)
			(end -0.67945 0.3048)
			(stroke
				(width 0.1)
				(type default)
			)
			(layer "F.Fab")
		)
		(fp_line
			(start 0.120396 0.2794)
			(end -0.12065 0.2794)
			(stroke
				(width 0.1)
				(type default)
			)
			(layer "F.Fab")
		)
		(fp_line
			(start 0.120396 0.3048)
			(end 0.120396 0.2794)
			(stroke
				(width 0.1)
				(type default)
			)
			(layer "F.Fab")
		)
		(fp_line
			(start 0.12065 -0.3048)
			(end 0.67945 -0.3048)
			(stroke
				(width 0.1)
				(type default)
			)
			(layer "F.Fab")
		)
		(fp_line
			(start 0.12065 -0.2794)
			(end 0.12065 -0.3048)
			(stroke
				(width 0.1)
				(type default)
			)
			(layer "F.Fab")
		)
		(fp_line
			(start 0.67945 -0.3048)
			(end 0.67945 0.3048)
			(stroke
				(width 0.1)
				(type default)
			)
			(layer "F.Fab")
		)
		(fp_line
			(start 0.67945 0.3048)
			(end 0.120396 0.3048)
			(stroke
				(width 0.1)
				(type default)
			)
			(layer "F.Fab")
		)
		(pad "1" smd rect
			(at -0.40005 0 180)
			(size 0.4572 0.508)
			(layers "F.Cu" "F.Mask" "F.Paste")
			(net "FAN_3_TACH_OL")
		)
		(pad "2" smd rect
			(at 0.40005 0 180)
			(size 0.4572 0.508)
			(layers "F.Cu" "F.Mask" "F.Paste")
			(net "FAN_3_TACH_OL_R2")
		)
	)
	(footprint ""
		(layer "F.Cu")
		(at 32.258 -22.098 90)
		(property "Reference" "R5397"
			(at 0 0 90)
			(layer "F.SilkS")
			(hide yes)
			(effects
				(font
					(size 1.27 1.27)
				)
			)
		)
		(property "Value" ""
			(at 0 0 90)
			(layer "F.Fab")
			(effects
				(font
					(size 1.27 1.27)
				)
			)
		)
		(duplicate_pad_numbers_are_jumpers no)
		(fp_line
			(start 0.7874 -0.4064)
			(end 0.7874 0.4064)
			(stroke
				(width 0.1524)
				(type default)
			)
			(layer "F.SilkS")
		)
		(fp_line
			(start -0.7874 -0.4064)
			(end 0.7874 -0.4064)
			(stroke
				(width 0.1524)
				(type default)
			)
			(layer "F.SilkS")
		)
		(fp_line
			(start 0.7874 0.4064)
			(end -0.7874 0.4064)
			(stroke
				(width 0.1524)
				(type default)
			)
			(layer "F.SilkS")
		)
		(fp_line
			(start -0.7874 0.4064)
			(end -0.7874 -0.4064)
			(stroke
				(width 0.1524)
				(type default)
			)
			(layer "F.SilkS")
		)
		(fp_line
			(start -0.12065 -0.305054)
			(end -0.12065 -0.2794)
			(stroke
				(width 0.1)
				(type default)
			)
			(layer "F.Fab")
		)
		(fp_line
			(start -0.67945 -0.305054)
			(end -0.12065 -0.305054)
			(stroke
				(width 0.1)
				(type default)
			)
			(layer "F.Fab")
		)
		(fp_line
			(start 0.67945 -0.3048)
			(end 0.67945 0.3048)
			(stroke
				(width 0.1)
				(type default)
			)
			(layer "F.Fab")
		)
		(fp_line
			(start 0.12065 -0.3048)
			(end 0.67945 -0.3048)
			(stroke
				(width 0.1)
				(type default)
			)
			(layer "F.Fab")
		)
		(fp_line
			(start 0.12065 -0.2794)
			(end 0.12065 -0.3048)
			(stroke
				(width 0.1)
				(type default)
			)
			(layer "F.Fab")
		)
		(fp_line
			(start -0.12065 -0.2794)
			(end 0.12065 -0.2794)
			(stroke
				(width 0.1)
				(type default)
			)
			(layer "F.Fab")
		)
		(fp_line
			(start 0.120396 0.2794)
			(end -0.12065 0.2794)
			(stroke
				(width 0.1)
				(type default)
			)
			(layer "F.Fab")
		)
		(fp_line
			(start -0.12065 0.2794)
			(end -0.12065 0.3048)
			(stroke
				(width 0.1)
				(type default)
			)
			(layer "F.Fab")
		)
		(fp_line
			(start 0.67945 0.3048)
			(end 0.120396 0.3048)
			(stroke
				(width 0.1)
				(type default)
			)
			(layer "F.Fab")
		)
		(fp_line
			(start 0.120396 0.3048)
			(end 0.120396 0.2794)
			(stroke
				(width 0.1)
				(type default)
			)
			(layer "F.Fab")
		)
		(fp_line
			(start -0.12065 0.3048)
			(end -0.67945 0.3048)
			(stroke
				(width 0.1)
				(type default)
			)
			(layer "F.Fab")
		)
		(fp_line
			(start -0.67945 0.3048)
			(end -0.67945 -0.305054)
			(stroke
				(width 0.1)
				(type default)
			)
			(layer "F.Fab")
		)
		(pad "1" smd circle
			(at -0.40005 0 90)
			(size 0 0)
			(layers "F.Cu" "F.Mask" "F.Paste")
			(net "P3V3_AUX")
		)
		(pad "2" smd circle
			(at 0.40005 0 90)
			(size 0 0)
			(layers "F.Cu" "F.Mask" "F.Paste")
			(net "FAN_3_FAIL_R_LED")
		)
	)
	(footprint ""
		(layer "F.Cu")
		(at 18.288 -118.364 90)
		(property "Reference" "R5313"
			(at 0 0 90)
			(layer "F.SilkS")
			(hide yes)
			(effects
				(font
					(size 1.27 1.27)
				)
			)
		)
		(property "Value" ""
			(at 0 0 90)
			(layer "F.Fab")
			(effects
				(font
					(size 1.27 1.27)
				)
			)
		)
		(duplicate_pad_numbers_are_jumpers no)
		(fp_line
			(start 1.2954 -0.5842)
			(end 1.2954 0.5842)
			(stroke
				(width 0.1524)
				(type default)
			)
			(layer "F.SilkS")
		)
		(fp_line
			(start -1.2954 -0.5842)
			(end 1.2954 -0.5842)
			(stroke
				(width 0.1524)
				(type default)
			)
			(layer "F.SilkS")
		)
		(fp_line
			(start 1.2954 0.5842)
			(end -1.2954 0.5842)
			(stroke
				(width 0.1524)
				(type default)
			)
			(layer "F.SilkS")
		)
		(fp_line
			(start -1.2954 0.5842)
			(end -1.2954 -0.5842)
			(stroke
				(width 0.1524)
				(type default)
			)
			(layer "F.SilkS")
		)
		(fp_line
			(start 0.8636 -0.4572)
			(end 0.8636 -0.406654)
			(stroke
				(width 0.1)
				(type default)
			)
			(layer "F.Fab")
		)
		(fp_line
			(start -0.8636 -0.4572)
			(end 0.8636 -0.4572)
			(stroke
				(width 0.1)
				(type default)
			)
			(layer "F.Fab")
		)
		(fp_line
			(start 1.1938 -0.406654)
			(end 1.1938 0.4064)
			(stroke
				(width 0.1)
				(type default)
			)
			(layer "F.Fab")
		)
		(fp_line
			(start 0.8636 -0.406654)
			(end 1.1938 -0.406654)
			(stroke
				(width 0.1)
				(type default)
			)
			(layer "F.Fab")
		)
		(fp_line
			(start -0.8636 -0.406654)
			(end -0.8636 -0.4572)
			(stroke
				(width 0.1)
				(type default)
			)
			(layer "F.Fab")
		)
		(fp_line
			(start -1.1938 -0.406654)
			(end -0.8636 -0.406654)
			(stroke
				(width 0.1)
				(type default)
			)
			(layer "F.Fab")
		)
		(fp_line
			(start 1.1938 0.4064)
			(end 0.8636 0.4064)
			(stroke
				(width 0.1)
				(type default)
			)
			(layer "F.Fab")
		)
		(fp_line
			(start 0.8636 0.4064)
			(end 0.8636 0.4572)
			(stroke
				(width 0.1)
				(type default)
			)
			(layer "F.Fab")
		)
		(fp_line
			(start -0.8636 0.4064)
			(end -1.1938 0.4064)
			(stroke
				(width 0.1)
				(type default)
			)
			(layer "F.Fab")
		)
		(fp_line
			(start -1.1938 0.4064)
			(end -1.1938 -0.406654)
			(stroke
				(width 0.1)
				(type default)
			)
			(layer "F.Fab")
		)
		(fp_line
			(start -0.8636 0.4318)
			(end -0.8636 0.4064)
			(stroke
				(width 0.1)
				(type default)
			)
			(layer "F.Fab")
		)
		(fp_line
			(start 0.8636 0.4572)
			(end -0.8636 0.4572)
			(stroke
				(width 0.1)
				(type default)
			)
			(layer "F.Fab")
		)
		(fp_line
			(start -0.8636 0.4572)
			(end -0.8636 0.4318)
			(stroke
				(width 0.1)
				(type default)
			)
			(layer "F.Fab")
		)
		(pad "1" smd rect
			(at -0.7366 0)
			(size 0.7112 0.8128)
			(layers "F.Cu" "F.Mask" "F.Paste")
			(net "P52V_FAN_5")
		)
		(pad "2" smd rect
			(at 0.7366 0)
			(size 0.7112 0.8128)
			(layers "F.Cu" "F.Mask" "F.Paste")
			(net "FAN_5_TACH_OL_R")
		)
	)
	(footprint ""
		(layer "F.Cu")
		(at 12.954 -73.406 180)
		(property "Reference" "PR55"
			(at 0 0 180)
			(layer "F.SilkS")
			(hide yes)
			(effects
				(font
					(size 1.27 1.27)
				)
			)
		)
		(property "Value" ""
			(at 0 0 180)
			(layer "F.Fab")
			(effects
				(font
					(size 1.27 1.27)
				)
			)
		)
		(duplicate_pad_numbers_are_jumpers no)
		(fp_line
			(start 0.7874 0.4064)
			(end -0.7874 0.4064)
			(stroke
				(width 0.1524)
				(type default)
			)
			(layer "F.SilkS")
		)
		(fp_line
			(start 0.7874 -0.4064)
			(end 0.7874 0.4064)
			(stroke
				(width 0.1524)
				(type default)
			)
			(layer "F.SilkS")
		)
		(fp_line
			(start -0.7874 0.4064)
			(end -0.7874 -0.4064)
			(stroke
				(width 0.1524)
				(type default)
			)
			(layer "F.SilkS")
		)
		(fp_line
			(start -0.7874 -0.4064)
			(end 0.7874 -0.4064)
			(stroke
				(width 0.1524)
				(type default)
			)
			(layer "F.SilkS")
		)
		(fp_line
			(start 0.67945 0.3048)
			(end 0.120396 0.3048)
			(stroke
				(width 0.1)
				(type default)
			)
			(layer "F.Fab")
		)
		(fp_line
			(start 0.67945 -0.3048)
			(end 0.67945 0.3048)
			(stroke
				(width 0.1)
				(type default)
			)
			(layer "F.Fab")
		)
		(fp_line
			(start 0.12065 -0.2794)
			(end 0.12065 -0.3048)
			(stroke
				(width 0.1)
				(type default)
			)
			(layer "F.Fab")
		)
		(fp_line
			(start 0.12065 -0.3048)
			(end 0.67945 -0.3048)
			(stroke
				(width 0.1)
				(type default)
			)
			(layer "F.Fab")
		)
		(fp_line
			(start 0.120396 0.3048)
			(end 0.120396 0.2794)
			(stroke
				(width 0.1)
				(type default)
			)
			(layer "F.Fab")
		)
		(fp_line
			(start 0.120396 0.2794)
			(end -0.12065 0.2794)
			(stroke
				(width 0.1)
				(type default)
			)
			(layer "F.Fab")
		)
		(fp_line
			(start -0.12065 0.3048)
			(end -0.67945 0.3048)
			(stroke
				(width 0.1)
				(type default)
			)
			(layer "F.Fab")
		)
		(fp_line
			(start -0.12065 0.2794)
			(end -0.12065 0.3048)
			(stroke
				(width 0.1)
				(type default)
			)
			(layer "F.Fab")
		)
		(fp_line
			(start -0.12065 -0.2794)
			(end 0.12065 -0.2794)
			(stroke
				(width 0.1)
				(type default)
			)
			(layer "F.Fab")
		)
		(fp_line
			(start -0.12065 -0.305054)
			(end -0.12065 -0.2794)
			(stroke
				(width 0.1)
				(type default)
			)
			(layer "F.Fab")
		)
		(fp_line
			(start -0.67945 0.3048)
			(end -0.67945 -0.305054)
			(stroke
				(width 0.1)
				(type default)
			)
			(layer "F.Fab")
		)
		(fp_line
			(start -0.67945 -0.305054)
			(end -0.12065 -0.305054)
			(stroke
				(width 0.1)
				(type default)
			)
			(layer "F.Fab")
		)
		(pad "1" smd circle
			(at -0.40005 0 180)
			(size 0 0)
			(layers "F.Cu" "F.Mask" "F.Paste")
			(net "FAN_5_FAULT_R")
		)
		(pad "2" smd circle
			(at 0.40005 0 180)
			(size 0 0)
			(layers "F.Cu" "F.Mask" "F.Paste")
			(net "FAN_5_P3V_R")
		)
	)
	(footprint ""
		(layer "F.Cu")
		(at 20.955 -129.159 -90)
		(property "Reference" "U330"
			(at 3.93573 1.75514 0)
			(unlocked yes)
			(layer "F.SilkS")
			(effects
				(font
					(size 0.7874 0.5842)
					(thickness 0.1524)
				)
				(justify left)
			)
		)
		(property "Value" ""
			(at 0 0 270)
			(layer "F.Fab")
			(effects
				(font
					(size 1.27 1.27)
				)
			)
		)
		(duplicate_pad_numbers_are_jumpers no)
		(fp_line
			(start -0.4064 2.54)
			(end -0.4064 3.302)
			(stroke
				(width 0.1524)
				(type default)
			)
			(layer "F.SilkS")
		)
		(fp_line
			(start -2.050034 2.050034)
			(end -1.417828 2.050034)
			(stroke
				(width 0.1524)
				(type default)
			)
			(layer "F.SilkS")
		)
		(fp_line
			(start 1.42367 2.050034)
			(end 2.050034 2.050034)
			(stroke
				(width 0.1524)
				(type default)
			)
			(layer "F.SilkS")
		)
		(fp_line
			(start 2.050034 2.050034)
			(end 2.050034 1.41732)
			(stroke
				(width 0.1524)
				(type default)
			)
			(layer "F.SilkS")
		)
		(fp_line
			(start -2.050034 1.41986)
			(end -2.050034 2.050034)
			(stroke
				(width 0.1524)
				(type default)
			)
			(layer "F.SilkS")
		)
		(fp_line
			(start 3.048 1.2192)
			(end 2.54 1.2192)
			(stroke
				(width 0.1524)
				(type default)
			)
			(layer "F.SilkS")
		)
		(fp_line
			(start -2.54508 0.398272)
			(end -3.05308 0.398272)
			(stroke
				(width 0.1524)
				(type default)
			)
			(layer "F.SilkS")
		)
		(fp_line
			(start 3.302 -0.8128)
			(end 2.54 -0.8128)
			(stroke
				(width 0.1524)
				(type default)
			)
			(layer "F.SilkS")
		)
		(fp_line
			(start 2.050034 -1.415796)
			(end 2.050034 -2.050034)
			(stroke
				(width 0.1524)
				(type default)
			)
			(layer "F.SilkS")
		)
		(fp_line
			(start -2.050034 -2.050034)
			(end -2.050034 -1.4224)
			(stroke
				(width 0.1524)
				(type default)
			)
			(layer "F.SilkS")
		)
		(fp_line
			(start -1.42367 -2.050034)
			(end -2.050034 -2.050034)
			(stroke
				(width 0.1524)
				(type default)
			)
			(layer "F.SilkS")
		)
		(fp_line
			(start 2.050034 -2.050034)
			(end 1.41859 -2.050034)
			(stroke
				(width 0.1524)
				(type default)
			)
			(layer "F.SilkS")
		)
		(fp_line
			(start 0 -3.048)
			(end 0 -2.54)
			(stroke
				(width 0.1524)
				(type default)
			)
			(layer "F.SilkS")
		)
		(fp_poly
			(pts
				(xy -3.5052 -1.707896) (xy -3.5052 -0.691896) (xy -2.4892 -1.199896)
			)
			(stroke
				(width 0)
				(type default)
			)
			(fill yes)
			(layer "F.SilkS")
		)
		(fp_line
			(start -0.396748 2.568448)
			(end -0.396748 3.330448)
			(stroke
				(width 0.1)
				(type default)
			)
			(layer "F.Fab")
		)
		(fp_line
			(start -2.050034 2.050034)
			(end 2.050034 2.050034)
			(stroke
				(width 0.1)
				(type default)
			)
			(layer "F.Fab")
		)
		(fp_line
			(start 2.050034 2.050034)
			(end 2.050034 -2.050034)
			(stroke
				(width 0.1)
				(type default)
			)
			(layer "F.Fab")
		)
		(fp_line
			(start 3.062732 1.198372)
			(end 2.554732 1.198372)
			(stroke
				(width 0.1)
				(type default)
			)
			(layer "F.Fab")
		)
		(fp_line
			(start -2.54508 0.398272)
			(end -3.05308 0.398272)
			(stroke
				(width 0.1)
				(type default)
			)
			(layer "F.Fab")
		)
		(fp_line
			(start 3.319272 -0.80264)
			(end 2.557272 -0.80264)
			(stroke
				(width 0.1)
				(type default)
			)
			(layer "F.Fab")
		)
		(fp_line
			(start -2.050034 -2.050034)
			(end -2.050034 2.050034)
			(stroke
				(width 0.1)
				(type default)
			)
			(layer "F.Fab")
		)
		(fp_line
			(start 2.050034 -2.050034)
			(end -2.050034 -2.050034)
			(stroke
				(width 0.1)
				(type default)
			)
			(layer "F.Fab")
		)
		(fp_line
			(start 0.009652 -3.052572)
			(end 0.009652 -2.544572)
			(stroke
				(width 0.1)
				(type default)
			)
			(layer "F.Fab")
		)
		(fp_poly
			(pts
				(xy -3.5052 -1.707896) (xy -3.5052 -0.691896) (xy -2.4892 -1.199896)
			)
			(stroke
				(width 0)
				(type default)
			)
			(fill yes)
			(layer "F.Fab")
		)
		(fp_text user "14"
			(at 0.30734 3.18897 270)
			(unlocked yes)
			(layer "F.SilkS")
			(effects
				(font
					(size 0.635 0.4064)
					(thickness 0.1524)
				)
				(justify left)
			)
		)
		(fp_text user "8"
			(at -1.92405 2.586482 270)
			(unlocked yes)
			(layer "F.SilkS")
			(effects
				(font
					(size 0.635 0.4064)
					(thickness 0.1524)
				)
				(justify left)
			)
		)
		(fp_text user "15"
			(at 2.630932 2.33045 0)
			(unlocked yes)
			(layer "F.SilkS")
			(effects
				(font
					(size 0.635 0.4064)
					(thickness 0.1524)
				)
				(justify left)
			)
		)
		(fp_text user "7"
			(at -2.563368 1.8923 0)
			(unlocked yes)
			(layer "F.SilkS")
			(effects
				(font
					(size 0.635 0.4064)
					(thickness 0.1524)
				)
				(justify left)
			)
		)
		(fp_text user "21"
			(at 2.618232 -1.3843 0)
			(unlocked yes)
			(layer "F.SilkS")
			(effects
				(font
					(size 0.635 0.4064)
					(thickness 0.1524)
				)
				(justify left)
			)
		)
		(fp_text user "28"
			(at -2.38125 -2.576068 270)
			(unlocked yes)
			(layer "F.SilkS")
			(effects
				(font
					(size 0.635 0.4064)
					(thickness 0.1524)
				)
				(justify left)
			)
		)
		(fp_text user "22"
			(at 1.41605 -2.684018 270)
			(unlocked yes)
			(layer "F.SilkS")
			(effects
				(font
					(size 0.635 0.4064)
					(thickness 0.1524)
				)
				(justify left)
			)
		)
		(fp_text user "14"
			(at 1.3208 2.745232 270)
			(unlocked yes)
			(layer "F.Fab")
			(effects
				(font
					(size 0.635 0.4064)
					(thickness 0.1524)
				)
				(justify left)
			)
		)
		(fp_text user "8"
			(at -1.92405 2.586482 270)
			(unlocked yes)
			(layer "F.Fab")
			(effects
				(font
					(size 0.635 0.4064)
					(thickness 0.1524)
				)
				(justify left)
			)
		)
		(fp_text user "15"
			(at 2.630932 2.33045 0)
			(unlocked yes)
			(layer "F.Fab")
			(effects
				(font
					(size 0.635 0.4064)
					(thickness 0.1524)
				)
				(justify left)
			)
		)
		(fp_text user "7"
			(at -2.563368 1.8923 0)
			(unlocked yes)
			(layer "F.Fab")
			(effects
				(font
					(size 0.635 0.4064)
					(thickness 0.1524)
				)
				(justify left)
			)
		)
		(fp_text user "21"
			(at 2.618232 -1.3843 0)
			(unlocked yes)
			(layer "F.Fab")
			(effects
				(font
					(size 0.635 0.4064)
					(thickness 0.1524)
				)
				(justify left)
			)
		)
		(fp_text user "28"
			(at -2.38125 -2.576068 270)
			(unlocked yes)
			(layer "F.Fab")
			(effects
				(font
					(size 0.635 0.4064)
					(thickness 0.1524)
				)
				(justify left)
			)
		)
		(fp_text user "22"
			(at 1.41605 -2.684018 270)
			(unlocked yes)
			(layer "F.Fab")
			(effects
				(font
					(size 0.635 0.4064)
					(thickness 0.1524)
				)
				(justify left)
			)
		)
		(pad "1" smd rect
			(at -1.999996 -1.199896)
			(size 0.1778 0.8128)
			(layers "F.Cu" "F.Mask" "F.Paste")
			(net "MAX31790_U330_FREQ_START")
		)
		(pad "2" smd rect
			(at -1.999996 -0.8001)
			(size 0.1778 0.8128)
			(layers "F.Cu" "F.Mask" "F.Paste")
			(net "MAX31790_U330_SPIN_START")
		)
		(pad "3" smd rect
			(at -1.999996 -0.40005)
			(size 0.1778 0.8128)
			(layers "F.Cu" "F.Mask" "F.Paste")
			(net "MAX31790_U330_ADD1")
		)
		(pad "4" smd rect
			(at -1.999996 0)
			(size 0.1778 0.8128)
			(layers "F.Cu" "F.Mask" "F.Paste")
			(net "MAX31790_U330_ADD0")
		)
		(pad "5" smd rect
			(at -1.999996 0.40005)
			(size 0.1778 0.8128)
			(layers "F.Cu" "F.Mask" "F.Paste")
			(net "MAX31790_U330_WD_START")
		)
		(pad "6" smd rect
			(at -1.999996 0.8001)
			(size 0.1778 0.8128)
			(layers "F.Cu" "F.Mask" "F.Paste")
			(net "TP_U330_XTAL2")
		)
		(pad "7" smd rect
			(at -1.999996 1.199896)
			(size 0.1778 0.8128)
			(layers "F.Cu" "F.Mask" "F.Paste")
			(net "TP_U330_XTAL1")
		)
		(pad "8" smd rect
			(at -1.199896 1.999996 270)
			(size 0.1778 0.8128)
			(layers "F.Cu" "F.Mask" "F.Paste")
			(net "GND")
		)
		(pad "9" smd rect
			(at -0.8001 1.999996 270)
			(size 0.1778 0.8128)
			(layers "F.Cu" "F.Mask" "F.Paste")
			(net "FAN_7_TACH_OL_R1")
		)
		(pad "10" smd rect
			(at -0.40005 1.999996 270)
			(size 0.1778 0.8128)
			(layers "F.Cu" "F.Mask" "F.Paste")
			(net "FAN_7_PWM_R1")
		)
		(pad "11" smd rect
			(at 0 1.999996 270)
			(size 0.1778 0.8128)
			(layers "F.Cu" "F.Mask" "F.Paste")
			(net "FAN_6_TACH_OL_R1")
		)
		(pad "12" smd rect
			(at 0.40005 1.999996 270)
			(size 0.1778 0.8128)
			(layers "F.Cu" "F.Mask" "F.Paste")
			(net "FAN_7_TACH_IL_R1")
		)
		(pad "13" smd rect
			(at 0.8001 1.999996 270)
			(size 0.1778 0.8128)
			(layers "F.Cu" "F.Mask" "F.Paste")
			(net "FAN_6_TACH_IL_R1")
		)
		(pad "14" smd rect
			(at 1.199896 1.999996 270)
			(size 0.1778 0.8128)
			(layers "F.Cu" "F.Mask" "F.Paste")
			(net "FAN_6_PWM_R1")
		)
		(pad "15" smd rect
			(at 1.999996 1.199896)
			(size 0.1778 0.8128)
			(layers "F.Cu" "F.Mask" "F.Paste")
			(net "FAN_5_TACH_OL_R1")
		)
		(pad "16" smd rect
			(at 1.999996 0.8001)
			(size 0.1778 0.8128)
			(layers "F.Cu" "F.Mask" "F.Paste")
			(net "FAN_5_PWM_R1")
		)
		(pad "17" smd rect
			(at 1.999996 0.40005)
			(size 0.1778 0.8128)
			(layers "F.Cu" "F.Mask" "F.Paste")
			(net "FAN_4_TACH_OL_R1")
		)
		(pad "18" smd rect
			(at 1.999996 0)
			(size 0.1778 0.8128)
			(layers "F.Cu" "F.Mask" "F.Paste")
			(net "FAN_5_TACH_IL_R1")
		)
		(pad "19" smd rect
			(at 1.999996 -0.40005)
			(size 0.1778 0.8128)
			(layers "F.Cu" "F.Mask" "F.Paste")
			(net "FAN_4_TACH_IL_R1")
		)
		(pad "20" smd rect
			(at 1.999996 -0.8001)
			(size 0.1778 0.8128)
			(layers "F.Cu" "F.Mask" "F.Paste")
			(net "FAN_4_PWM_R1")
		)
		(pad "21" smd rect
			(at 1.999996 -1.199896)
			(size 0.1778 0.8128)
			(layers "F.Cu" "F.Mask" "F.Paste")
			(net "P3V3_AUX")
		)
		(pad "22" smd rect
			(at 1.199896 -1.999996 270)
			(size 0.1778 0.8128)
			(layers "F.Cu" "F.Mask" "F.Paste")
			(net "SMB_PDBV_FAN_R_U330_SDA")
		)
		(pad "23" smd rect
			(at 0.8001 -1.999996 270)
			(size 0.1778 0.8128)
			(layers "F.Cu" "F.Mask" "F.Paste")
			(net "SMB_PDBV_FAN_R_U330_SCL")
		)
		(pad "24" smd rect
			(at 0.40005 -1.999996 270)
			(size 0.1778 0.8128)
			(layers "F.Cu" "F.Mask" "F.Paste")
			(net "U330_FAN FAIL_N")
		)
		(pad "25" smd rect
			(at 0 -1.999996 270)
			(size 0.1778 0.8128)
			(layers "F.Cu" "F.Mask" "F.Paste")
			(net "MAX31790_U330_PWM_START0")
		)
		(pad "26" smd rect
			(at -0.40005 -1.999996 270)
			(size 0.1778 0.8128)
			(layers "F.Cu" "F.Mask" "F.Paste")
			(net "MAX31790_U330_PWM_START1")
		)
		(pad "27" smd rect
			(at -0.8001 -1.999996 270)
			(size 0.1778 0.8128)
			(layers "F.Cu" "F.Mask" "F.Paste")
			(net "U330_FAN FS_N")
		)
		(pad "28" smd rect
			(at -1.199896 -1.999996 270)
			(size 0.1778 0.8128)
			(layers "F.Cu" "F.Mask" "F.Paste")
			(net "NC_U330_CLKOUT")
		)
		(pad "TH" smd rect
			(at 0 0)
			(size 2.7178 2.7178)
			(layers "F.Cu" "F.Mask" "F.Paste")
			(net "GND")
		)
		(zone
			(layer "F.Cu")
			(hatch none 0.5)
			(connect_pads
				(clearance 0)
			)
			(min_thickness 0.25)
			(keepout
				(tracks not_allowed)
				(vias allowed)
				(pads allowed)
				(copperpour not_allowed)
				(footprints allowed)
			)
			(placement
				(enabled no)
				(sheetname "")
			)
			(fill
				(thermal_gap 0.5)
				(thermal_bridge_width 0.5)
				(island_removal_mode 0)
			)
			(polygon
				(pts
					(xy 22.4917 -129.3876) (xy 22.37105 -129.3876) (xy 22.37105 -130.57505) (xy 19.53895 -130.57505)
					(xy 19.53895 -127.74295) (xy 22.37105 -127.74295) (xy 22.37105 -129.3622) (xy 22.4917 -129.3622)
					(xy 22.4917 -127.6223) (xy 19.4183 -127.6223) (xy 19.4183 -130.6957) (xy 22.4917 -130.6957)
				)
			)
		)
	)
	(footprint ""
		(layer "F.Cu")
		(at 18.415 -182.626 180)
		(property "Reference" "R5467"
			(at 0 0 180)
			(layer "F.SilkS")
			(hide yes)
			(effects
				(font
					(size 1.27 1.27)
				)
			)
		)
		(property "Value" ""
			(at 0 0 180)
			(layer "F.Fab")
			(effects
				(font
					(size 1.27 1.27)
				)
			)
		)
		(duplicate_pad_numbers_are_jumpers no)
		(fp_line
			(start 0.7874 0.4064)
			(end -0.7874 0.4064)
			(stroke
				(width 0.1524)
				(type default)
			)
			(layer "F.SilkS")
		)
		(fp_line
			(start 0.7874 -0.4064)
			(end 0.7874 0.4064)
			(stroke
				(width 0.1524)
				(type default)
			)
			(layer "F.SilkS")
		)
		(fp_line
			(start -0.7874 0.4064)
			(end -0.7874 -0.4064)
			(stroke
				(width 0.1524)
				(type default)
			)
			(layer "F.SilkS")
		)
		(fp_line
			(start -0.7874 -0.4064)
			(end 0.7874 -0.4064)
			(stroke
				(width 0.1524)
				(type default)
			)
			(layer "F.SilkS")
		)
		(fp_line
			(start 0.67945 0.3048)
			(end 0.120396 0.3048)
			(stroke
				(width 0.1)
				(type default)
			)
			(layer "F.Fab")
		)
		(fp_line
			(start 0.67945 -0.3048)
			(end 0.67945 0.3048)
			(stroke
				(width 0.1)
				(type default)
			)
			(layer "F.Fab")
		)
		(fp_line
			(start 0.12065 -0.2794)
			(end 0.12065 -0.3048)
			(stroke
				(width 0.1)
				(type default)
			)
			(layer "F.Fab")
		)
		(fp_line
			(start 0.12065 -0.3048)
			(end 0.67945 -0.3048)
			(stroke
				(width 0.1)
				(type default)
			)
			(layer "F.Fab")
		)
		(fp_line
			(start 0.120396 0.3048)
			(end 0.120396 0.2794)
			(stroke
				(width 0.1)
				(type default)
			)
			(layer "F.Fab")
		)
		(fp_line
			(start 0.120396 0.2794)
			(end -0.12065 0.2794)
			(stroke
				(width 0.1)
				(type default)
			)
			(layer "F.Fab")
		)
		(fp_line
			(start -0.12065 0.3048)
			(end -0.67945 0.3048)
			(stroke
				(width 0.1)
				(type default)
			)
			(layer "F.Fab")
		)
		(fp_line
			(start -0.12065 0.2794)
			(end -0.12065 0.3048)
			(stroke
				(width 0.1)
				(type default)
			)
			(layer "F.Fab")
		)
		(fp_line
			(start -0.12065 -0.2794)
			(end 0.12065 -0.2794)
			(stroke
				(width 0.1)
				(type default)
			)
			(layer "F.Fab")
		)
		(fp_line
			(start -0.12065 -0.305054)
			(end -0.12065 -0.2794)
			(stroke
				(width 0.1)
				(type default)
			)
			(layer "F.Fab")
		)
		(fp_line
			(start -0.67945 0.3048)
			(end -0.67945 -0.305054)
			(stroke
				(width 0.1)
				(type default)
			)
			(layer "F.Fab")
		)
		(fp_line
			(start -0.67945 -0.305054)
			(end -0.12065 -0.305054)
			(stroke
				(width 0.1)
				(type default)
			)
			(layer "F.Fab")
		)
		(pad "1" smd circle
			(at -0.40005 0 180)
			(size 0 0)
			(layers "F.Cu" "F.Mask" "F.Paste")
			(net "SMB_PDBV_FAN_SCL")
		)
		(pad "2" smd circle
			(at 0.40005 0 180)
			(size 0 0)
			(layers "F.Cu" "F.Mask" "F.Paste")
			(net "SMB_PDBV_FAN_R_IOX_SCL")
		)
	)
	(footprint ""
		(layer "F.Cu")
		(at 45.085 -187.96 180)
		(property "Reference" "R4965"
			(at 0 0 180)
			(layer "F.SilkS")
			(hide yes)
			(effects
				(font
					(size 1.27 1.27)
				)
			)
		)
		(property "Value" ""
			(at 0 0 180)
			(layer "F.Fab")
			(effects
				(font
					(size 1.27 1.27)
				)
			)
		)
		(duplicate_pad_numbers_are_jumpers no)
		(fp_line
			(start 0.7874 0.4064)
			(end -0.7874 0.4064)
			(stroke
				(width 0.1524)
				(type default)
			)
			(layer "F.SilkS")
		)
		(fp_line
			(start 0.7874 -0.4064)
			(end 0.7874 0.4064)
			(stroke
				(width 0.1524)
				(type default)
			)
			(layer "F.SilkS")
		)
		(fp_line
			(start -0.7874 0.4064)
			(end -0.7874 -0.4064)
			(stroke
				(width 0.1524)
				(type default)
			)
			(layer "F.SilkS")
		)
		(fp_line
			(start -0.7874 -0.4064)
			(end 0.7874 -0.4064)
			(stroke
				(width 0.1524)
				(type default)
			)
			(layer "F.SilkS")
		)
		(fp_line
			(start 0.67945 0.3048)
			(end 0.120396 0.3048)
			(stroke
				(width 0.1)
				(type default)
			)
			(layer "F.Fab")
		)
		(fp_line
			(start 0.67945 -0.3048)
			(end 0.67945 0.3048)
			(stroke
				(width 0.1)
				(type default)
			)
			(layer "F.Fab")
		)
		(fp_line
			(start 0.12065 -0.2794)
			(end 0.12065 -0.3048)
			(stroke
				(width 0.1)
				(type default)
			)
			(layer "F.Fab")
		)
		(fp_line
			(start 0.12065 -0.3048)
			(end 0.67945 -0.3048)
			(stroke
				(width 0.1)
				(type default)
			)
			(layer "F.Fab")
		)
		(fp_line
			(start 0.120396 0.3048)
			(end 0.120396 0.2794)
			(stroke
				(width 0.1)
				(type default)
			)
			(layer "F.Fab")
		)
		(fp_line
			(start 0.120396 0.2794)
			(end -0.12065 0.2794)
			(stroke
				(width 0.1)
				(type default)
			)
			(layer "F.Fab")
		)
		(fp_line
			(start -0.12065 0.3048)
			(end -0.67945 0.3048)
			(stroke
				(width 0.1)
				(type default)
			)
			(layer "F.Fab")
		)
		(fp_line
			(start -0.12065 0.2794)
			(end -0.12065 0.3048)
			(stroke
				(width 0.1)
				(type default)
			)
			(layer "F.Fab")
		)
		(fp_line
			(start -0.12065 -0.2794)
			(end 0.12065 -0.2794)
			(stroke
				(width 0.1)
				(type default)
			)
			(layer "F.Fab")
		)
		(fp_line
			(start -0.12065 -0.305054)
			(end -0.12065 -0.2794)
			(stroke
				(width 0.1)
				(type default)
			)
			(layer "F.Fab")
		)
		(fp_line
			(start -0.67945 0.3048)
			(end -0.67945 -0.305054)
			(stroke
				(width 0.1)
				(type default)
			)
			(layer "F.Fab")
		)
		(fp_line
			(start -0.67945 -0.305054)
			(end -0.12065 -0.305054)
			(stroke
				(width 0.1)
				(type default)
			)
			(layer "F.Fab")
		)
		(pad "1" smd circle
			(at -0.40005 0 180)
			(size 0 0)
			(layers "F.Cu" "F.Mask" "F.Paste")
			(net "GND")
		)
		(pad "2" smd circle
			(at 0.40005 0 180)
			(size 0 0)
			(layers "F.Cu" "F.Mask" "F.Paste")
			(net "PD_FAN_BUFF_INPUT_U337E")
		)
	)
	(footprint ""
		(layer "F.Cu")
		(at 28.956 -160.02 90)
		(property "Reference" "R4877"
			(at 0 0 90)
			(layer "F.SilkS")
			(hide yes)
			(effects
				(font
					(size 1.27 1.27)
				)
			)
		)
		(property "Value" ""
			(at 0 0 90)
			(layer "F.Fab")
			(effects
				(font
					(size 1.27 1.27)
				)
			)
		)
		(duplicate_pad_numbers_are_jumpers no)
		(fp_line
			(start 0.7874 -0.4064)
			(end 0.7874 0.4064)
			(stroke
				(width 0.1524)
				(type default)
			)
			(layer "F.SilkS")
		)
		(fp_line
			(start -0.7874 -0.4064)
			(end 0.7874 -0.4064)
			(stroke
				(width 0.1524)
				(type default)
			)
			(layer "F.SilkS")
		)
		(fp_line
			(start 0.7874 0.4064)
			(end -0.7874 0.4064)
			(stroke
				(width 0.1524)
				(type default)
			)
			(layer "F.SilkS")
		)
		(fp_line
			(start -0.7874 0.4064)
			(end -0.7874 -0.4064)
			(stroke
				(width 0.1524)
				(type default)
			)
			(layer "F.SilkS")
		)
		(fp_line
			(start -0.12065 -0.305054)
			(end -0.12065 -0.2794)
			(stroke
				(width 0.1)
				(type default)
			)
			(layer "F.Fab")
		)
		(fp_line
			(start -0.67945 -0.305054)
			(end -0.12065 -0.305054)
			(stroke
				(width 0.1)
				(type default)
			)
			(layer "F.Fab")
		)
		(fp_line
			(start 0.67945 -0.3048)
			(end 0.67945 0.3048)
			(stroke
				(width 0.1)
				(type default)
			)
			(layer "F.Fab")
		)
		(fp_line
			(start 0.12065 -0.3048)
			(end 0.67945 -0.3048)
			(stroke
				(width 0.1)
				(type default)
			)
			(layer "F.Fab")
		)
		(fp_line
			(start 0.12065 -0.2794)
			(end 0.12065 -0.3048)
			(stroke
				(width 0.1)
				(type default)
			)
			(layer "F.Fab")
		)
		(fp_line
			(start -0.12065 -0.2794)
			(end 0.12065 -0.2794)
			(stroke
				(width 0.1)
				(type default)
			)
			(layer "F.Fab")
		)
		(fp_line
			(start 0.120396 0.2794)
			(end -0.12065 0.2794)
			(stroke
				(width 0.1)
				(type default)
			)
			(layer "F.Fab")
		)
		(fp_line
			(start -0.12065 0.2794)
			(end -0.12065 0.3048)
			(stroke
				(width 0.1)
				(type default)
			)
			(layer "F.Fab")
		)
		(fp_line
			(start 0.67945 0.3048)
			(end 0.120396 0.3048)
			(stroke
				(width 0.1)
				(type default)
			)
			(layer "F.Fab")
		)
		(fp_line
			(start 0.120396 0.3048)
			(end 0.120396 0.2794)
			(stroke
				(width 0.1)
				(type default)
			)
			(layer "F.Fab")
		)
		(fp_line
			(start -0.12065 0.3048)
			(end -0.67945 0.3048)
			(stroke
				(width 0.1)
				(type default)
			)
			(layer "F.Fab")
		)
		(fp_line
			(start -0.67945 0.3048)
			(end -0.67945 -0.305054)
			(stroke
				(width 0.1)
				(type default)
			)
			(layer "F.Fab")
		)
		(pad "1" smd circle
			(at -0.40005 0 90)
			(size 0 0)
			(layers "F.Cu" "F.Mask" "F.Paste")
			(net "SMB_FAN5_R_SCL")
		)
		(pad "2" smd circle
			(at 0.40005 0 90)
			(size 0 0)
			(layers "F.Cu" "F.Mask" "F.Paste")
			(net "SMB_FAN5_SCL")
		)
	)
	(footprint ""
		(layer "F.Cu")
		(at 17.907 -162.814 180)
		(property "Reference" "R5495"
			(at 0 0 180)
			(layer "F.SilkS")
			(hide yes)
			(effects
				(font
					(size 1.27 1.27)
				)
			)
		)
		(property "Value" ""
			(at 0 0 180)
			(layer "F.Fab")
			(effects
				(font
					(size 1.27 1.27)
				)
			)
		)
		(duplicate_pad_numbers_are_jumpers no)
		(fp_line
			(start 0.7874 0.4064)
			(end -0.7874 0.4064)
			(stroke
				(width 0.1524)
				(type default)
			)
			(layer "F.SilkS")
		)
		(fp_line
			(start 0.7874 -0.4064)
			(end 0.7874 0.4064)
			(stroke
				(width 0.1524)
				(type default)
			)
			(layer "F.SilkS")
		)
		(fp_line
			(start -0.7874 0.4064)
			(end -0.7874 -0.4064)
			(stroke
				(width 0.1524)
				(type default)
			)
			(layer "F.SilkS")
		)
		(fp_line
			(start -0.7874 -0.4064)
			(end 0.7874 -0.4064)
			(stroke
				(width 0.1524)
				(type default)
			)
			(layer "F.SilkS")
		)
		(fp_line
			(start 0.67945 0.3048)
			(end 0.120396 0.3048)
			(stroke
				(width 0.1)
				(type default)
			)
			(layer "F.Fab")
		)
		(fp_line
			(start 0.67945 -0.3048)
			(end 0.67945 0.3048)
			(stroke
				(width 0.1)
				(type default)
			)
			(layer "F.Fab")
		)
		(fp_line
			(start 0.12065 -0.2794)
			(end 0.12065 -0.3048)
			(stroke
				(width 0.1)
				(type default)
			)
			(layer "F.Fab")
		)
		(fp_line
			(start 0.12065 -0.3048)
			(end 0.67945 -0.3048)
			(stroke
				(width 0.1)
				(type default)
			)
			(layer "F.Fab")
		)
		(fp_line
			(start 0.120396 0.3048)
			(end 0.120396 0.2794)
			(stroke
				(width 0.1)
				(type default)
			)
			(layer "F.Fab")
		)
		(fp_line
			(start 0.120396 0.2794)
			(end -0.12065 0.2794)
			(stroke
				(width 0.1)
				(type default)
			)
			(layer "F.Fab")
		)
		(fp_line
			(start -0.12065 0.3048)
			(end -0.67945 0.3048)
			(stroke
				(width 0.1)
				(type default)
			)
			(layer "F.Fab")
		)
		(fp_line
			(start -0.12065 0.2794)
			(end -0.12065 0.3048)
			(stroke
				(width 0.1)
				(type default)
			)
			(layer "F.Fab")
		)
		(fp_line
			(start -0.12065 -0.2794)
			(end 0.12065 -0.2794)
			(stroke
				(width 0.1)
				(type default)
			)
			(layer "F.Fab")
		)
		(fp_line
			(start -0.12065 -0.305054)
			(end -0.12065 -0.2794)
			(stroke
				(width 0.1)
				(type default)
			)
			(layer "F.Fab")
		)
		(fp_line
			(start -0.67945 0.3048)
			(end -0.67945 -0.305054)
			(stroke
				(width 0.1)
				(type default)
			)
			(layer "F.Fab")
		)
		(fp_line
			(start -0.67945 -0.305054)
			(end -0.12065 -0.305054)
			(stroke
				(width 0.1)
				(type default)
			)
			(layer "F.Fab")
		)
		(pad "1" smd circle
			(at -0.40005 0 180)
			(size 0 0)
			(layers "F.Cu" "F.Mask" "F.Paste")
			(net "FAN_0_PRESENT_R_N")
		)
		(pad "2" smd circle
			(at 0.40005 0 180)
			(size 0 0)
			(layers "F.Cu" "F.Mask" "F.Paste")
			(net "FAN_0_PRESENT_N")
		)
	)
	(footprint ""
		(layer "F.Cu")
		(at 14.87805 -136.144)
		(property "Reference" "R5620"
			(at 0 0 0)
			(layer "F.SilkS")
			(hide yes)
			(effects
				(font
					(size 1.27 1.27)
				)
			)
		)
		(property "Value" ""
			(at 0 0 0)
			(layer "F.Fab")
			(effects
				(font
					(size 1.27 1.27)
				)
			)
		)
		(duplicate_pad_numbers_are_jumpers no)
		(fp_line
			(start -0.7874 -0.4064)
			(end 0.7874 -0.4064)
			(stroke
				(width 0.1524)
				(type default)
			)
			(layer "F.SilkS")
		)
		(fp_line
			(start -0.7874 0.4064)
			(end -0.7874 -0.4064)
			(stroke
				(width 0.1524)
				(type default)
			)
			(layer "F.SilkS")
		)
		(fp_line
			(start 0.7874 -0.4064)
			(end 0.7874 0.4064)
			(stroke
				(width 0.1524)
				(type default)
			)
			(layer "F.SilkS")
		)
		(fp_line
			(start 0.7874 0.4064)
			(end -0.7874 0.4064)
			(stroke
				(width 0.1524)
				(type default)
			)
			(layer "F.SilkS")
		)
		(fp_line
			(start -0.67945 -0.305054)
			(end -0.12065 -0.305054)
			(stroke
				(width 0.1)
				(type default)
			)
			(layer "F.Fab")
		)
		(fp_line
			(start -0.67945 0.3048)
			(end -0.67945 -0.305054)
			(stroke
				(width 0.1)
				(type default)
			)
			(layer "F.Fab")
		)
		(fp_line
			(start -0.12065 -0.305054)
			(end -0.12065 -0.2794)
			(stroke
				(width 0.1)
				(type default)
			)
			(layer "F.Fab")
		)
		(fp_line
			(start -0.12065 -0.2794)
			(end 0.12065 -0.2794)
			(stroke
				(width 0.1)
				(type default)
			)
			(layer "F.Fab")
		)
		(fp_line
			(start -0.12065 0.2794)
			(end -0.12065 0.3048)
			(stroke
				(width 0.1)
				(type default)
			)
			(layer "F.Fab")
		)
		(fp_line
			(start -0.12065 0.3048)
			(end -0.67945 0.3048)
			(stroke
				(width 0.1)
				(type default)
			)
			(layer "F.Fab")
		)
		(fp_line
			(start 0.120396 0.2794)
			(end -0.12065 0.2794)
			(stroke
				(width 0.1)
				(type default)
			)
			(layer "F.Fab")
		)
		(fp_line
			(start 0.120396 0.3048)
			(end 0.120396 0.2794)
			(stroke
				(width 0.1)
				(type default)
			)
			(layer "F.Fab")
		)
		(fp_line
			(start 0.12065 -0.3048)
			(end 0.67945 -0.3048)
			(stroke
				(width 0.1)
				(type default)
			)
			(layer "F.Fab")
		)
		(fp_line
			(start 0.12065 -0.2794)
			(end 0.12065 -0.3048)
			(stroke
				(width 0.1)
				(type default)
			)
			(layer "F.Fab")
		)
		(fp_line
			(start 0.67945 -0.3048)
			(end 0.67945 0.3048)
			(stroke
				(width 0.1)
				(type default)
			)
			(layer "F.Fab")
		)
		(fp_line
			(start 0.67945 0.3048)
			(end 0.120396 0.3048)
			(stroke
				(width 0.1)
				(type default)
			)
			(layer "F.Fab")
		)
		(pad "1" smd rect
			(at -0.40005 0 180)
			(size 0.4572 0.508)
			(layers "F.Cu" "F.Mask" "F.Paste")
			(net "FAN_7_TACH_OL")
		)
		(pad "2" smd rect
			(at 0.40005 0 180)
			(size 0.4572 0.508)
			(layers "F.Cu" "F.Mask" "F.Paste")
			(net "FAN_7_TACH_OL_R1")
		)
	)
	(footprint ""
		(layer "F.Cu")
		(at 22.225 -133.985 90)
		(property "Reference" "R4946"
			(at 0 0 90)
			(layer "F.SilkS")
			(hide yes)
			(effects
				(font
					(size 1.27 1.27)
				)
			)
		)
		(property "Value" ""
			(at 0 0 90)
			(layer "F.Fab")
			(effects
				(font
					(size 1.27 1.27)
				)
			)
		)
		(duplicate_pad_numbers_are_jumpers no)
		(fp_line
			(start 0.7874 -0.4064)
			(end 0.7874 0.4064)
			(stroke
				(width 0.1524)
				(type default)
			)
			(layer "F.SilkS")
		)
		(fp_line
			(start -0.7874 -0.4064)
			(end 0.7874 -0.4064)
			(stroke
				(width 0.1524)
				(type default)
			)
			(layer "F.SilkS")
		)
		(fp_line
			(start 0.7874 0.4064)
			(end -0.7874 0.4064)
			(stroke
				(width 0.1524)
				(type default)
			)
			(layer "F.SilkS")
		)
		(fp_line
			(start -0.7874 0.4064)
			(end -0.7874 -0.4064)
			(stroke
				(width 0.1524)
				(type default)
			)
			(layer "F.SilkS")
		)
		(fp_line
			(start -0.12065 -0.305054)
			(end -0.12065 -0.2794)
			(stroke
				(width 0.1)
				(type default)
			)
			(layer "F.Fab")
		)
		(fp_line
			(start -0.67945 -0.305054)
			(end -0.12065 -0.305054)
			(stroke
				(width 0.1)
				(type default)
			)
			(layer "F.Fab")
		)
		(fp_line
			(start 0.67945 -0.3048)
			(end 0.67945 0.3048)
			(stroke
				(width 0.1)
				(type default)
			)
			(layer "F.Fab")
		)
		(fp_line
			(start 0.12065 -0.3048)
			(end 0.67945 -0.3048)
			(stroke
				(width 0.1)
				(type default)
			)
			(layer "F.Fab")
		)
		(fp_line
			(start 0.12065 -0.2794)
			(end 0.12065 -0.3048)
			(stroke
				(width 0.1)
				(type default)
			)
			(layer "F.Fab")
		)
		(fp_line
			(start -0.12065 -0.2794)
			(end 0.12065 -0.2794)
			(stroke
				(width 0.1)
				(type default)
			)
			(layer "F.Fab")
		)
		(fp_line
			(start 0.120396 0.2794)
			(end -0.12065 0.2794)
			(stroke
				(width 0.1)
				(type default)
			)
			(layer "F.Fab")
		)
		(fp_line
			(start -0.12065 0.2794)
			(end -0.12065 0.3048)
			(stroke
				(width 0.1)
				(type default)
			)
			(layer "F.Fab")
		)
		(fp_line
			(start 0.67945 0.3048)
			(end 0.120396 0.3048)
			(stroke
				(width 0.1)
				(type default)
			)
			(layer "F.Fab")
		)
		(fp_line
			(start 0.120396 0.3048)
			(end 0.120396 0.2794)
			(stroke
				(width 0.1)
				(type default)
			)
			(layer "F.Fab")
		)
		(fp_line
			(start -0.12065 0.3048)
			(end -0.67945 0.3048)
			(stroke
				(width 0.1)
				(type default)
			)
			(layer "F.Fab")
		)
		(fp_line
			(start -0.67945 0.3048)
			(end -0.67945 -0.305054)
			(stroke
				(width 0.1)
				(type default)
			)
			(layer "F.Fab")
		)
		(pad "1" smd circle
			(at -0.40005 0 90)
			(size 0 0)
			(layers "F.Cu" "F.Mask" "F.Paste")
			(net "MAX31790_U330_SPIN_START")
		)
		(pad "2" smd circle
			(at 0.40005 0 90)
			(size 0 0)
			(layers "F.Cu" "F.Mask" "F.Paste")
			(net "P3V3_AUX")
		)
	)
	(footprint ""
		(layer "F.Cu")
		(at 17.399 -22.606 180)
		(property "Reference" "U342"
			(at 7.112 -0.15367 0)
			(unlocked yes)
			(layer "F.SilkS")
			(effects
				(font
					(size 0.7874 0.5842)
					(thickness 0.1524)
				)
				(justify left)
			)
		)
		(property "Value" ""
			(at 0 0 180)
			(layer "F.Fab")
			(effects
				(font
					(size 1.27 1.27)
				)
			)
		)
		(duplicate_pad_numbers_are_jumpers no)
		(fp_line
			(start 1.335278 1.100074)
			(end 1.335278 -1.100074)
			(stroke
				(width 0.1524)
				(type default)
			)
			(layer "F.SilkS")
		)
		(fp_line
			(start 1.335278 -1.100074)
			(end -1.335278 -1.100074)
			(stroke
				(width 0.1524)
				(type default)
			)
			(layer "F.SilkS")
		)
		(fp_line
			(start -1.335278 1.100074)
			(end 1.335278 1.100074)
			(stroke
				(width 0.1524)
				(type default)
			)
			(layer "F.SilkS")
		)
		(fp_line
			(start -1.335278 -1.100074)
			(end -1.335278 1.100074)
			(stroke
				(width 0.1524)
				(type default)
			)
			(layer "F.SilkS")
		)
		(fp_line
			(start 0.674878 1.100074)
			(end 0.674878 -1.100074)
			(stroke
				(width 0.1)
				(type default)
			)
			(layer "F.Fab")
		)
		(fp_line
			(start 0.674878 -1.100074)
			(end -0.674878 -1.100074)
			(stroke
				(width 0.1)
				(type default)
			)
			(layer "F.Fab")
		)
		(fp_line
			(start -0.674878 1.100074)
			(end 0.674878 1.100074)
			(stroke
				(width 0.1)
				(type default)
			)
			(layer "F.Fab")
		)
		(fp_line
			(start -0.674878 -1.100074)
			(end -0.674878 1.100074)
			(stroke
				(width 0.1)
				(type default)
			)
			(layer "F.Fab")
		)
		(pad "D" smd rect
			(at 0.8001 0 90)
			(size 0.6096 0.8128)
			(layers "F.Cu" "F.Mask" "F.Paste")
			(net "FAN_4_FAIL_LED_R_N")
		)
		(pad "G" smd rect
			(at -0.8001 -0.649986 90)
			(size 0.6096 0.8128)
			(layers "F.Cu" "F.Mask" "F.Paste")
			(net "FAN_4_FAIL_R_LED")
		)
		(pad "S" smd rect
			(at -0.8001 0.649986 90)
			(size 0.6096 0.8128)
			(layers "F.Cu" "F.Mask" "F.Paste")
			(net "GND")
		)
	)
	(footprint ""
		(layer "F.Cu")
		(at 15.621 -167.64)
		(property "Reference" "C58"
			(at 0 0 0)
			(layer "F.SilkS")
			(hide yes)
			(effects
				(font
					(size 1.27 1.27)
				)
			)
		)
		(property "Value" ""
			(at 0 0 0)
			(layer "F.Fab")
			(effects
				(font
					(size 1.27 1.27)
				)
			)
		)
		(duplicate_pad_numbers_are_jumpers no)
		(fp_line
			(start -0.7874 -0.4064)
			(end 0.7874 -0.4064)
			(stroke
				(width 0.1524)
				(type default)
			)
			(layer "F.SilkS")
		)
		(fp_line
			(start -0.7874 0.4064)
			(end -0.7874 -0.4064)
			(stroke
				(width 0.1524)
				(type default)
			)
			(layer "F.SilkS")
		)
		(fp_line
			(start 0.7874 -0.4064)
			(end 0.7874 0.4064)
			(stroke
				(width 0.1524)
				(type default)
			)
			(layer "F.SilkS")
		)
		(fp_line
			(start 0.7874 0.4064)
			(end -0.7874 0.4064)
			(stroke
				(width 0.1524)
				(type default)
			)
			(layer "F.SilkS")
		)
		(fp_line
			(start -0.67945 -0.305054)
			(end -0.12065 -0.305054)
			(stroke
				(width 0.1)
				(type default)
			)
			(layer "F.Fab")
		)
		(fp_line
			(start -0.67945 0.3048)
			(end -0.67945 -0.305054)
			(stroke
				(width 0.1)
				(type default)
			)
			(layer "F.Fab")
		)
		(fp_line
			(start -0.12065 -0.305054)
			(end -0.12065 -0.2794)
			(stroke
				(width 0.1)
				(type default)
			)
			(layer "F.Fab")
		)
		(fp_line
			(start -0.12065 -0.2794)
			(end 0.12065 -0.2794)
			(stroke
				(width 0.1)
				(type default)
			)
			(layer "F.Fab")
		)
		(fp_line
			(start -0.12065 0.2794)
			(end -0.12065 0.3048)
			(stroke
				(width 0.1)
				(type default)
			)
			(layer "F.Fab")
		)
		(fp_line
			(start -0.12065 0.3048)
			(end -0.67945 0.3048)
			(stroke
				(width 0.1)
				(type default)
			)
			(layer "F.Fab")
		)
		(fp_line
			(start 0.120396 0.2794)
			(end -0.12065 0.2794)
			(stroke
				(width 0.1)
				(type default)
			)
			(layer "F.Fab")
		)
		(fp_line
			(start 0.120396 0.3048)
			(end 0.120396 0.2794)
			(stroke
				(width 0.1)
				(type default)
			)
			(layer "F.Fab")
		)
		(fp_line
			(start 0.12065 -0.3048)
			(end 0.67945 -0.3048)
			(stroke
				(width 0.1)
				(type default)
			)
			(layer "F.Fab")
		)
		(fp_line
			(start 0.12065 -0.2794)
			(end 0.12065 -0.3048)
			(stroke
				(width 0.1)
				(type default)
			)
			(layer "F.Fab")
		)
		(fp_line
			(start 0.67945 -0.3048)
			(end 0.67945 0.3048)
			(stroke
				(width 0.1)
				(type default)
			)
			(layer "F.Fab")
		)
		(fp_line
			(start 0.67945 0.3048)
			(end 0.120396 0.3048)
			(stroke
				(width 0.1)
				(type default)
			)
			(layer "F.Fab")
		)
		(pad "1" smd circle
			(at -0.40005 0)
			(size 0 0)
			(layers "F.Cu" "F.Mask" "F.Paste")
			(net "FAN_3_PRESENT_N")
		)
		(pad "2" smd circle
			(at 0.40005 0)
			(size 0 0)
			(layers "F.Cu" "F.Mask" "F.Paste")
			(net "GND")
		)
	)
	(footprint ""
		(layer "F.Cu")
		(at 3.429 -124.714 180)
		(property "Reference" "C2027"
			(at 0 0 180)
			(layer "F.SilkS")
			(hide yes)
			(effects
				(font
					(size 1.27 1.27)
				)
			)
		)
		(property "Value" ""
			(at 0 0 180)
			(layer "F.Fab")
			(effects
				(font
					(size 1.27 1.27)
				)
			)
		)
		(duplicate_pad_numbers_are_jumpers no)
		(fp_line
			(start 0.7874 0.4064)
			(end -0.7874 0.4064)
			(stroke
				(width 0.1524)
				(type default)
			)
			(layer "F.SilkS")
		)
		(fp_line
			(start 0.7874 -0.4064)
			(end 0.7874 0.4064)
			(stroke
				(width 0.1524)
				(type default)
			)
			(layer "F.SilkS")
		)
		(fp_line
			(start -0.7874 0.4064)
			(end -0.7874 -0.4064)
			(stroke
				(width 0.1524)
				(type default)
			)
			(layer "F.SilkS")
		)
		(fp_line
			(start -0.7874 -0.4064)
			(end 0.7874 -0.4064)
			(stroke
				(width 0.1524)
				(type default)
			)
			(layer "F.SilkS")
		)
		(fp_line
			(start 0.6858 0.3048)
			(end 0.1016 0.3048)
			(stroke
				(width 0.1)
				(type default)
			)
			(layer "F.Fab")
		)
		(fp_line
			(start 0.6858 -0.3048)
			(end 0.6858 0.3048)
			(stroke
				(width 0.1)
				(type default)
			)
			(layer "F.Fab")
		)
		(fp_line
			(start 0.1016 0.3048)
			(end 0.1016 0.2794)
			(stroke
				(width 0.1)
				(type default)
			)
			(layer "F.Fab")
		)
		(fp_line
			(start 0.1016 0.2794)
			(end -0.1016 0.2794)
			(stroke
				(width 0.1)
				(type default)
			)
			(layer "F.Fab")
		)
		(fp_line
			(start 0.1016 -0.2794)
			(end 0.1016 -0.3048)
			(stroke
				(width 0.1)
				(type default)
			)
			(layer "F.Fab")
		)
		(fp_line
			(start 0.1016 -0.3048)
			(end 0.6858 -0.3048)
			(stroke
				(width 0.1)
				(type default)
			)
			(layer "F.Fab")
		)
		(fp_line
			(start -0.1016 0.3048)
			(end -0.6858 0.3048)
			(stroke
				(width 0.1)
				(type default)
			)
			(layer "F.Fab")
		)
		(fp_line
			(start -0.1016 0.2794)
			(end -0.1016 0.3048)
			(stroke
				(width 0.1)
				(type default)
			)
			(layer "F.Fab")
		)
		(fp_line
			(start -0.1016 -0.2794)
			(end 0.1016 -0.2794)
			(stroke
				(width 0.1)
				(type default)
			)
			(layer "F.Fab")
		)
		(fp_line
			(start -0.1016 -0.3048)
			(end -0.1016 -0.2794)
			(stroke
				(width 0.1)
				(type default)
			)
			(layer "F.Fab")
		)
		(fp_line
			(start -0.6858 0.3048)
			(end -0.6858 -0.3048)
			(stroke
				(width 0.1)
				(type default)
			)
			(layer "F.Fab")
		)
		(fp_line
			(start -0.6858 -0.3048)
			(end -0.1016 -0.3048)
			(stroke
				(width 0.1)
				(type default)
			)
			(layer "F.Fab")
		)
		(pad "1" smd rect
			(at -0.40005 0)
			(size 0.4572 0.508)
			(layers "F.Cu" "F.Mask" "F.Paste")
			(net "GND")
		)
		(pad "2" smd rect
			(at 0.40005 0)
			(size 0.4572 0.508)
			(layers "F.Cu" "F.Mask" "F.Paste")
			(net "P12V_LED_FAN5")
		)
	)
	(footprint ""
		(layer "F.Cu")
		(at 34.666428 -252.894846 90)
		(property "Reference" "C2067"
			(at 0 0 90)
			(layer "F.SilkS")
			(hide yes)
			(effects
				(font
					(size 1.27 1.27)
				)
			)
		)
		(property "Value" ""
			(at 0 0 90)
			(layer "F.Fab")
			(effects
				(font
					(size 1.27 1.27)
				)
			)
		)
		(duplicate_pad_numbers_are_jumpers no)
		(fp_line
			(start 0.7874 -0.4064)
			(end 0.7874 0.4064)
			(stroke
				(width 0.1524)
				(type default)
			)
			(layer "F.SilkS")
		)
		(fp_line
			(start -0.7874 -0.4064)
			(end 0.7874 -0.4064)
			(stroke
				(width 0.1524)
				(type default)
			)
			(layer "F.SilkS")
		)
		(fp_line
			(start 0.7874 0.4064)
			(end -0.7874 0.4064)
			(stroke
				(width 0.1524)
				(type default)
			)
			(layer "F.SilkS")
		)
		(fp_line
			(start -0.7874 0.4064)
			(end -0.7874 -0.4064)
			(stroke
				(width 0.1524)
				(type default)
			)
			(layer "F.SilkS")
		)
		(fp_line
			(start -0.12065 -0.305054)
			(end -0.12065 -0.2794)
			(stroke
				(width 0.1)
				(type default)
			)
			(layer "F.Fab")
		)
		(fp_line
			(start -0.67945 -0.305054)
			(end -0.12065 -0.305054)
			(stroke
				(width 0.1)
				(type default)
			)
			(layer "F.Fab")
		)
		(fp_line
			(start 0.67945 -0.3048)
			(end 0.67945 0.3048)
			(stroke
				(width 0.1)
				(type default)
			)
			(layer "F.Fab")
		)
		(fp_line
			(start 0.12065 -0.3048)
			(end 0.67945 -0.3048)
			(stroke
				(width 0.1)
				(type default)
			)
			(layer "F.Fab")
		)
		(fp_line
			(start 0.12065 -0.2794)
			(end 0.12065 -0.3048)
			(stroke
				(width 0.1)
				(type default)
			)
			(layer "F.Fab")
		)
		(fp_line
			(start -0.12065 -0.2794)
			(end 0.12065 -0.2794)
			(stroke
				(width 0.1)
				(type default)
			)
			(layer "F.Fab")
		)
		(fp_line
			(start 0.120396 0.2794)
			(end -0.12065 0.2794)
			(stroke
				(width 0.1)
				(type default)
			)
			(layer "F.Fab")
		)
		(fp_line
			(start -0.12065 0.2794)
			(end -0.12065 0.3048)
			(stroke
				(width 0.1)
				(type default)
			)
			(layer "F.Fab")
		)
		(fp_line
			(start 0.67945 0.3048)
			(end 0.120396 0.3048)
			(stroke
				(width 0.1)
				(type default)
			)
			(layer "F.Fab")
		)
		(fp_line
			(start 0.120396 0.3048)
			(end 0.120396 0.2794)
			(stroke
				(width 0.1)
				(type default)
			)
			(layer "F.Fab")
		)
		(fp_line
			(start -0.12065 0.3048)
			(end -0.67945 0.3048)
			(stroke
				(width 0.1)
				(type default)
			)
			(layer "F.Fab")
		)
		(fp_line
			(start -0.67945 0.3048)
			(end -0.67945 -0.305054)
			(stroke
				(width 0.1)
				(type default)
			)
			(layer "F.Fab")
		)
		(pad "1" smd circle
			(at -0.40005 0 90)
			(size 0 0)
			(layers "F.Cu" "F.Mask" "F.Paste")
			(net "P3V3_AUX")
		)
		(pad "2" smd circle
			(at 0.40005 0 90)
			(size 0 0)
			(layers "F.Cu" "F.Mask" "F.Paste")
			(net "GND")
		)
	)
	(footprint ""
		(layer "F.Cu")
		(at 35.052 -107.823)
		(property "Reference" "R5529"
			(at 0 0 0)
			(layer "F.SilkS")
			(hide yes)
			(effects
				(font
					(size 1.27 1.27)
				)
			)
		)
		(property "Value" ""
			(at 0 0 0)
			(layer "F.Fab")
			(effects
				(font
					(size 1.27 1.27)
				)
			)
		)
		(duplicate_pad_numbers_are_jumpers no)
		(fp_line
			(start -0.7874 -0.4064)
			(end 0.7874 -0.4064)
			(stroke
				(width 0.1524)
				(type default)
			)
			(layer "F.SilkS")
		)
		(fp_line
			(start -0.7874 0.4064)
			(end -0.7874 -0.4064)
			(stroke
				(width 0.1524)
				(type default)
			)
			(layer "F.SilkS")
		)
		(fp_line
			(start 0.7874 -0.4064)
			(end 0.7874 0.4064)
			(stroke
				(width 0.1524)
				(type default)
			)
			(layer "F.SilkS")
		)
		(fp_line
			(start 0.7874 0.4064)
			(end -0.7874 0.4064)
			(stroke
				(width 0.1524)
				(type default)
			)
			(layer "F.SilkS")
		)
		(fp_line
			(start -0.67945 -0.305054)
			(end -0.12065 -0.305054)
			(stroke
				(width 0.1)
				(type default)
			)
			(layer "F.Fab")
		)
		(fp_line
			(start -0.67945 0.3048)
			(end -0.67945 -0.305054)
			(stroke
				(width 0.1)
				(type default)
			)
			(layer "F.Fab")
		)
		(fp_line
			(start -0.12065 -0.305054)
			(end -0.12065 -0.2794)
			(stroke
				(width 0.1)
				(type default)
			)
			(layer "F.Fab")
		)
		(fp_line
			(start -0.12065 -0.2794)
			(end 0.12065 -0.2794)
			(stroke
				(width 0.1)
				(type default)
			)
			(layer "F.Fab")
		)
		(fp_line
			(start -0.12065 0.2794)
			(end -0.12065 0.3048)
			(stroke
				(width 0.1)
				(type default)
			)
			(layer "F.Fab")
		)
		(fp_line
			(start -0.12065 0.3048)
			(end -0.67945 0.3048)
			(stroke
				(width 0.1)
				(type default)
			)
			(layer "F.Fab")
		)
		(fp_line
			(start 0.120396 0.2794)
			(end -0.12065 0.2794)
			(stroke
				(width 0.1)
				(type default)
			)
			(layer "F.Fab")
		)
		(fp_line
			(start 0.120396 0.3048)
			(end 0.120396 0.2794)
			(stroke
				(width 0.1)
				(type default)
			)
			(layer "F.Fab")
		)
		(fp_line
			(start 0.12065 -0.3048)
			(end 0.67945 -0.3048)
			(stroke
				(width 0.1)
				(type default)
			)
			(layer "F.Fab")
		)
		(fp_line
			(start 0.12065 -0.2794)
			(end 0.12065 -0.3048)
			(stroke
				(width 0.1)
				(type default)
			)
			(layer "F.Fab")
		)
		(fp_line
			(start 0.67945 -0.3048)
			(end 0.67945 0.3048)
			(stroke
				(width 0.1)
				(type default)
			)
			(layer "F.Fab")
		)
		(fp_line
			(start 0.67945 0.3048)
			(end 0.120396 0.3048)
			(stroke
				(width 0.1)
				(type default)
			)
			(layer "F.Fab")
		)
		(pad "1" smd rect
			(at -0.40005 0 180)
			(size 0.4572 0.508)
			(layers "F.Cu" "F.Mask" "F.Paste")
			(net "P12V_LED_FAN2")
		)
		(pad "2" smd rect
			(at 0.40005 0 180)
			(size 0.4572 0.508)
			(layers "F.Cu" "F.Mask" "F.Paste")
			(net "FAN_2_OK_LED_R_N")
		)
	)
	(footprint ""
		(layer "F.Cu")
		(at 20.32 -141.605 -90)
		(property "Reference" "R572"
			(at 0 0 270)
			(layer "F.SilkS")
			(hide yes)
			(effects
				(font
					(size 1.27 1.27)
				)
			)
		)
		(property "Value" ""
			(at 0 0 270)
			(layer "F.Fab")
			(effects
				(font
					(size 1.27 1.27)
				)
			)
		)
		(duplicate_pad_numbers_are_jumpers no)
		(fp_line
			(start -0.7874 0.4064)
			(end -0.7874 -0.4064)
			(stroke
				(width 0.1524)
				(type default)
			)
			(layer "F.SilkS")
		)
		(fp_line
			(start 0.7874 0.4064)
			(end -0.7874 0.4064)
			(stroke
				(width 0.1524)
				(type default)
			)
			(layer "F.SilkS")
		)
		(fp_line
			(start -0.7874 -0.4064)
			(end 0.7874 -0.4064)
			(stroke
				(width 0.1524)
				(type default)
			)
			(layer "F.SilkS")
		)
		(fp_line
			(start 0.7874 -0.4064)
			(end 0.7874 0.4064)
			(stroke
				(width 0.1524)
				(type default)
			)
			(layer "F.SilkS")
		)
		(fp_line
			(start -0.67945 0.3048)
			(end -0.67945 -0.305054)
			(stroke
				(width 0.1)
				(type default)
			)
			(layer "F.Fab")
		)
		(fp_line
			(start -0.12065 0.3048)
			(end -0.67945 0.3048)
			(stroke
				(width 0.1)
				(type default)
			)
			(layer "F.Fab")
		)
		(fp_line
			(start 0.120396 0.3048)
			(end 0.120396 0.2794)
			(stroke
				(width 0.1)
				(type default)
			)
			(layer "F.Fab")
		)
		(fp_line
			(start 0.67945 0.3048)
			(end 0.120396 0.3048)
			(stroke
				(width 0.1)
				(type default)
			)
			(layer "F.Fab")
		)
		(fp_line
			(start -0.12065 0.2794)
			(end -0.12065 0.3048)
			(stroke
				(width 0.1)
				(type default)
			)
			(layer "F.Fab")
		)
		(fp_line
			(start 0.120396 0.2794)
			(end -0.12065 0.2794)
			(stroke
				(width 0.1)
				(type default)
			)
			(layer "F.Fab")
		)
		(fp_line
			(start -0.12065 -0.2794)
			(end 0.12065 -0.2794)
			(stroke
				(width 0.1)
				(type default)
			)
			(layer "F.Fab")
		)
		(fp_line
			(start 0.12065 -0.2794)
			(end 0.12065 -0.3048)
			(stroke
				(width 0.1)
				(type default)
			)
			(layer "F.Fab")
		)
		(fp_line
			(start 0.12065 -0.3048)
			(end 0.67945 -0.3048)
			(stroke
				(width 0.1)
				(type default)
			)
			(layer "F.Fab")
		)
		(fp_line
			(start 0.67945 -0.3048)
			(end 0.67945 0.3048)
			(stroke
				(width 0.1)
				(type default)
			)
			(layer "F.Fab")
		)
		(fp_line
			(start -0.67945 -0.305054)
			(end -0.12065 -0.305054)
			(stroke
				(width 0.1)
				(type default)
			)
			(layer "F.Fab")
		)
		(fp_line
			(start -0.12065 -0.305054)
			(end -0.12065 -0.2794)
			(stroke
				(width 0.1)
				(type default)
			)
			(layer "F.Fab")
		)
		(pad "1" smd circle
			(at -0.40005 0 270)
			(size 0 0)
			(layers "F.Cu" "F.Mask" "F.Paste")
			(net "RST_SMB_PDB_N")
		)
		(pad "2" smd circle
			(at 0.40005 0 270)
			(size 0 0)
			(layers "F.Cu" "F.Mask" "F.Paste")
			(net "P3V3_AUX")
		)
	)
	(footprint ""
		(layer "F.Cu")
		(at 37.846 -132.588 180)
		(property "Reference" "R5601"
			(at 0 0 180)
			(layer "F.SilkS")
			(hide yes)
			(effects
				(font
					(size 1.27 1.27)
				)
			)
		)
		(property "Value" ""
			(at 0 0 180)
			(layer "F.Fab")
			(effects
				(font
					(size 1.27 1.27)
				)
			)
		)
		(duplicate_pad_numbers_are_jumpers no)
		(fp_line
			(start 0.7874 0.4064)
			(end -0.7874 0.4064)
			(stroke
				(width 0.1524)
				(type default)
			)
			(layer "F.SilkS")
		)
		(fp_line
			(start 0.7874 -0.4064)
			(end 0.7874 0.4064)
			(stroke
				(width 0.1524)
				(type default)
			)
			(layer "F.SilkS")
		)
		(fp_line
			(start -0.7874 0.4064)
			(end -0.7874 -0.4064)
			(stroke
				(width 0.1524)
				(type default)
			)
			(layer "F.SilkS")
		)
		(fp_line
			(start -0.7874 -0.4064)
			(end 0.7874 -0.4064)
			(stroke
				(width 0.1524)
				(type default)
			)
			(layer "F.SilkS")
		)
		(fp_line
			(start 0.67945 0.3048)
			(end 0.120396 0.3048)
			(stroke
				(width 0.1)
				(type default)
			)
			(layer "F.Fab")
		)
		(fp_line
			(start 0.67945 -0.3048)
			(end 0.67945 0.3048)
			(stroke
				(width 0.1)
				(type default)
			)
			(layer "F.Fab")
		)
		(fp_line
			(start 0.12065 -0.2794)
			(end 0.12065 -0.3048)
			(stroke
				(width 0.1)
				(type default)
			)
			(layer "F.Fab")
		)
		(fp_line
			(start 0.12065 -0.3048)
			(end 0.67945 -0.3048)
			(stroke
				(width 0.1)
				(type default)
			)
			(layer "F.Fab")
		)
		(fp_line
			(start 0.120396 0.3048)
			(end 0.120396 0.2794)
			(stroke
				(width 0.1)
				(type default)
			)
			(layer "F.Fab")
		)
		(fp_line
			(start 0.120396 0.2794)
			(end -0.12065 0.2794)
			(stroke
				(width 0.1)
				(type default)
			)
			(layer "F.Fab")
		)
		(fp_line
			(start -0.12065 0.3048)
			(end -0.67945 0.3048)
			(stroke
				(width 0.1)
				(type default)
			)
			(layer "F.Fab")
		)
		(fp_line
			(start -0.12065 0.2794)
			(end -0.12065 0.3048)
			(stroke
				(width 0.1)
				(type default)
			)
			(layer "F.Fab")
		)
		(fp_line
			(start -0.12065 -0.2794)
			(end 0.12065 -0.2794)
			(stroke
				(width 0.1)
				(type default)
			)
			(layer "F.Fab")
		)
		(fp_line
			(start -0.12065 -0.305054)
			(end -0.12065 -0.2794)
			(stroke
				(width 0.1)
				(type default)
			)
			(layer "F.Fab")
		)
		(fp_line
			(start -0.67945 0.3048)
			(end -0.67945 -0.305054)
			(stroke
				(width 0.1)
				(type default)
			)
			(layer "F.Fab")
		)
		(fp_line
			(start -0.67945 -0.305054)
			(end -0.12065 -0.305054)
			(stroke
				(width 0.1)
				(type default)
			)
			(layer "F.Fab")
		)
		(pad "1" smd rect
			(at -0.40005 0)
			(size 0.4572 0.508)
			(layers "F.Cu" "F.Mask" "F.Paste")
			(net "FAN_1_PWM")
		)
		(pad "2" smd rect
			(at 0.40005 0)
			(size 0.4572 0.508)
			(layers "F.Cu" "F.Mask" "F.Paste")
			(net "FAN_1_PWM_R1")
		)
	)
	(footprint ""
		(layer "F.Cu")
		(at 29.083 -141.605 -90)
		(property "Reference" "R5281"
			(at 0 0 270)
			(layer "F.SilkS")
			(hide yes)
			(effects
				(font
					(size 1.27 1.27)
				)
			)
		)
		(property "Value" ""
			(at 0 0 270)
			(layer "F.Fab")
			(effects
				(font
					(size 1.27 1.27)
				)
			)
		)
		(duplicate_pad_numbers_are_jumpers no)
		(fp_line
			(start -0.7874 0.4064)
			(end -0.7874 -0.4064)
			(stroke
				(width 0.1524)
				(type default)
			)
			(layer "F.SilkS")
		)
		(fp_line
			(start 0.7874 0.4064)
			(end -0.7874 0.4064)
			(stroke
				(width 0.1524)
				(type default)
			)
			(layer "F.SilkS")
		)
		(fp_line
			(start -0.7874 -0.4064)
			(end 0.7874 -0.4064)
			(stroke
				(width 0.1524)
				(type default)
			)
			(layer "F.SilkS")
		)
		(fp_line
			(start 0.7874 -0.4064)
			(end 0.7874 0.4064)
			(stroke
				(width 0.1524)
				(type default)
			)
			(layer "F.SilkS")
		)
		(fp_line
			(start -0.67945 0.3048)
			(end -0.67945 -0.305054)
			(stroke
				(width 0.1)
				(type default)
			)
			(layer "F.Fab")
		)
		(fp_line
			(start -0.12065 0.3048)
			(end -0.67945 0.3048)
			(stroke
				(width 0.1)
				(type default)
			)
			(layer "F.Fab")
		)
		(fp_line
			(start 0.120396 0.3048)
			(end 0.120396 0.2794)
			(stroke
				(width 0.1)
				(type default)
			)
			(layer "F.Fab")
		)
		(fp_line
			(start 0.67945 0.3048)
			(end 0.120396 0.3048)
			(stroke
				(width 0.1)
				(type default)
			)
			(layer "F.Fab")
		)
		(fp_line
			(start -0.12065 0.2794)
			(end -0.12065 0.3048)
			(stroke
				(width 0.1)
				(type default)
			)
			(layer "F.Fab")
		)
		(fp_line
			(start 0.120396 0.2794)
			(end -0.12065 0.2794)
			(stroke
				(width 0.1)
				(type default)
			)
			(layer "F.Fab")
		)
		(fp_line
			(start -0.12065 -0.2794)
			(end 0.12065 -0.2794)
			(stroke
				(width 0.1)
				(type default)
			)
			(layer "F.Fab")
		)
		(fp_line
			(start 0.12065 -0.2794)
			(end 0.12065 -0.3048)
			(stroke
				(width 0.1)
				(type default)
			)
			(layer "F.Fab")
		)
		(fp_line
			(start 0.12065 -0.3048)
			(end 0.67945 -0.3048)
			(stroke
				(width 0.1)
				(type default)
			)
			(layer "F.Fab")
		)
		(fp_line
			(start 0.67945 -0.3048)
			(end 0.67945 0.3048)
			(stroke
				(width 0.1)
				(type default)
			)
			(layer "F.Fab")
		)
		(fp_line
			(start -0.67945 -0.305054)
			(end -0.12065 -0.305054)
			(stroke
				(width 0.1)
				(type default)
			)
			(layer "F.Fab")
		)
		(fp_line
			(start -0.12065 -0.305054)
			(end -0.12065 -0.2794)
			(stroke
				(width 0.1)
				(type default)
			)
			(layer "F.Fab")
		)
		(pad "1" smd circle
			(at -0.40005 0 270)
			(size 0 0)
			(layers "F.Cu" "F.Mask" "F.Paste")
			(net "SMB_FAN2_R_SDA")
		)
		(pad "2" smd circle
			(at 0.40005 0 270)
			(size 0 0)
			(layers "F.Cu" "F.Mask" "F.Paste")
			(net "P3V3_AUX")
		)
	)
	(footprint ""
		(layer "F.Cu")
		(at 43.561 -172.847)
		(property "Reference" "R5097"
			(at 0 0 0)
			(layer "F.SilkS")
			(hide yes)
			(effects
				(font
					(size 1.27 1.27)
				)
			)
		)
		(property "Value" ""
			(at 0 0 0)
			(layer "F.Fab")
			(effects
				(font
					(size 1.27 1.27)
				)
			)
		)
		(duplicate_pad_numbers_are_jumpers no)
		(fp_line
			(start -0.7874 -0.4064)
			(end 0.7874 -0.4064)
			(stroke
				(width 0.1524)
				(type default)
			)
			(layer "F.SilkS")
		)
		(fp_line
			(start -0.7874 0.4064)
			(end -0.7874 -0.4064)
			(stroke
				(width 0.1524)
				(type default)
			)
			(layer "F.SilkS")
		)
		(fp_line
			(start 0.7874 -0.4064)
			(end 0.7874 0.4064)
			(stroke
				(width 0.1524)
				(type default)
			)
			(layer "F.SilkS")
		)
		(fp_line
			(start 0.7874 0.4064)
			(end -0.7874 0.4064)
			(stroke
				(width 0.1524)
				(type default)
			)
			(layer "F.SilkS")
		)
		(fp_line
			(start -0.67945 -0.305054)
			(end -0.12065 -0.305054)
			(stroke
				(width 0.1)
				(type default)
			)
			(layer "F.Fab")
		)
		(fp_line
			(start -0.67945 0.3048)
			(end -0.67945 -0.305054)
			(stroke
				(width 0.1)
				(type default)
			)
			(layer "F.Fab")
		)
		(fp_line
			(start -0.12065 -0.305054)
			(end -0.12065 -0.2794)
			(stroke
				(width 0.1)
				(type default)
			)
			(layer "F.Fab")
		)
		(fp_line
			(start -0.12065 -0.2794)
			(end 0.12065 -0.2794)
			(stroke
				(width 0.1)
				(type default)
			)
			(layer "F.Fab")
		)
		(fp_line
			(start -0.12065 0.2794)
			(end -0.12065 0.3048)
			(stroke
				(width 0.1)
				(type default)
			)
			(layer "F.Fab")
		)
		(fp_line
			(start -0.12065 0.3048)
			(end -0.67945 0.3048)
			(stroke
				(width 0.1)
				(type default)
			)
			(layer "F.Fab")
		)
		(fp_line
			(start 0.120396 0.2794)
			(end -0.12065 0.2794)
			(stroke
				(width 0.1)
				(type default)
			)
			(layer "F.Fab")
		)
		(fp_line
			(start 0.120396 0.3048)
			(end 0.120396 0.2794)
			(stroke
				(width 0.1)
				(type default)
			)
			(layer "F.Fab")
		)
		(fp_line
			(start 0.12065 -0.3048)
			(end 0.67945 -0.3048)
			(stroke
				(width 0.1)
				(type default)
			)
			(layer "F.Fab")
		)
		(fp_line
			(start 0.12065 -0.2794)
			(end 0.12065 -0.3048)
			(stroke
				(width 0.1)
				(type default)
			)
			(layer "F.Fab")
		)
		(fp_line
			(start 0.67945 -0.3048)
			(end 0.67945 0.3048)
			(stroke
				(width 0.1)
				(type default)
			)
			(layer "F.Fab")
		)
		(fp_line
			(start 0.67945 0.3048)
			(end 0.120396 0.3048)
			(stroke
				(width 0.1)
				(type default)
			)
			(layer "F.Fab")
		)
		(pad "1" smd circle
			(at -0.40005 0)
			(size 0 0)
			(layers "F.Cu" "F.Mask" "F.Paste")
			(net "FAN_1_FAIL_LED")
		)
		(pad "2" smd circle
			(at 0.40005 0)
			(size 0 0)
			(layers "F.Cu" "F.Mask" "F.Paste")
			(net "FAN_1_FAIL_R_LED")
		)
	)
	(footprint ""
		(layer "F.Cu")
		(at 8.763 -313.817)
		(property "Reference" "R5661"
			(at 0 0 0)
			(layer "F.SilkS")
			(hide yes)
			(effects
				(font
					(size 1.27 1.27)
				)
			)
		)
		(property "Value" ""
			(at 0 0 0)
			(layer "F.Fab")
			(effects
				(font
					(size 1.27 1.27)
				)
			)
		)
		(duplicate_pad_numbers_are_jumpers no)
		(fp_line
			(start -0.7874 -0.4064)
			(end 0.7874 -0.4064)
			(stroke
				(width 0.1524)
				(type default)
			)
			(layer "F.SilkS")
		)
		(fp_line
			(start -0.7874 0.4064)
			(end -0.7874 -0.4064)
			(stroke
				(width 0.1524)
				(type default)
			)
			(layer "F.SilkS")
		)
		(fp_line
			(start 0.7874 -0.4064)
			(end 0.7874 0.4064)
			(stroke
				(width 0.1524)
				(type default)
			)
			(layer "F.SilkS")
		)
		(fp_line
			(start 0.7874 0.4064)
			(end -0.7874 0.4064)
			(stroke
				(width 0.1524)
				(type default)
			)
			(layer "F.SilkS")
		)
		(fp_line
			(start -0.67945 -0.305054)
			(end -0.12065 -0.305054)
			(stroke
				(width 0.1)
				(type default)
			)
			(layer "F.Fab")
		)
		(fp_line
			(start -0.67945 0.3048)
			(end -0.67945 -0.305054)
			(stroke
				(width 0.1)
				(type default)
			)
			(layer "F.Fab")
		)
		(fp_line
			(start -0.12065 -0.305054)
			(end -0.12065 -0.2794)
			(stroke
				(width 0.1)
				(type default)
			)
			(layer "F.Fab")
		)
		(fp_line
			(start -0.12065 -0.2794)
			(end 0.12065 -0.2794)
			(stroke
				(width 0.1)
				(type default)
			)
			(layer "F.Fab")
		)
		(fp_line
			(start -0.12065 0.2794)
			(end -0.12065 0.3048)
			(stroke
				(width 0.1)
				(type default)
			)
			(layer "F.Fab")
		)
		(fp_line
			(start -0.12065 0.3048)
			(end -0.67945 0.3048)
			(stroke
				(width 0.1)
				(type default)
			)
			(layer "F.Fab")
		)
		(fp_line
			(start 0.120396 0.2794)
			(end -0.12065 0.2794)
			(stroke
				(width 0.1)
				(type default)
			)
			(layer "F.Fab")
		)
		(fp_line
			(start 0.120396 0.3048)
			(end 0.120396 0.2794)
			(stroke
				(width 0.1)
				(type default)
			)
			(layer "F.Fab")
		)
		(fp_line
			(start 0.12065 -0.3048)
			(end 0.67945 -0.3048)
			(stroke
				(width 0.1)
				(type default)
			)
			(layer "F.Fab")
		)
		(fp_line
			(start 0.12065 -0.2794)
			(end 0.12065 -0.3048)
			(stroke
				(width 0.1)
				(type default)
			)
			(layer "F.Fab")
		)
		(fp_line
			(start 0.67945 -0.3048)
			(end 0.67945 0.3048)
			(stroke
				(width 0.1)
				(type default)
			)
			(layer "F.Fab")
		)
		(fp_line
			(start 0.67945 0.3048)
			(end 0.120396 0.3048)
			(stroke
				(width 0.1)
				(type default)
			)
			(layer "F.Fab")
		)
		(pad "1" smd rect
			(at -0.40005 0 180)
			(size 0.4572 0.508)
			(layers "F.Cu" "F.Mask" "F.Paste")
			(net "P12V_LED")
		)
		(pad "2" smd rect
			(at 0.40005 0 180)
			(size 0.4572 0.508)
			(layers "F.Cu" "F.Mask" "F.Paste")
			(net "U412_D1")
		)
	)
	(footprint ""
		(layer "F.Cu")
		(at 28.956 -168.529)
		(property "Reference" "R5468"
			(at 0 0 0)
			(layer "F.SilkS")
			(hide yes)
			(effects
				(font
					(size 1.27 1.27)
				)
			)
		)
		(property "Value" ""
			(at 0 0 0)
			(layer "F.Fab")
			(effects
				(font
					(size 1.27 1.27)
				)
			)
		)
		(duplicate_pad_numbers_are_jumpers no)
		(fp_line
			(start -0.7874 -0.4064)
			(end 0.7874 -0.4064)
			(stroke
				(width 0.1524)
				(type default)
			)
			(layer "F.SilkS")
		)
		(fp_line
			(start -0.7874 0.4064)
			(end -0.7874 -0.4064)
			(stroke
				(width 0.1524)
				(type default)
			)
			(layer "F.SilkS")
		)
		(fp_line
			(start 0.7874 -0.4064)
			(end 0.7874 0.4064)
			(stroke
				(width 0.1524)
				(type default)
			)
			(layer "F.SilkS")
		)
		(fp_line
			(start 0.7874 0.4064)
			(end -0.7874 0.4064)
			(stroke
				(width 0.1524)
				(type default)
			)
			(layer "F.SilkS")
		)
		(fp_line
			(start -0.67945 -0.305054)
			(end -0.12065 -0.305054)
			(stroke
				(width 0.1)
				(type default)
			)
			(layer "F.Fab")
		)
		(fp_line
			(start -0.67945 0.3048)
			(end -0.67945 -0.305054)
			(stroke
				(width 0.1)
				(type default)
			)
			(layer "F.Fab")
		)
		(fp_line
			(start -0.12065 -0.305054)
			(end -0.12065 -0.2794)
			(stroke
				(width 0.1)
				(type default)
			)
			(layer "F.Fab")
		)
		(fp_line
			(start -0.12065 -0.2794)
			(end 0.12065 -0.2794)
			(stroke
				(width 0.1)
				(type default)
			)
			(layer "F.Fab")
		)
		(fp_line
			(start -0.12065 0.2794)
			(end -0.12065 0.3048)
			(stroke
				(width 0.1)
				(type default)
			)
			(layer "F.Fab")
		)
		(fp_line
			(start -0.12065 0.3048)
			(end -0.67945 0.3048)
			(stroke
				(width 0.1)
				(type default)
			)
			(layer "F.Fab")
		)
		(fp_line
			(start 0.120396 0.2794)
			(end -0.12065 0.2794)
			(stroke
				(width 0.1)
				(type default)
			)
			(layer "F.Fab")
		)
		(fp_line
			(start 0.120396 0.3048)
			(end 0.120396 0.2794)
			(stroke
				(width 0.1)
				(type default)
			)
			(layer "F.Fab")
		)
		(fp_line
			(start 0.12065 -0.3048)
			(end 0.67945 -0.3048)
			(stroke
				(width 0.1)
				(type default)
			)
			(layer "F.Fab")
		)
		(fp_line
			(start 0.12065 -0.2794)
			(end 0.12065 -0.3048)
			(stroke
				(width 0.1)
				(type default)
			)
			(layer "F.Fab")
		)
		(fp_line
			(start 0.67945 -0.3048)
			(end 0.67945 0.3048)
			(stroke
				(width 0.1)
				(type default)
			)
			(layer "F.Fab")
		)
		(fp_line
			(start 0.67945 0.3048)
			(end 0.120396 0.3048)
			(stroke
				(width 0.1)
				(type default)
			)
			(layer "F.Fab")
		)
		(pad "1" smd circle
			(at -0.40005 0)
			(size 0 0)
			(layers "F.Cu" "F.Mask" "F.Paste")
			(net "SMB_PDBV_FAN_SCL")
		)
		(pad "2" smd circle
			(at 0.40005 0)
			(size 0 0)
			(layers "F.Cu" "F.Mask" "F.Paste")
			(net "SMB_PDBV_FAN_R1_IOX_SCL")
		)
	)
	(footprint ""
		(layer "F.Cu")
		(at 20.828 -172.72)
		(property "Reference" "R5674"
			(at 0 0 0)
			(layer "F.SilkS")
			(hide yes)
			(effects
				(font
					(size 1.27 1.27)
				)
			)
		)
		(property "Value" ""
			(at 0 0 0)
			(layer "F.Fab")
			(effects
				(font
					(size 1.27 1.27)
				)
			)
		)
		(duplicate_pad_numbers_are_jumpers no)
		(fp_line
			(start -0.7874 -0.4064)
			(end 0.7874 -0.4064)
			(stroke
				(width 0.1524)
				(type default)
			)
			(layer "F.SilkS")
		)
		(fp_line
			(start -0.7874 0.4064)
			(end -0.7874 -0.4064)
			(stroke
				(width 0.1524)
				(type default)
			)
			(layer "F.SilkS")
		)
		(fp_line
			(start 0.7874 -0.4064)
			(end 0.7874 0.4064)
			(stroke
				(width 0.1524)
				(type default)
			)
			(layer "F.SilkS")
		)
		(fp_line
			(start 0.7874 0.4064)
			(end -0.7874 0.4064)
			(stroke
				(width 0.1524)
				(type default)
			)
			(layer "F.SilkS")
		)
		(fp_line
			(start -0.67945 -0.305054)
			(end -0.12065 -0.305054)
			(stroke
				(width 0.1)
				(type default)
			)
			(layer "F.Fab")
		)
		(fp_line
			(start -0.67945 0.3048)
			(end -0.67945 -0.305054)
			(stroke
				(width 0.1)
				(type default)
			)
			(layer "F.Fab")
		)
		(fp_line
			(start -0.12065 -0.305054)
			(end -0.12065 -0.2794)
			(stroke
				(width 0.1)
				(type default)
			)
			(layer "F.Fab")
		)
		(fp_line
			(start -0.12065 -0.2794)
			(end 0.12065 -0.2794)
			(stroke
				(width 0.1)
				(type default)
			)
			(layer "F.Fab")
		)
		(fp_line
			(start -0.12065 0.2794)
			(end -0.12065 0.3048)
			(stroke
				(width 0.1)
				(type default)
			)
			(layer "F.Fab")
		)
		(fp_line
			(start -0.12065 0.3048)
			(end -0.67945 0.3048)
			(stroke
				(width 0.1)
				(type default)
			)
			(layer "F.Fab")
		)
		(fp_line
			(start 0.120396 0.2794)
			(end -0.12065 0.2794)
			(stroke
				(width 0.1)
				(type default)
			)
			(layer "F.Fab")
		)
		(fp_line
			(start 0.120396 0.3048)
			(end 0.120396 0.2794)
			(stroke
				(width 0.1)
				(type default)
			)
			(layer "F.Fab")
		)
		(fp_line
			(start 0.12065 -0.3048)
			(end 0.67945 -0.3048)
			(stroke
				(width 0.1)
				(type default)
			)
			(layer "F.Fab")
		)
		(fp_line
			(start 0.12065 -0.2794)
			(end 0.12065 -0.3048)
			(stroke
				(width 0.1)
				(type default)
			)
			(layer "F.Fab")
		)
		(fp_line
			(start 0.67945 -0.3048)
			(end 0.67945 0.3048)
			(stroke
				(width 0.1)
				(type default)
			)
			(layer "F.Fab")
		)
		(fp_line
			(start 0.67945 0.3048)
			(end 0.120396 0.3048)
			(stroke
				(width 0.1)
				(type default)
			)
			(layer "F.Fab")
		)
		(pad "1" smd circle
			(at -0.40005 0)
			(size 0 0)
			(layers "F.Cu" "F.Mask" "F.Paste")
			(net "FM_BOARD_SKU_ID1")
		)
		(pad "2" smd circle
			(at 0.40005 0)
			(size 0 0)
			(layers "F.Cu" "F.Mask" "F.Paste")
			(net "GND")
		)
	)
	(footprint ""
		(layer "F.Cu")
		(at 33.02 -299.339)
		(property "Reference" "D268"
			(at -0.508 1.16967 0)
			(unlocked yes)
			(layer "F.SilkS")
			(effects
				(font
					(size 0.7874 0.5842)
					(thickness 0.1524)
				)
				(justify left)
			)
		)
		(property "Value" ""
			(at 0 0 0)
			(layer "F.Fab")
			(effects
				(font
					(size 1.27 1.27)
				)
			)
		)
		(duplicate_pad_numbers_are_jumpers no)
		(fp_line
			(start -0.854964 -0.450088)
			(end -0.854964 0.450088)
			(stroke
				(width 0.1524)
				(type default)
			)
			(layer "F.SilkS")
		)
		(fp_line
			(start -0.854964 0.450088)
			(end 0.925068 0.450088)
			(stroke
				(width 0.1524)
				(type default)
			)
			(layer "F.SilkS")
		)
		(fp_line
			(start 0.845058 0.4064)
			(end 0.845058 -0.381)
			(stroke
				(width 0.1524)
				(type default)
			)
			(layer "F.SilkS")
		)
		(fp_line
			(start 0.870458 -0.2794)
			(end 0.845058 0.4064)
			(stroke
				(width 0.1524)
				(type default)
			)
			(layer "F.SilkS")
		)
		(fp_line
			(start 0.94488 -0.450088)
			(end -0.854964 -0.450088)
			(stroke
				(width 0.1524)
				(type default)
			)
			(layer "F.SilkS")
		)
		(fp_line
			(start 0.94488 0.450088)
			(end 0.94488 -0.450088)
			(stroke
				(width 0.1524)
				(type default)
			)
			(layer "F.SilkS")
		)
		(fp_line
			(start -0.54991 -0.350012)
			(end -0.54991 0.350012)
			(stroke
				(width 0.1)
				(type default)
			)
			(layer "F.Fab")
		)
		(fp_line
			(start -0.54991 0.350012)
			(end 0.54991 0.350012)
			(stroke
				(width 0.1)
				(type default)
			)
			(layer "F.Fab")
		)
		(fp_line
			(start 0.54991 -0.350012)
			(end -0.54991 -0.350012)
			(stroke
				(width 0.1)
				(type default)
			)
			(layer "F.Fab")
		)
		(fp_line
			(start 0.54991 0.350012)
			(end 0.54991 -0.350012)
			(stroke
				(width 0.1)
				(type default)
			)
			(layer "F.Fab")
		)
		(fp_text user "+"
			(at -1.143 0.47625 180)
			(unlocked yes)
			(layer "F.SilkS")
			(effects
				(font
					(size 1.905 1.4224)
					(thickness 0.1524)
				)
				(justify left)
			)
		)
		(fp_text user "-"
			(at 1.778 -0.41275 180)
			(unlocked yes)
			(layer "F.SilkS")
			(effects
				(font
					(size 1.905 1.4224)
					(thickness 0.1524)
				)
				(justify left)
			)
		)
		(fp_text user "+"
			(at -0.808228 0.239014 180)
			(unlocked yes)
			(layer "F.Fab")
			(effects
				(font
					(size 1.905 1.4224)
					(thickness 0.1524)
				)
				(justify left)
			)
		)
		(fp_text user "-"
			(at 2.48539 0.239014 180)
			(unlocked yes)
			(layer "F.Fab")
			(effects
				(font
					(size 1.905 1.4224)
					(thickness 0.1524)
				)
				(justify left)
			)
		)
		(pad "A" smd rect
			(at -0.424942 0)
			(size 0.5588 0.6096)
			(layers "F.Cu" "F.Mask" "F.Paste")
			(net "GND")
		)
		(pad "C" smd rect
			(at 0.424942 0 180)
			(size 0.5588 0.6096)
			(layers "F.Cu" "F.Mask" "F.Paste")
			(net "FAN_0_PWM_IL_R")
		)
	)
	(footprint ""
		(layer "F.Cu")
		(at 29.083 -197.358 -90)
		(property "Reference" "U401"
			(at -1.905 1.24333 90)
			(unlocked yes)
			(layer "F.SilkS")
			(effects
				(font
					(size 0.7874 0.5842)
					(thickness 0.1524)
				)
				(justify left)
			)
		)
		(property "Value" ""
			(at 0 0 270)
			(layer "F.Fab")
			(effects
				(font
					(size 1.27 1.27)
				)
			)
		)
		(duplicate_pad_numbers_are_jumpers no)
		(fp_line
			(start -1.33096 1.100074)
			(end -1.33096 -1.100074)
			(stroke
				(width 0.1524)
				(type default)
			)
			(layer "F.SilkS")
		)
		(fp_line
			(start 1.33096 1.100074)
			(end -1.33096 1.100074)
			(stroke
				(width 0.1524)
				(type default)
			)
			(layer "F.SilkS")
		)
		(fp_line
			(start 0 -0.649986)
			(end 0.381 -1.100074)
			(stroke
				(width 0.1524)
				(type default)
			)
			(layer "F.SilkS")
		)
		(fp_line
			(start -1.33096 -1.100074)
			(end -0.381 -1.100074)
			(stroke
				(width 0.1524)
				(type default)
			)
			(layer "F.SilkS")
		)
		(fp_line
			(start -0.381 -1.100074)
			(end 0 -0.649986)
			(stroke
				(width 0.1524)
				(type default)
			)
			(layer "F.SilkS")
		)
		(fp_line
			(start 0.381 -1.100074)
			(end 1.33096 -1.100074)
			(stroke
				(width 0.1524)
				(type default)
			)
			(layer "F.SilkS")
		)
		(fp_line
			(start 1.33096 -1.100074)
			(end 1.33096 1.100074)
			(stroke
				(width 0.1524)
				(type default)
			)
			(layer "F.SilkS")
		)
		(fp_poly
			(pts
				(xy -2.209292 -1.029462) (xy -2.209292 -0.521462) (xy -1.447292 -0.775462)
			)
			(stroke
				(width 0)
				(type default)
			)
			(fill yes)
			(layer "F.SilkS")
		)
		(fp_line
			(start -0.674878 1.100074)
			(end -0.674878 -1.100074)
			(stroke
				(width 0.1)
				(type default)
			)
			(layer "F.Fab")
		)
		(fp_line
			(start 0.674878 1.100074)
			(end -0.674878 1.100074)
			(stroke
				(width 0.1)
				(type default)
			)
			(layer "F.Fab")
		)
		(fp_line
			(start -0.674878 -1.100074)
			(end 0.674878 -1.100074)
			(stroke
				(width 0.1)
				(type default)
			)
			(layer "F.Fab")
		)
		(fp_line
			(start 0.674878 -1.100074)
			(end 0.674878 1.100074)
			(stroke
				(width 0.1)
				(type default)
			)
			(layer "F.Fab")
		)
		(fp_poly
			(pts
				(xy -2.209292 -0.902462) (xy -2.209292 -0.394462) (xy -1.447292 -0.648462)
			)
			(stroke
				(width 0)
				(type default)
			)
			(fill yes)
			(layer "F.Fab")
		)
		(pad "1" smd rect
			(at -0.94996 -0.649986)
			(size 0.4064 0.508)
			(layers "F.Cu" "F.Mask" "F.Paste")
			(net "NC_U401_P1")
		)
		(pad "2" smd rect
			(at -0.94996 0)
			(size 0.4064 0.508)
			(layers "F.Cu" "F.Mask" "F.Paste")
			(net "FAN_6_PWM")
		)
		(pad "3" smd rect
			(at -0.94996 0.649986)
			(size 0.4064 0.508)
			(layers "F.Cu" "F.Mask" "F.Paste")
			(net "GND")
		)
		(pad "4" smd rect
			(at 0.94996 0.649986)
			(size 0.4064 0.508)
			(layers "F.Cu" "F.Mask" "F.Paste")
			(net "FAN_6_PWM_BUF")
		)
		(pad "5" smd rect
			(at 0.94996 -0.649986)
			(size 0.4064 0.508)
			(layers "F.Cu" "F.Mask" "F.Paste")
			(net "P3V3_AUX")
		)
	)
	(footprint ""
		(layer "F.Cu")
		(at 30.988 -36.703 180)
		(property "Reference" "R5653"
			(at 0 0 180)
			(layer "F.SilkS")
			(hide yes)
			(effects
				(font
					(size 1.27 1.27)
				)
			)
		)
		(property "Value" ""
			(at 0 0 180)
			(layer "F.Fab")
			(effects
				(font
					(size 1.27 1.27)
				)
			)
		)
		(duplicate_pad_numbers_are_jumpers no)
		(fp_line
			(start 0.7874 0.4064)
			(end -0.7874 0.4064)
			(stroke
				(width 0.1524)
				(type default)
			)
			(layer "F.SilkS")
		)
		(fp_line
			(start 0.7874 -0.4064)
			(end 0.7874 0.4064)
			(stroke
				(width 0.1524)
				(type default)
			)
			(layer "F.SilkS")
		)
		(fp_line
			(start -0.7874 0.4064)
			(end -0.7874 -0.4064)
			(stroke
				(width 0.1524)
				(type default)
			)
			(layer "F.SilkS")
		)
		(fp_line
			(start -0.7874 -0.4064)
			(end 0.7874 -0.4064)
			(stroke
				(width 0.1524)
				(type default)
			)
			(layer "F.SilkS")
		)
		(fp_line
			(start 0.67945 0.3048)
			(end 0.120396 0.3048)
			(stroke
				(width 0.1)
				(type default)
			)
			(layer "F.Fab")
		)
		(fp_line
			(start 0.67945 -0.3048)
			(end 0.67945 0.3048)
			(stroke
				(width 0.1)
				(type default)
			)
			(layer "F.Fab")
		)
		(fp_line
			(start 0.12065 -0.2794)
			(end 0.12065 -0.3048)
			(stroke
				(width 0.1)
				(type default)
			)
			(layer "F.Fab")
		)
		(fp_line
			(start 0.12065 -0.3048)
			(end 0.67945 -0.3048)
			(stroke
				(width 0.1)
				(type default)
			)
			(layer "F.Fab")
		)
		(fp_line
			(start 0.120396 0.3048)
			(end 0.120396 0.2794)
			(stroke
				(width 0.1)
				(type default)
			)
			(layer "F.Fab")
		)
		(fp_line
			(start 0.120396 0.2794)
			(end -0.12065 0.2794)
			(stroke
				(width 0.1)
				(type default)
			)
			(layer "F.Fab")
		)
		(fp_line
			(start -0.12065 0.3048)
			(end -0.67945 0.3048)
			(stroke
				(width 0.1)
				(type default)
			)
			(layer "F.Fab")
		)
		(fp_line
			(start -0.12065 0.2794)
			(end -0.12065 0.3048)
			(stroke
				(width 0.1)
				(type default)
			)
			(layer "F.Fab")
		)
		(fp_line
			(start -0.12065 -0.2794)
			(end 0.12065 -0.2794)
			(stroke
				(width 0.1)
				(type default)
			)
			(layer "F.Fab")
		)
		(fp_line
			(start -0.12065 -0.305054)
			(end -0.12065 -0.2794)
			(stroke
				(width 0.1)
				(type default)
			)
			(layer "F.Fab")
		)
		(fp_line
			(start -0.67945 0.3048)
			(end -0.67945 -0.305054)
			(stroke
				(width 0.1)
				(type default)
			)
			(layer "F.Fab")
		)
		(fp_line
			(start -0.67945 -0.305054)
			(end -0.12065 -0.305054)
			(stroke
				(width 0.1)
				(type default)
			)
			(layer "F.Fab")
		)
		(pad "1" smd rect
			(at -0.40005 0)
			(size 0.4572 0.508)
			(layers "F.Cu" "F.Mask" "F.Paste")
			(net "P12V_LED")
		)
		(pad "2" smd rect
			(at 0.40005 0)
			(size 0.4572 0.508)
			(layers "F.Cu" "F.Mask" "F.Paste")
			(net "U408_D1")
		)
	)
	(footprint ""
		(layer "F.Cu")
		(at 37.338 -27.391868 180)
		(property "Reference" "R5240"
			(at 0 0 180)
			(layer "F.SilkS")
			(hide yes)
			(effects
				(font
					(size 1.27 1.27)
				)
			)
		)
		(property "Value" ""
			(at 0 0 180)
			(layer "F.Fab")
			(effects
				(font
					(size 1.27 1.27)
				)
			)
		)
		(duplicate_pad_numbers_are_jumpers no)
		(fp_line
			(start 0.7874 0.4064)
			(end -0.7874 0.4064)
			(stroke
				(width 0.1524)
				(type default)
			)
			(layer "F.SilkS")
		)
		(fp_line
			(start 0.7874 -0.4064)
			(end 0.7874 0.4064)
			(stroke
				(width 0.1524)
				(type default)
			)
			(layer "F.SilkS")
		)
		(fp_line
			(start -0.7874 0.4064)
			(end -0.7874 -0.4064)
			(stroke
				(width 0.1524)
				(type default)
			)
			(layer "F.SilkS")
		)
		(fp_line
			(start -0.7874 -0.4064)
			(end 0.7874 -0.4064)
			(stroke
				(width 0.1524)
				(type default)
			)
			(layer "F.SilkS")
		)
		(fp_line
			(start 0.67945 0.3048)
			(end 0.120396 0.3048)
			(stroke
				(width 0.1)
				(type default)
			)
			(layer "F.Fab")
		)
		(fp_line
			(start 0.67945 -0.3048)
			(end 0.67945 0.3048)
			(stroke
				(width 0.1)
				(type default)
			)
			(layer "F.Fab")
		)
		(fp_line
			(start 0.12065 -0.2794)
			(end 0.12065 -0.3048)
			(stroke
				(width 0.1)
				(type default)
			)
			(layer "F.Fab")
		)
		(fp_line
			(start 0.12065 -0.3048)
			(end 0.67945 -0.3048)
			(stroke
				(width 0.1)
				(type default)
			)
			(layer "F.Fab")
		)
		(fp_line
			(start 0.120396 0.3048)
			(end 0.120396 0.2794)
			(stroke
				(width 0.1)
				(type default)
			)
			(layer "F.Fab")
		)
		(fp_line
			(start 0.120396 0.2794)
			(end -0.12065 0.2794)
			(stroke
				(width 0.1)
				(type default)
			)
			(layer "F.Fab")
		)
		(fp_line
			(start -0.12065 0.3048)
			(end -0.67945 0.3048)
			(stroke
				(width 0.1)
				(type default)
			)
			(layer "F.Fab")
		)
		(fp_line
			(start -0.12065 0.2794)
			(end -0.12065 0.3048)
			(stroke
				(width 0.1)
				(type default)
			)
			(layer "F.Fab")
		)
		(fp_line
			(start -0.12065 -0.2794)
			(end 0.12065 -0.2794)
			(stroke
				(width 0.1)
				(type default)
			)
			(layer "F.Fab")
		)
		(fp_line
			(start -0.12065 -0.305054)
			(end -0.12065 -0.2794)
			(stroke
				(width 0.1)
				(type default)
			)
			(layer "F.Fab")
		)
		(fp_line
			(start -0.67945 0.3048)
			(end -0.67945 -0.305054)
			(stroke
				(width 0.1)
				(type default)
			)
			(layer "F.Fab")
		)
		(fp_line
			(start -0.67945 -0.305054)
			(end -0.12065 -0.305054)
			(stroke
				(width 0.1)
				(type default)
			)
			(layer "F.Fab")
		)
		(pad "1" smd circle
			(at -0.40005 0 180)
			(size 0 0)
			(layers "F.Cu" "F.Mask" "F.Paste")
			(net "FAN_3_PWM_IL_R")
		)
		(pad "2" smd circle
			(at 0.40005 0 180)
			(size 0 0)
			(layers "F.Cu" "F.Mask" "F.Paste")
			(net "FAN_3_PWM_IL")
		)
	)
	(footprint ""
		(layer "F.Cu")
		(at 5.461 -247.523 180)
		(property "Reference" "PR65"
			(at 0 0 180)
			(layer "F.SilkS")
			(hide yes)
			(effects
				(font
					(size 1.27 1.27)
				)
			)
		)
		(property "Value" ""
			(at 0 0 180)
			(layer "F.Fab")
			(effects
				(font
					(size 1.27 1.27)
				)
			)
		)
		(duplicate_pad_numbers_are_jumpers no)
		(fp_line
			(start 0.7874 0.4064)
			(end -0.7874 0.4064)
			(stroke
				(width 0.1524)
				(type default)
			)
			(layer "F.SilkS")
		)
		(fp_line
			(start 0.7874 -0.4064)
			(end 0.7874 0.4064)
			(stroke
				(width 0.1524)
				(type default)
			)
			(layer "F.SilkS")
		)
		(fp_line
			(start -0.7874 0.4064)
			(end -0.7874 -0.4064)
			(stroke
				(width 0.1524)
				(type default)
			)
			(layer "F.SilkS")
		)
		(fp_line
			(start -0.7874 -0.4064)
			(end 0.7874 -0.4064)
			(stroke
				(width 0.1524)
				(type default)
			)
			(layer "F.SilkS")
		)
		(fp_line
			(start 0.67945 0.3048)
			(end 0.120396 0.3048)
			(stroke
				(width 0.1)
				(type default)
			)
			(layer "F.Fab")
		)
		(fp_line
			(start 0.67945 -0.3048)
			(end 0.67945 0.3048)
			(stroke
				(width 0.1)
				(type default)
			)
			(layer "F.Fab")
		)
		(fp_line
			(start 0.12065 -0.2794)
			(end 0.12065 -0.3048)
			(stroke
				(width 0.1)
				(type default)
			)
			(layer "F.Fab")
		)
		(fp_line
			(start 0.12065 -0.3048)
			(end 0.67945 -0.3048)
			(stroke
				(width 0.1)
				(type default)
			)
			(layer "F.Fab")
		)
		(fp_line
			(start 0.120396 0.3048)
			(end 0.120396 0.2794)
			(stroke
				(width 0.1)
				(type default)
			)
			(layer "F.Fab")
		)
		(fp_line
			(start 0.120396 0.2794)
			(end -0.12065 0.2794)
			(stroke
				(width 0.1)
				(type default)
			)
			(layer "F.Fab")
		)
		(fp_line
			(start -0.12065 0.3048)
			(end -0.67945 0.3048)
			(stroke
				(width 0.1)
				(type default)
			)
			(layer "F.Fab")
		)
		(fp_line
			(start -0.12065 0.2794)
			(end -0.12065 0.3048)
			(stroke
				(width 0.1)
				(type default)
			)
			(layer "F.Fab")
		)
		(fp_line
			(start -0.12065 -0.2794)
			(end 0.12065 -0.2794)
			(stroke
				(width 0.1)
				(type default)
			)
			(layer "F.Fab")
		)
		(fp_line
			(start -0.12065 -0.305054)
			(end -0.12065 -0.2794)
			(stroke
				(width 0.1)
				(type default)
			)
			(layer "F.Fab")
		)
		(fp_line
			(start -0.67945 0.3048)
			(end -0.67945 -0.305054)
			(stroke
				(width 0.1)
				(type default)
			)
			(layer "F.Fab")
		)
		(fp_line
			(start -0.67945 -0.305054)
			(end -0.12065 -0.305054)
			(stroke
				(width 0.1)
				(type default)
			)
			(layer "F.Fab")
		)
		(pad "1" smd circle
			(at -0.40005 0 180)
			(size 0 0)
			(layers "F.Cu" "F.Mask" "F.Paste")
			(net "FAN_6_P3V_R")
		)
		(pad "2" smd circle
			(at 0.40005 0 180)
			(size 0 0)
			(layers "F.Cu" "F.Mask" "F.Paste")
			(net "FAN_6_MODE")
		)
	)
	(footprint ""
		(layer "F.Cu")
		(at 23.622 -143.891 -90)
		(property "Reference" "R4789"
			(at 0 0 270)
			(layer "F.SilkS")
			(hide yes)
			(effects
				(font
					(size 1.27 1.27)
				)
			)
		)
		(property "Value" ""
			(at 0 0 270)
			(layer "F.Fab")
			(effects
				(font
					(size 1.27 1.27)
				)
			)
		)
		(duplicate_pad_numbers_are_jumpers no)
		(fp_line
			(start -0.7874 0.4064)
			(end -0.7874 -0.4064)
			(stroke
				(width 0.1524)
				(type default)
			)
			(layer "F.SilkS")
		)
		(fp_line
			(start 0.7874 0.4064)
			(end -0.7874 0.4064)
			(stroke
				(width 0.1524)
				(type default)
			)
			(layer "F.SilkS")
		)
		(fp_line
			(start -0.7874 -0.4064)
			(end 0.7874 -0.4064)
			(stroke
				(width 0.1524)
				(type default)
			)
			(layer "F.SilkS")
		)
		(fp_line
			(start 0.7874 -0.4064)
			(end 0.7874 0.4064)
			(stroke
				(width 0.1524)
				(type default)
			)
			(layer "F.SilkS")
		)
		(fp_line
			(start -0.67945 0.3048)
			(end -0.67945 -0.305054)
			(stroke
				(width 0.1)
				(type default)
			)
			(layer "F.Fab")
		)
		(fp_line
			(start -0.12065 0.3048)
			(end -0.67945 0.3048)
			(stroke
				(width 0.1)
				(type default)
			)
			(layer "F.Fab")
		)
		(fp_line
			(start 0.120396 0.3048)
			(end 0.120396 0.2794)
			(stroke
				(width 0.1)
				(type default)
			)
			(layer "F.Fab")
		)
		(fp_line
			(start 0.67945 0.3048)
			(end 0.120396 0.3048)
			(stroke
				(width 0.1)
				(type default)
			)
			(layer "F.Fab")
		)
		(fp_line
			(start -0.12065 0.2794)
			(end -0.12065 0.3048)
			(stroke
				(width 0.1)
				(type default)
			)
			(layer "F.Fab")
		)
		(fp_line
			(start 0.120396 0.2794)
			(end -0.12065 0.2794)
			(stroke
				(width 0.1)
				(type default)
			)
			(layer "F.Fab")
		)
		(fp_line
			(start -0.12065 -0.2794)
			(end 0.12065 -0.2794)
			(stroke
				(width 0.1)
				(type default)
			)
			(layer "F.Fab")
		)
		(fp_line
			(start 0.12065 -0.2794)
			(end 0.12065 -0.3048)
			(stroke
				(width 0.1)
				(type default)
			)
			(layer "F.Fab")
		)
		(fp_line
			(start 0.12065 -0.3048)
			(end 0.67945 -0.3048)
			(stroke
				(width 0.1)
				(type default)
			)
			(layer "F.Fab")
		)
		(fp_line
			(start 0.67945 -0.3048)
			(end 0.67945 0.3048)
			(stroke
				(width 0.1)
				(type default)
			)
			(layer "F.Fab")
		)
		(fp_line
			(start -0.67945 -0.305054)
			(end -0.12065 -0.305054)
			(stroke
				(width 0.1)
				(type default)
			)
			(layer "F.Fab")
		)
		(fp_line
			(start -0.12065 -0.305054)
			(end -0.12065 -0.2794)
			(stroke
				(width 0.1)
				(type default)
			)
			(layer "F.Fab")
		)
		(pad "1" smd circle
			(at -0.40005 0 270)
			(size 0 0)
			(layers "F.Cu" "F.Mask" "F.Paste")
			(net "SMB_FAN0_R_SCL")
		)
		(pad "2" smd circle
			(at 0.40005 0 270)
			(size 0 0)
			(layers "F.Cu" "F.Mask" "F.Paste")
			(net "SMB_FAN0_SCL")
		)
	)
	(footprint ""
		(layer "F.Cu")
		(at 3.81 -183.642)
		(property "Reference" "R2361"
			(at 0 0 0)
			(layer "F.SilkS")
			(hide yes)
			(effects
				(font
					(size 1.27 1.27)
				)
			)
		)
		(property "Value" ""
			(at 0 0 0)
			(layer "F.Fab")
			(effects
				(font
					(size 1.27 1.27)
				)
			)
		)
		(duplicate_pad_numbers_are_jumpers no)
		(fp_line
			(start -0.7874 -0.4064)
			(end 0.7874 -0.4064)
			(stroke
				(width 0.1524)
				(type default)
			)
			(layer "F.SilkS")
		)
		(fp_line
			(start -0.7874 0.4064)
			(end -0.7874 -0.4064)
			(stroke
				(width 0.1524)
				(type default)
			)
			(layer "F.SilkS")
		)
		(fp_line
			(start 0.7874 -0.4064)
			(end 0.7874 0.4064)
			(stroke
				(width 0.1524)
				(type default)
			)
			(layer "F.SilkS")
		)
		(fp_line
			(start 0.7874 0.4064)
			(end -0.7874 0.4064)
			(stroke
				(width 0.1524)
				(type default)
			)
			(layer "F.SilkS")
		)
		(fp_line
			(start -0.67945 -0.305054)
			(end -0.12065 -0.305054)
			(stroke
				(width 0.1)
				(type default)
			)
			(layer "F.Fab")
		)
		(fp_line
			(start -0.67945 0.3048)
			(end -0.67945 -0.305054)
			(stroke
				(width 0.1)
				(type default)
			)
			(layer "F.Fab")
		)
		(fp_line
			(start -0.12065 -0.305054)
			(end -0.12065 -0.2794)
			(stroke
				(width 0.1)
				(type default)
			)
			(layer "F.Fab")
		)
		(fp_line
			(start -0.12065 -0.2794)
			(end 0.12065 -0.2794)
			(stroke
				(width 0.1)
				(type default)
			)
			(layer "F.Fab")
		)
		(fp_line
			(start -0.12065 0.2794)
			(end -0.12065 0.3048)
			(stroke
				(width 0.1)
				(type default)
			)
			(layer "F.Fab")
		)
		(fp_line
			(start -0.12065 0.3048)
			(end -0.67945 0.3048)
			(stroke
				(width 0.1)
				(type default)
			)
			(layer "F.Fab")
		)
		(fp_line
			(start 0.120396 0.2794)
			(end -0.12065 0.2794)
			(stroke
				(width 0.1)
				(type default)
			)
			(layer "F.Fab")
		)
		(fp_line
			(start 0.120396 0.3048)
			(end 0.120396 0.2794)
			(stroke
				(width 0.1)
				(type default)
			)
			(layer "F.Fab")
		)
		(fp_line
			(start 0.12065 -0.3048)
			(end 0.67945 -0.3048)
			(stroke
				(width 0.1)
				(type default)
			)
			(layer "F.Fab")
		)
		(fp_line
			(start 0.12065 -0.2794)
			(end 0.12065 -0.3048)
			(stroke
				(width 0.1)
				(type default)
			)
			(layer "F.Fab")
		)
		(fp_line
			(start 0.67945 -0.3048)
			(end 0.67945 0.3048)
			(stroke
				(width 0.1)
				(type default)
			)
			(layer "F.Fab")
		)
		(fp_line
			(start 0.67945 0.3048)
			(end 0.120396 0.3048)
			(stroke
				(width 0.1)
				(type default)
			)
			(layer "F.Fab")
		)
		(pad "1" smd circle
			(at -0.40005 0)
			(size 0 0)
			(layers "F.Cu" "F.Mask" "F.Paste")
			(net "P3V3_AUX")
		)
		(pad "2" smd circle
			(at 0.40005 0)
			(size 0 0)
			(layers "F.Cu" "F.Mask" "F.Paste")
			(net "PCA9555_MB0_A1")
		)
	)
	(footprint ""
		(layer "F.Cu")
		(at 35.56 -32.217868 180)
		(property "Reference" "C2052"
			(at 0 0 180)
			(layer "F.SilkS")
			(hide yes)
			(effects
				(font
					(size 1.27 1.27)
				)
			)
		)
		(property "Value" ""
			(at 0 0 180)
			(layer "F.Fab")
			(effects
				(font
					(size 1.27 1.27)
				)
			)
		)
		(duplicate_pad_numbers_are_jumpers no)
		(fp_line
			(start 0.7874 0.4064)
			(end -0.7874 0.4064)
			(stroke
				(width 0.1524)
				(type default)
			)
			(layer "F.SilkS")
		)
		(fp_line
			(start 0.7874 -0.4064)
			(end 0.7874 0.4064)
			(stroke
				(width 0.1524)
				(type default)
			)
			(layer "F.SilkS")
		)
		(fp_line
			(start -0.7874 0.4064)
			(end -0.7874 -0.4064)
			(stroke
				(width 0.1524)
				(type default)
			)
			(layer "F.SilkS")
		)
		(fp_line
			(start -0.7874 -0.4064)
			(end 0.7874 -0.4064)
			(stroke
				(width 0.1524)
				(type default)
			)
			(layer "F.SilkS")
		)
		(fp_line
			(start 0.67945 0.3048)
			(end 0.120396 0.3048)
			(stroke
				(width 0.1)
				(type default)
			)
			(layer "F.Fab")
		)
		(fp_line
			(start 0.67945 -0.3048)
			(end 0.67945 0.3048)
			(stroke
				(width 0.1)
				(type default)
			)
			(layer "F.Fab")
		)
		(fp_line
			(start 0.12065 -0.2794)
			(end 0.12065 -0.3048)
			(stroke
				(width 0.1)
				(type default)
			)
			(layer "F.Fab")
		)
		(fp_line
			(start 0.12065 -0.3048)
			(end 0.67945 -0.3048)
			(stroke
				(width 0.1)
				(type default)
			)
			(layer "F.Fab")
		)
		(fp_line
			(start 0.120396 0.3048)
			(end 0.120396 0.2794)
			(stroke
				(width 0.1)
				(type default)
			)
			(layer "F.Fab")
		)
		(fp_line
			(start 0.120396 0.2794)
			(end -0.12065 0.2794)
			(stroke
				(width 0.1)
				(type default)
			)
			(layer "F.Fab")
		)
		(fp_line
			(start -0.12065 0.3048)
			(end -0.67945 0.3048)
			(stroke
				(width 0.1)
				(type default)
			)
			(layer "F.Fab")
		)
		(fp_line
			(start -0.12065 0.2794)
			(end -0.12065 0.3048)
			(stroke
				(width 0.1)
				(type default)
			)
			(layer "F.Fab")
		)
		(fp_line
			(start -0.12065 -0.2794)
			(end 0.12065 -0.2794)
			(stroke
				(width 0.1)
				(type default)
			)
			(layer "F.Fab")
		)
		(fp_line
			(start -0.12065 -0.305054)
			(end -0.12065 -0.2794)
			(stroke
				(width 0.1)
				(type default)
			)
			(layer "F.Fab")
		)
		(fp_line
			(start -0.67945 0.3048)
			(end -0.67945 -0.305054)
			(stroke
				(width 0.1)
				(type default)
			)
			(layer "F.Fab")
		)
		(fp_line
			(start -0.67945 -0.305054)
			(end -0.12065 -0.305054)
			(stroke
				(width 0.1)
				(type default)
			)
			(layer "F.Fab")
		)
		(pad "1" smd circle
			(at -0.40005 0 180)
			(size 0 0)
			(layers "F.Cu" "F.Mask" "F.Paste")
			(net "FAN_3_PWM_OL_R")
		)
		(pad "2" smd circle
			(at 0.40005 0 180)
			(size 0 0)
			(layers "F.Cu" "F.Mask" "F.Paste")
			(net "GND")
		)
	)
	(footprint ""
		(layer "F.Cu")
		(at 25.019 -160.02 90)
		(property "Reference" "R4879"
			(at 0 0 90)
			(layer "F.SilkS")
			(hide yes)
			(effects
				(font
					(size 1.27 1.27)
				)
			)
		)
		(property "Value" ""
			(at 0 0 90)
			(layer "F.Fab")
			(effects
				(font
					(size 1.27 1.27)
				)
			)
		)
		(duplicate_pad_numbers_are_jumpers no)
		(fp_line
			(start 0.7874 -0.4064)
			(end 0.7874 0.4064)
			(stroke
				(width 0.1524)
				(type default)
			)
			(layer "F.SilkS")
		)
		(fp_line
			(start -0.7874 -0.4064)
			(end 0.7874 -0.4064)
			(stroke
				(width 0.1524)
				(type default)
			)
			(layer "F.SilkS")
		)
		(fp_line
			(start 0.7874 0.4064)
			(end -0.7874 0.4064)
			(stroke
				(width 0.1524)
				(type default)
			)
			(layer "F.SilkS")
		)
		(fp_line
			(start -0.7874 0.4064)
			(end -0.7874 -0.4064)
			(stroke
				(width 0.1524)
				(type default)
			)
			(layer "F.SilkS")
		)
		(fp_line
			(start -0.12065 -0.305054)
			(end -0.12065 -0.2794)
			(stroke
				(width 0.1)
				(type default)
			)
			(layer "F.Fab")
		)
		(fp_line
			(start -0.67945 -0.305054)
			(end -0.12065 -0.305054)
			(stroke
				(width 0.1)
				(type default)
			)
			(layer "F.Fab")
		)
		(fp_line
			(start 0.67945 -0.3048)
			(end 0.67945 0.3048)
			(stroke
				(width 0.1)
				(type default)
			)
			(layer "F.Fab")
		)
		(fp_line
			(start 0.12065 -0.3048)
			(end 0.67945 -0.3048)
			(stroke
				(width 0.1)
				(type default)
			)
			(layer "F.Fab")
		)
		(fp_line
			(start 0.12065 -0.2794)
			(end 0.12065 -0.3048)
			(stroke
				(width 0.1)
				(type default)
			)
			(layer "F.Fab")
		)
		(fp_line
			(start -0.12065 -0.2794)
			(end 0.12065 -0.2794)
			(stroke
				(width 0.1)
				(type default)
			)
			(layer "F.Fab")
		)
		(fp_line
			(start 0.120396 0.2794)
			(end -0.12065 0.2794)
			(stroke
				(width 0.1)
				(type default)
			)
			(layer "F.Fab")
		)
		(fp_line
			(start -0.12065 0.2794)
			(end -0.12065 0.3048)
			(stroke
				(width 0.1)
				(type default)
			)
			(layer "F.Fab")
		)
		(fp_line
			(start 0.67945 0.3048)
			(end 0.120396 0.3048)
			(stroke
				(width 0.1)
				(type default)
			)
			(layer "F.Fab")
		)
		(fp_line
			(start 0.120396 0.3048)
			(end 0.120396 0.2794)
			(stroke
				(width 0.1)
				(type default)
			)
			(layer "F.Fab")
		)
		(fp_line
			(start -0.12065 0.3048)
			(end -0.67945 0.3048)
			(stroke
				(width 0.1)
				(type default)
			)
			(layer "F.Fab")
		)
		(fp_line
			(start -0.67945 0.3048)
			(end -0.67945 -0.305054)
			(stroke
				(width 0.1)
				(type default)
			)
			(layer "F.Fab")
		)
		(pad "1" smd circle
			(at -0.40005 0 90)
			(size 0 0)
			(layers "F.Cu" "F.Mask" "F.Paste")
			(net "SMB_FAN6_R_SCL")
		)
		(pad "2" smd circle
			(at 0.40005 0 90)
			(size 0 0)
			(layers "F.Cu" "F.Mask" "F.Paste")
			(net "SMB_FAN6_SCL")
		)
	)
	(footprint ""
		(layer "F.Cu")
		(at 34.925 -297.18)
		(property "Reference" "R5526"
			(at 0 0 0)
			(layer "F.SilkS")
			(hide yes)
			(effects
				(font
					(size 1.27 1.27)
				)
			)
		)
		(property "Value" ""
			(at 0 0 0)
			(layer "F.Fab")
			(effects
				(font
					(size 1.27 1.27)
				)
			)
		)
		(duplicate_pad_numbers_are_jumpers no)
		(fp_line
			(start -0.7874 -0.4064)
			(end 0.7874 -0.4064)
			(stroke
				(width 0.1524)
				(type default)
			)
			(layer "F.SilkS")
		)
		(fp_line
			(start -0.7874 0.4064)
			(end -0.7874 -0.4064)
			(stroke
				(width 0.1524)
				(type default)
			)
			(layer "F.SilkS")
		)
		(fp_line
			(start 0.7874 -0.4064)
			(end 0.7874 0.4064)
			(stroke
				(width 0.1524)
				(type default)
			)
			(layer "F.SilkS")
		)
		(fp_line
			(start 0.7874 0.4064)
			(end -0.7874 0.4064)
			(stroke
				(width 0.1524)
				(type default)
			)
			(layer "F.SilkS")
		)
		(fp_line
			(start -0.67945 -0.305054)
			(end -0.12065 -0.305054)
			(stroke
				(width 0.1)
				(type default)
			)
			(layer "F.Fab")
		)
		(fp_line
			(start -0.67945 0.3048)
			(end -0.67945 -0.305054)
			(stroke
				(width 0.1)
				(type default)
			)
			(layer "F.Fab")
		)
		(fp_line
			(start -0.12065 -0.305054)
			(end -0.12065 -0.2794)
			(stroke
				(width 0.1)
				(type default)
			)
			(layer "F.Fab")
		)
		(fp_line
			(start -0.12065 -0.2794)
			(end 0.12065 -0.2794)
			(stroke
				(width 0.1)
				(type default)
			)
			(layer "F.Fab")
		)
		(fp_line
			(start -0.12065 0.2794)
			(end -0.12065 0.3048)
			(stroke
				(width 0.1)
				(type default)
			)
			(layer "F.Fab")
		)
		(fp_line
			(start -0.12065 0.3048)
			(end -0.67945 0.3048)
			(stroke
				(width 0.1)
				(type default)
			)
			(layer "F.Fab")
		)
		(fp_line
			(start 0.120396 0.2794)
			(end -0.12065 0.2794)
			(stroke
				(width 0.1)
				(type default)
			)
			(layer "F.Fab")
		)
		(fp_line
			(start 0.120396 0.3048)
			(end 0.120396 0.2794)
			(stroke
				(width 0.1)
				(type default)
			)
			(layer "F.Fab")
		)
		(fp_line
			(start 0.12065 -0.3048)
			(end 0.67945 -0.3048)
			(stroke
				(width 0.1)
				(type default)
			)
			(layer "F.Fab")
		)
		(fp_line
			(start 0.12065 -0.2794)
			(end 0.12065 -0.3048)
			(stroke
				(width 0.1)
				(type default)
			)
			(layer "F.Fab")
		)
		(fp_line
			(start 0.67945 -0.3048)
			(end 0.67945 0.3048)
			(stroke
				(width 0.1)
				(type default)
			)
			(layer "F.Fab")
		)
		(fp_line
			(start 0.67945 0.3048)
			(end 0.120396 0.3048)
			(stroke
				(width 0.1)
				(type default)
			)
			(layer "F.Fab")
		)
		(pad "1" smd rect
			(at -0.40005 0 180)
			(size 0.4572 0.508)
			(layers "F.Cu" "F.Mask" "F.Paste")
			(net "P12V_LED_FAN0")
		)
		(pad "2" smd rect
			(at 0.40005 0 180)
			(size 0.4572 0.508)
			(layers "F.Cu" "F.Mask" "F.Paste")
			(net "FAN_0_FAIL_LED_R_N")
		)
	)
	(footprint ""
		(layer "F.Cu")
		(at 14.351 -299.339 180)
		(property "Reference" "R5380"
			(at 0 0 180)
			(layer "F.SilkS")
			(hide yes)
			(effects
				(font
					(size 1.27 1.27)
				)
			)
		)
		(property "Value" ""
			(at 0 0 180)
			(layer "F.Fab")
			(effects
				(font
					(size 1.27 1.27)
				)
			)
		)
		(duplicate_pad_numbers_are_jumpers no)
		(fp_line
			(start 0.7874 0.4064)
			(end -0.7874 0.4064)
			(stroke
				(width 0.1524)
				(type default)
			)
			(layer "F.SilkS")
		)
		(fp_line
			(start 0.7874 -0.4064)
			(end 0.7874 0.4064)
			(stroke
				(width 0.1524)
				(type default)
			)
			(layer "F.SilkS")
		)
		(fp_line
			(start -0.7874 0.4064)
			(end -0.7874 -0.4064)
			(stroke
				(width 0.1524)
				(type default)
			)
			(layer "F.SilkS")
		)
		(fp_line
			(start -0.7874 -0.4064)
			(end 0.7874 -0.4064)
			(stroke
				(width 0.1524)
				(type default)
			)
			(layer "F.SilkS")
		)
		(fp_line
			(start 0.67945 0.3048)
			(end 0.120396 0.3048)
			(stroke
				(width 0.1)
				(type default)
			)
			(layer "F.Fab")
		)
		(fp_line
			(start 0.67945 -0.3048)
			(end 0.67945 0.3048)
			(stroke
				(width 0.1)
				(type default)
			)
			(layer "F.Fab")
		)
		(fp_line
			(start 0.12065 -0.2794)
			(end 0.12065 -0.3048)
			(stroke
				(width 0.1)
				(type default)
			)
			(layer "F.Fab")
		)
		(fp_line
			(start 0.12065 -0.3048)
			(end 0.67945 -0.3048)
			(stroke
				(width 0.1)
				(type default)
			)
			(layer "F.Fab")
		)
		(fp_line
			(start 0.120396 0.3048)
			(end 0.120396 0.2794)
			(stroke
				(width 0.1)
				(type default)
			)
			(layer "F.Fab")
		)
		(fp_line
			(start 0.120396 0.2794)
			(end -0.12065 0.2794)
			(stroke
				(width 0.1)
				(type default)
			)
			(layer "F.Fab")
		)
		(fp_line
			(start -0.12065 0.3048)
			(end -0.67945 0.3048)
			(stroke
				(width 0.1)
				(type default)
			)
			(layer "F.Fab")
		)
		(fp_line
			(start -0.12065 0.2794)
			(end -0.12065 0.3048)
			(stroke
				(width 0.1)
				(type default)
			)
			(layer "F.Fab")
		)
		(fp_line
			(start -0.12065 -0.2794)
			(end 0.12065 -0.2794)
			(stroke
				(width 0.1)
				(type default)
			)
			(layer "F.Fab")
		)
		(fp_line
			(start -0.12065 -0.305054)
			(end -0.12065 -0.2794)
			(stroke
				(width 0.1)
				(type default)
			)
			(layer "F.Fab")
		)
		(fp_line
			(start -0.67945 0.3048)
			(end -0.67945 -0.305054)
			(stroke
				(width 0.1)
				(type default)
			)
			(layer "F.Fab")
		)
		(fp_line
			(start -0.67945 -0.305054)
			(end -0.12065 -0.305054)
			(stroke
				(width 0.1)
				(type default)
			)
			(layer "F.Fab")
		)
		(pad "1" smd rect
			(at -0.40005 0)
			(size 0.4572 0.508)
			(layers "F.Cu" "F.Mask" "F.Paste")
			(net "FAN_7_OK_LED_R_N")
		)
		(pad "2" smd rect
			(at 0.40005 0)
			(size 0.4572 0.508)
			(layers "F.Cu" "F.Mask" "F.Paste")
			(net "FAN_7_OK_R_LED_N")
		)
	)
	(footprint ""
		(layer "F.Cu")
		(at 16.139922 -275.608288)
		(property "Reference" "PC54"
			(at -5.344922 6.013958 0)
			(unlocked yes)
			(layer "F.SilkS")
			(effects
				(font
					(size 0.7874 0.5842)
					(thickness 0.1524)
				)
				(justify left)
			)
		)
		(property "Value" ""
			(at 0 0 0)
			(layer "F.Fab")
			(effects
				(font
					(size 1.27 1.27)
				)
			)
		)
		(duplicate_pad_numbers_are_jumpers no)
		(fp_line
			(start -5.249926 -3.979926)
			(end -5.249926 -1.2446)
			(stroke
				(width 0.1524)
				(type default)
			)
			(layer "F.SilkS")
		)
		(fp_line
			(start -5.249926 1.2446)
			(end -5.249926 3.979926)
			(stroke
				(width 0.1524)
				(type default)
			)
			(layer "F.SilkS")
		)
		(fp_line
			(start -5.249926 3.979926)
			(end -3.979926 5.249926)
			(stroke
				(width 0.1524)
				(type default)
			)
			(layer "F.SilkS")
		)
		(fp_line
			(start -3.979926 -5.249926)
			(end -5.249926 -3.979926)
			(stroke
				(width 0.1524)
				(type default)
			)
			(layer "F.SilkS")
		)
		(fp_line
			(start -3.979926 5.249926)
			(end 5.249926 5.249926)
			(stroke
				(width 0.1524)
				(type default)
			)
			(layer "F.SilkS")
		)
		(fp_line
			(start 5.249926 -5.249926)
			(end -3.979926 -5.249926)
			(stroke
				(width 0.1524)
				(type default)
			)
			(layer "F.SilkS")
		)
		(fp_line
			(start 5.249926 -1.2446)
			(end 5.249926 -5.249926)
			(stroke
				(width 0.1524)
				(type default)
			)
			(layer "F.SilkS")
		)
		(fp_line
			(start 5.249926 5.249926)
			(end 5.249926 1.2446)
			(stroke
				(width 0.1524)
				(type default)
			)
			(layer "F.SilkS")
		)
		(fp_line
			(start -5.249926 -5.249926)
			(end -5.249926 5.249926)
			(stroke
				(width 0.1)
				(type default)
			)
			(layer "F.Fab")
		)
		(fp_line
			(start -5.249926 5.249926)
			(end 5.249926 5.249926)
			(stroke
				(width 0.1)
				(type default)
			)
			(layer "F.Fab")
		)
		(fp_line
			(start 5.249926 -5.249926)
			(end -5.249926 -5.249926)
			(stroke
				(width 0.1)
				(type default)
			)
			(layer "F.Fab")
		)
		(fp_line
			(start 5.249926 5.249926)
			(end 5.249926 -5.249926)
			(stroke
				(width 0.1)
				(type default)
			)
			(layer "F.Fab")
		)
		(pad "1" smd rect
			(at -4.45008 0 90)
			(size 2.2098 4.4196)
			(layers "F.Cu" "F.Mask" "F.Paste")
			(net "P52V_FAN_7")
		)
		(pad "2" smd rect
			(at 4.45008 0 90)
			(size 2.2098 4.4196)
			(layers "F.Cu" "F.Mask" "F.Paste")
			(net "GND")
		)
	)
	(footprint ""
		(layer "F.Cu")
		(at 38.62705 -137.668)
		(property "Reference" "R5573"
			(at 0 0 0)
			(layer "F.SilkS")
			(hide yes)
			(effects
				(font
					(size 1.27 1.27)
				)
			)
		)
		(property "Value" ""
			(at 0 0 0)
			(layer "F.Fab")
			(effects
				(font
					(size 1.27 1.27)
				)
			)
		)
		(duplicate_pad_numbers_are_jumpers no)
		(fp_line
			(start -0.7874 -0.4064)
			(end 0.7874 -0.4064)
			(stroke
				(width 0.1524)
				(type default)
			)
			(layer "F.SilkS")
		)
		(fp_line
			(start -0.7874 0.4064)
			(end -0.7874 -0.4064)
			(stroke
				(width 0.1524)
				(type default)
			)
			(layer "F.SilkS")
		)
		(fp_line
			(start 0.7874 -0.4064)
			(end 0.7874 0.4064)
			(stroke
				(width 0.1524)
				(type default)
			)
			(layer "F.SilkS")
		)
		(fp_line
			(start 0.7874 0.4064)
			(end -0.7874 0.4064)
			(stroke
				(width 0.1524)
				(type default)
			)
			(layer "F.SilkS")
		)
		(fp_line
			(start -0.67945 -0.305054)
			(end -0.12065 -0.305054)
			(stroke
				(width 0.1)
				(type default)
			)
			(layer "F.Fab")
		)
		(fp_line
			(start -0.67945 0.3048)
			(end -0.67945 -0.305054)
			(stroke
				(width 0.1)
				(type default)
			)
			(layer "F.Fab")
		)
		(fp_line
			(start -0.12065 -0.305054)
			(end -0.12065 -0.2794)
			(stroke
				(width 0.1)
				(type default)
			)
			(layer "F.Fab")
		)
		(fp_line
			(start -0.12065 -0.2794)
			(end 0.12065 -0.2794)
			(stroke
				(width 0.1)
				(type default)
			)
			(layer "F.Fab")
		)
		(fp_line
			(start -0.12065 0.2794)
			(end -0.12065 0.3048)
			(stroke
				(width 0.1)
				(type default)
			)
			(layer "F.Fab")
		)
		(fp_line
			(start -0.12065 0.3048)
			(end -0.67945 0.3048)
			(stroke
				(width 0.1)
				(type default)
			)
			(layer "F.Fab")
		)
		(fp_line
			(start 0.120396 0.2794)
			(end -0.12065 0.2794)
			(stroke
				(width 0.1)
				(type default)
			)
			(layer "F.Fab")
		)
		(fp_line
			(start 0.120396 0.3048)
			(end 0.120396 0.2794)
			(stroke
				(width 0.1)
				(type default)
			)
			(layer "F.Fab")
		)
		(fp_line
			(start 0.12065 -0.3048)
			(end 0.67945 -0.3048)
			(stroke
				(width 0.1)
				(type default)
			)
			(layer "F.Fab")
		)
		(fp_line
			(start 0.12065 -0.2794)
			(end 0.12065 -0.3048)
			(stroke
				(width 0.1)
				(type default)
			)
			(layer "F.Fab")
		)
		(fp_line
			(start 0.67945 -0.3048)
			(end 0.67945 0.3048)
			(stroke
				(width 0.1)
				(type default)
			)
			(layer "F.Fab")
		)
		(fp_line
			(start 0.67945 0.3048)
			(end 0.120396 0.3048)
			(stroke
				(width 0.1)
				(type default)
			)
			(layer "F.Fab")
		)
		(pad "1" smd rect
			(at -0.40005 0 180)
			(size 0.4572 0.508)
			(layers "F.Cu" "F.Mask" "F.Paste")
			(net "FAN_0_PWM")
		)
		(pad "2" smd rect
			(at 0.40005 0 180)
			(size 0.4572 0.508)
			(layers "F.Cu" "F.Mask" "F.Paste")
			(net "FAN_0_PWM_R2")
		)
	)
	(footprint ""
		(layer "F.Cu")
		(at 6.477 -174.244)
		(property "Reference" "R4864"
			(at 0 0 0)
			(layer "F.SilkS")
			(hide yes)
			(effects
				(font
					(size 1.27 1.27)
				)
			)
		)
		(property "Value" ""
			(at 0 0 0)
			(layer "F.Fab")
			(effects
				(font
					(size 1.27 1.27)
				)
			)
		)
		(duplicate_pad_numbers_are_jumpers no)
		(fp_line
			(start -0.7874 -0.4064)
			(end 0.7874 -0.4064)
			(stroke
				(width 0.1524)
				(type default)
			)
			(layer "F.SilkS")
		)
		(fp_line
			(start -0.7874 0.4064)
			(end -0.7874 -0.4064)
			(stroke
				(width 0.1524)
				(type default)
			)
			(layer "F.SilkS")
		)
		(fp_line
			(start 0.7874 -0.4064)
			(end 0.7874 0.4064)
			(stroke
				(width 0.1524)
				(type default)
			)
			(layer "F.SilkS")
		)
		(fp_line
			(start 0.7874 0.4064)
			(end -0.7874 0.4064)
			(stroke
				(width 0.1524)
				(type default)
			)
			(layer "F.SilkS")
		)
		(fp_line
			(start -0.67945 -0.305054)
			(end -0.12065 -0.305054)
			(stroke
				(width 0.1)
				(type default)
			)
			(layer "F.Fab")
		)
		(fp_line
			(start -0.67945 0.3048)
			(end -0.67945 -0.305054)
			(stroke
				(width 0.1)
				(type default)
			)
			(layer "F.Fab")
		)
		(fp_line
			(start -0.12065 -0.305054)
			(end -0.12065 -0.2794)
			(stroke
				(width 0.1)
				(type default)
			)
			(layer "F.Fab")
		)
		(fp_line
			(start -0.12065 -0.2794)
			(end 0.12065 -0.2794)
			(stroke
				(width 0.1)
				(type default)
			)
			(layer "F.Fab")
		)
		(fp_line
			(start -0.12065 0.2794)
			(end -0.12065 0.3048)
			(stroke
				(width 0.1)
				(type default)
			)
			(layer "F.Fab")
		)
		(fp_line
			(start -0.12065 0.3048)
			(end -0.67945 0.3048)
			(stroke
				(width 0.1)
				(type default)
			)
			(layer "F.Fab")
		)
		(fp_line
			(start 0.120396 0.2794)
			(end -0.12065 0.2794)
			(stroke
				(width 0.1)
				(type default)
			)
			(layer "F.Fab")
		)
		(fp_line
			(start 0.120396 0.3048)
			(end 0.120396 0.2794)
			(stroke
				(width 0.1)
				(type default)
			)
			(layer "F.Fab")
		)
		(fp_line
			(start 0.12065 -0.3048)
			(end 0.67945 -0.3048)
			(stroke
				(width 0.1)
				(type default)
			)
			(layer "F.Fab")
		)
		(fp_line
			(start 0.12065 -0.2794)
			(end 0.12065 -0.3048)
			(stroke
				(width 0.1)
				(type default)
			)
			(layer "F.Fab")
		)
		(fp_line
			(start 0.67945 -0.3048)
			(end 0.67945 0.3048)
			(stroke
				(width 0.1)
				(type default)
			)
			(layer "F.Fab")
		)
		(fp_line
			(start 0.67945 0.3048)
			(end 0.120396 0.3048)
			(stroke
				(width 0.1)
				(type default)
			)
			(layer "F.Fab")
		)
		(pad "1" smd circle
			(at -0.40005 0)
			(size 0 0)
			(layers "F.Cu" "F.Mask" "F.Paste")
			(net "P3V3_AUX")
		)
		(pad "2" smd circle
			(at 0.40005 0)
			(size 0 0)
			(layers "F.Cu" "F.Mask" "F.Paste")
			(net "FAN_7_PRSNT_BUF_R_N")
		)
	)
	(footprint ""
		(layer "F.Cu")
		(at 20.955 -218.059)
		(property "Reference" "C2126"
			(at 0 0 0)
			(layer "F.SilkS")
			(hide yes)
			(effects
				(font
					(size 1.27 1.27)
				)
			)
		)
		(property "Value" ""
			(at 0 0 0)
			(layer "F.Fab")
			(effects
				(font
					(size 1.27 1.27)
				)
			)
		)
		(duplicate_pad_numbers_are_jumpers no)
		(fp_line
			(start -1.2954 -0.5842)
			(end 1.2954 -0.5842)
			(stroke
				(width 0.1524)
				(type default)
			)
			(layer "F.SilkS")
		)
		(fp_line
			(start -1.2954 0.5842)
			(end -1.2954 -0.5842)
			(stroke
				(width 0.1524)
				(type default)
			)
			(layer "F.SilkS")
		)
		(fp_line
			(start 1.2954 -0.5842)
			(end 1.2954 0.5842)
			(stroke
				(width 0.1524)
				(type default)
			)
			(layer "F.SilkS")
		)
		(fp_line
			(start 1.2954 0.5842)
			(end -1.2954 0.5842)
			(stroke
				(width 0.1524)
				(type default)
			)
			(layer "F.SilkS")
		)
		(fp_line
			(start -1.1938 -0.4064)
			(end -0.8636 -0.4064)
			(stroke
				(width 0.1)
				(type default)
			)
			(layer "F.Fab")
		)
		(fp_line
			(start -1.1938 0.4064)
			(end -1.1938 -0.4064)
			(stroke
				(width 0.1)
				(type default)
			)
			(layer "F.Fab")
		)
		(fp_line
			(start -0.8636 -0.4572)
			(end 0.8636 -0.4572)
			(stroke
				(width 0.1)
				(type default)
			)
			(layer "F.Fab")
		)
		(fp_line
			(start -0.8636 -0.4064)
			(end -0.8636 -0.4572)
			(stroke
				(width 0.1)
				(type default)
			)
			(layer "F.Fab")
		)
		(fp_line
			(start -0.8636 0.4064)
			(end -1.1938 0.4064)
			(stroke
				(width 0.1)
				(type default)
			)
			(layer "F.Fab")
		)
		(fp_line
			(start -0.8636 0.4572)
			(end -0.8636 0.4064)
			(stroke
				(width 0.1)
				(type default)
			)
			(layer "F.Fab")
		)
		(fp_line
			(start 0.8636 -0.4572)
			(end 0.8636 -0.4064)
			(stroke
				(width 0.1)
				(type default)
			)
			(layer "F.Fab")
		)
		(fp_line
			(start 0.8636 -0.4064)
			(end 1.1938 -0.4064)
			(stroke
				(width 0.1)
				(type default)
			)
			(layer "F.Fab")
		)
		(fp_line
			(start 0.8636 0.4064)
			(end 0.8636 0.4572)
			(stroke
				(width 0.1)
				(type default)
			)
			(layer "F.Fab")
		)
		(fp_line
			(start 0.8636 0.4572)
			(end -0.8636 0.4572)
			(stroke
				(width 0.1)
				(type default)
			)
			(layer "F.Fab")
		)
		(fp_line
			(start 1.1938 -0.4064)
			(end 1.1938 0.4064)
			(stroke
				(width 0.1)
				(type default)
			)
			(layer "F.Fab")
		)
		(fp_line
			(start 1.1938 0.4064)
			(end 0.8636 0.4064)
			(stroke
				(width 0.1)
				(type default)
			)
			(layer "F.Fab")
		)
		(pad "1" smd rect
			(at -0.7366 0 270)
			(size 0.7112 0.8128)
			(layers "F.Cu" "F.Mask" "F.Paste")
			(net "U411_D1")
		)
		(pad "2" smd rect
			(at 0.7366 0 270)
			(size 0.7112 0.8128)
			(layers "F.Cu" "F.Mask" "F.Paste")
			(net "GND")
		)
	)
	(footprint ""
		(layer "F.Cu")
		(at 35.179 -207.038956 180)
		(property "Reference" "C2029"
			(at 0 0 180)
			(layer "F.SilkS")
			(hide yes)
			(effects
				(font
					(size 1.27 1.27)
				)
			)
		)
		(property "Value" ""
			(at 0 0 180)
			(layer "F.Fab")
			(effects
				(font
					(size 1.27 1.27)
				)
			)
		)
		(duplicate_pad_numbers_are_jumpers no)
		(fp_line
			(start 0.7874 0.4064)
			(end -0.7874 0.4064)
			(stroke
				(width 0.1524)
				(type default)
			)
			(layer "F.SilkS")
		)
		(fp_line
			(start 0.7874 -0.4064)
			(end 0.7874 0.4064)
			(stroke
				(width 0.1524)
				(type default)
			)
			(layer "F.SilkS")
		)
		(fp_line
			(start -0.7874 0.4064)
			(end -0.7874 -0.4064)
			(stroke
				(width 0.1524)
				(type default)
			)
			(layer "F.SilkS")
		)
		(fp_line
			(start -0.7874 -0.4064)
			(end 0.7874 -0.4064)
			(stroke
				(width 0.1524)
				(type default)
			)
			(layer "F.SilkS")
		)
		(fp_line
			(start 0.67945 0.3048)
			(end 0.120396 0.3048)
			(stroke
				(width 0.1)
				(type default)
			)
			(layer "F.Fab")
		)
		(fp_line
			(start 0.67945 -0.3048)
			(end 0.67945 0.3048)
			(stroke
				(width 0.1)
				(type default)
			)
			(layer "F.Fab")
		)
		(fp_line
			(start 0.12065 -0.2794)
			(end 0.12065 -0.3048)
			(stroke
				(width 0.1)
				(type default)
			)
			(layer "F.Fab")
		)
		(fp_line
			(start 0.12065 -0.3048)
			(end 0.67945 -0.3048)
			(stroke
				(width 0.1)
				(type default)
			)
			(layer "F.Fab")
		)
		(fp_line
			(start 0.120396 0.3048)
			(end 0.120396 0.2794)
			(stroke
				(width 0.1)
				(type default)
			)
			(layer "F.Fab")
		)
		(fp_line
			(start 0.120396 0.2794)
			(end -0.12065 0.2794)
			(stroke
				(width 0.1)
				(type default)
			)
			(layer "F.Fab")
		)
		(fp_line
			(start -0.12065 0.3048)
			(end -0.67945 0.3048)
			(stroke
				(width 0.1)
				(type default)
			)
			(layer "F.Fab")
		)
		(fp_line
			(start -0.12065 0.2794)
			(end -0.12065 0.3048)
			(stroke
				(width 0.1)
				(type default)
			)
			(layer "F.Fab")
		)
		(fp_line
			(start -0.12065 -0.2794)
			(end 0.12065 -0.2794)
			(stroke
				(width 0.1)
				(type default)
			)
			(layer "F.Fab")
		)
		(fp_line
			(start -0.12065 -0.305054)
			(end -0.12065 -0.2794)
			(stroke
				(width 0.1)
				(type default)
			)
			(layer "F.Fab")
		)
		(fp_line
			(start -0.67945 0.3048)
			(end -0.67945 -0.305054)
			(stroke
				(width 0.1)
				(type default)
			)
			(layer "F.Fab")
		)
		(fp_line
			(start -0.67945 -0.305054)
			(end -0.12065 -0.305054)
			(stroke
				(width 0.1)
				(type default)
			)
			(layer "F.Fab")
		)
		(pad "1" smd circle
			(at -0.40005 0 180)
			(size 0 0)
			(layers "F.Cu" "F.Mask" "F.Paste")
			(net "FAN_1_PWM_IL_R")
		)
		(pad "2" smd circle
			(at 0.40005 0 180)
			(size 0 0)
			(layers "F.Cu" "F.Mask" "F.Paste")
			(net "GND")
		)
	)
	(footprint ""
		(layer "F.Cu")
		(at 18.669 -103.124)
		(property "Reference" "R5314"
			(at 0 0 0)
			(layer "F.SilkS")
			(hide yes)
			(effects
				(font
					(size 1.27 1.27)
				)
			)
		)
		(property "Value" ""
			(at 0 0 0)
			(layer "F.Fab")
			(effects
				(font
					(size 1.27 1.27)
				)
			)
		)
		(duplicate_pad_numbers_are_jumpers no)
		(fp_line
			(start -0.7874 -0.4064)
			(end 0.7874 -0.4064)
			(stroke
				(width 0.1524)
				(type default)
			)
			(layer "F.SilkS")
		)
		(fp_line
			(start -0.7874 0.4064)
			(end -0.7874 -0.4064)
			(stroke
				(width 0.1524)
				(type default)
			)
			(layer "F.SilkS")
		)
		(fp_line
			(start 0.7874 -0.4064)
			(end 0.7874 0.4064)
			(stroke
				(width 0.1524)
				(type default)
			)
			(layer "F.SilkS")
		)
		(fp_line
			(start 0.7874 0.4064)
			(end -0.7874 0.4064)
			(stroke
				(width 0.1524)
				(type default)
			)
			(layer "F.SilkS")
		)
		(fp_line
			(start -0.67945 -0.305054)
			(end -0.12065 -0.305054)
			(stroke
				(width 0.1)
				(type default)
			)
			(layer "F.Fab")
		)
		(fp_line
			(start -0.67945 0.3048)
			(end -0.67945 -0.305054)
			(stroke
				(width 0.1)
				(type default)
			)
			(layer "F.Fab")
		)
		(fp_line
			(start -0.12065 -0.305054)
			(end -0.12065 -0.2794)
			(stroke
				(width 0.1)
				(type default)
			)
			(layer "F.Fab")
		)
		(fp_line
			(start -0.12065 -0.2794)
			(end 0.12065 -0.2794)
			(stroke
				(width 0.1)
				(type default)
			)
			(layer "F.Fab")
		)
		(fp_line
			(start -0.12065 0.2794)
			(end -0.12065 0.3048)
			(stroke
				(width 0.1)
				(type default)
			)
			(layer "F.Fab")
		)
		(fp_line
			(start -0.12065 0.3048)
			(end -0.67945 0.3048)
			(stroke
				(width 0.1)
				(type default)
			)
			(layer "F.Fab")
		)
		(fp_line
			(start 0.120396 0.2794)
			(end -0.12065 0.2794)
			(stroke
				(width 0.1)
				(type default)
			)
			(layer "F.Fab")
		)
		(fp_line
			(start 0.120396 0.3048)
			(end 0.120396 0.2794)
			(stroke
				(width 0.1)
				(type default)
			)
			(layer "F.Fab")
		)
		(fp_line
			(start 0.12065 -0.3048)
			(end 0.67945 -0.3048)
			(stroke
				(width 0.1)
				(type default)
			)
			(layer "F.Fab")
		)
		(fp_line
			(start 0.12065 -0.2794)
			(end 0.12065 -0.3048)
			(stroke
				(width 0.1)
				(type default)
			)
			(layer "F.Fab")
		)
		(fp_line
			(start 0.67945 -0.3048)
			(end 0.67945 0.3048)
			(stroke
				(width 0.1)
				(type default)
			)
			(layer "F.Fab")
		)
		(fp_line
			(start 0.67945 0.3048)
			(end 0.120396 0.3048)
			(stroke
				(width 0.1)
				(type default)
			)
			(layer "F.Fab")
		)
		(pad "1" smd rect
			(at -0.40005 0 180)
			(size 0.4572 0.508)
			(layers "F.Cu" "F.Mask" "F.Paste")
			(net "FAN_5_TACH_IL_R")
		)
		(pad "2" smd rect
			(at 0.40005 0 180)
			(size 0.4572 0.508)
			(layers "F.Cu" "F.Mask" "F.Paste")
			(net "FAN_5_TACH_IL")
		)
	)
	(footprint ""
		(layer "F.Cu")
		(at 14.351 -294.64 180)
		(property "Reference" "R5698"
			(at 0 0 180)
			(layer "F.SilkS")
			(hide yes)
			(effects
				(font
					(size 1.27 1.27)
				)
			)
		)
		(property "Value" ""
			(at 0 0 180)
			(layer "F.Fab")
			(effects
				(font
					(size 1.27 1.27)
				)
			)
		)
		(duplicate_pad_numbers_are_jumpers no)
		(fp_line
			(start 0.7874 0.4064)
			(end -0.7874 0.4064)
			(stroke
				(width 0.1524)
				(type default)
			)
			(layer "F.SilkS")
		)
		(fp_line
			(start 0.7874 -0.4064)
			(end 0.7874 0.4064)
			(stroke
				(width 0.1524)
				(type default)
			)
			(layer "F.SilkS")
		)
		(fp_line
			(start -0.7874 0.4064)
			(end -0.7874 -0.4064)
			(stroke
				(width 0.1524)
				(type default)
			)
			(layer "F.SilkS")
		)
		(fp_line
			(start -0.7874 -0.4064)
			(end 0.7874 -0.4064)
			(stroke
				(width 0.1524)
				(type default)
			)
			(layer "F.SilkS")
		)
		(fp_line
			(start 0.67945 0.3048)
			(end 0.120396 0.3048)
			(stroke
				(width 0.1)
				(type default)
			)
			(layer "F.Fab")
		)
		(fp_line
			(start 0.67945 -0.3048)
			(end 0.67945 0.3048)
			(stroke
				(width 0.1)
				(type default)
			)
			(layer "F.Fab")
		)
		(fp_line
			(start 0.12065 -0.2794)
			(end 0.12065 -0.3048)
			(stroke
				(width 0.1)
				(type default)
			)
			(layer "F.Fab")
		)
		(fp_line
			(start 0.12065 -0.3048)
			(end 0.67945 -0.3048)
			(stroke
				(width 0.1)
				(type default)
			)
			(layer "F.Fab")
		)
		(fp_line
			(start 0.120396 0.3048)
			(end 0.120396 0.2794)
			(stroke
				(width 0.1)
				(type default)
			)
			(layer "F.Fab")
		)
		(fp_line
			(start 0.120396 0.2794)
			(end -0.12065 0.2794)
			(stroke
				(width 0.1)
				(type default)
			)
			(layer "F.Fab")
		)
		(fp_line
			(start -0.12065 0.3048)
			(end -0.67945 0.3048)
			(stroke
				(width 0.1)
				(type default)
			)
			(layer "F.Fab")
		)
		(fp_line
			(start -0.12065 0.2794)
			(end -0.12065 0.3048)
			(stroke
				(width 0.1)
				(type default)
			)
			(layer "F.Fab")
		)
		(fp_line
			(start -0.12065 -0.2794)
			(end 0.12065 -0.2794)
			(stroke
				(width 0.1)
				(type default)
			)
			(layer "F.Fab")
		)
		(fp_line
			(start -0.12065 -0.305054)
			(end -0.12065 -0.2794)
			(stroke
				(width 0.1)
				(type default)
			)
			(layer "F.Fab")
		)
		(fp_line
			(start -0.67945 0.3048)
			(end -0.67945 -0.305054)
			(stroke
				(width 0.1)
				(type default)
			)
			(layer "F.Fab")
		)
		(fp_line
			(start -0.67945 -0.305054)
			(end -0.12065 -0.305054)
			(stroke
				(width 0.1)
				(type default)
			)
			(layer "F.Fab")
		)
		(pad "1" smd rect
			(at -0.40005 0)
			(size 0.4572 0.508)
			(layers "F.Cu" "F.Mask" "F.Paste")
			(net "P12V_LED_R_FAN7")
		)
		(pad "2" smd rect
			(at 0.40005 0)
			(size 0.4572 0.508)
			(layers "F.Cu" "F.Mask" "F.Paste")
			(net "P12V_LED_R1_FAN7")
		)
	)
	(footprint ""
		(layer "F.Cu")
		(at 23.241 -211.328 -90)
		(property "Reference" "R5512"
			(at 0 0 270)
			(layer "F.SilkS")
			(hide yes)
			(effects
				(font
					(size 1.27 1.27)
				)
			)
		)
		(property "Value" ""
			(at 0 0 270)
			(layer "F.Fab")
			(effects
				(font
					(size 1.27 1.27)
				)
			)
		)
		(duplicate_pad_numbers_are_jumpers no)
		(fp_line
			(start -0.7874 0.4064)
			(end -0.7874 -0.4064)
			(stroke
				(width 0.1524)
				(type default)
			)
			(layer "F.SilkS")
		)
		(fp_line
			(start 0.7874 0.4064)
			(end -0.7874 0.4064)
			(stroke
				(width 0.1524)
				(type default)
			)
			(layer "F.SilkS")
		)
		(fp_line
			(start -0.7874 -0.4064)
			(end 0.7874 -0.4064)
			(stroke
				(width 0.1524)
				(type default)
			)
			(layer "F.SilkS")
		)
		(fp_line
			(start 0.7874 -0.4064)
			(end 0.7874 0.4064)
			(stroke
				(width 0.1524)
				(type default)
			)
			(layer "F.SilkS")
		)
		(fp_line
			(start -0.67945 0.3048)
			(end -0.67945 -0.305054)
			(stroke
				(width 0.1)
				(type default)
			)
			(layer "F.Fab")
		)
		(fp_line
			(start -0.12065 0.3048)
			(end -0.67945 0.3048)
			(stroke
				(width 0.1)
				(type default)
			)
			(layer "F.Fab")
		)
		(fp_line
			(start 0.120396 0.3048)
			(end 0.120396 0.2794)
			(stroke
				(width 0.1)
				(type default)
			)
			(layer "F.Fab")
		)
		(fp_line
			(start 0.67945 0.3048)
			(end 0.120396 0.3048)
			(stroke
				(width 0.1)
				(type default)
			)
			(layer "F.Fab")
		)
		(fp_line
			(start -0.12065 0.2794)
			(end -0.12065 0.3048)
			(stroke
				(width 0.1)
				(type default)
			)
			(layer "F.Fab")
		)
		(fp_line
			(start 0.120396 0.2794)
			(end -0.12065 0.2794)
			(stroke
				(width 0.1)
				(type default)
			)
			(layer "F.Fab")
		)
		(fp_line
			(start -0.12065 -0.2794)
			(end 0.12065 -0.2794)
			(stroke
				(width 0.1)
				(type default)
			)
			(layer "F.Fab")
		)
		(fp_line
			(start 0.12065 -0.2794)
			(end 0.12065 -0.3048)
			(stroke
				(width 0.1)
				(type default)
			)
			(layer "F.Fab")
		)
		(fp_line
			(start 0.12065 -0.3048)
			(end 0.67945 -0.3048)
			(stroke
				(width 0.1)
				(type default)
			)
			(layer "F.Fab")
		)
		(fp_line
			(start 0.67945 -0.3048)
			(end 0.67945 0.3048)
			(stroke
				(width 0.1)
				(type default)
			)
			(layer "F.Fab")
		)
		(fp_line
			(start -0.67945 -0.305054)
			(end -0.12065 -0.305054)
			(stroke
				(width 0.1)
				(type default)
			)
			(layer "F.Fab")
		)
		(fp_line
			(start -0.12065 -0.305054)
			(end -0.12065 -0.2794)
			(stroke
				(width 0.1)
				(type default)
			)
			(layer "F.Fab")
		)
		(pad "1" smd circle
			(at -0.40005 0 270)
			(size 0 0)
			(layers "F.Cu" "F.Mask" "F.Paste")
			(net "P3V3_AUX")
		)
		(pad "2" smd circle
			(at 0.40005 0 270)
			(size 0 0)
			(layers "F.Cu" "F.Mask" "F.Paste")
			(net "FAN_1_PWM_BUF")
		)
	)
	(footprint ""
		(layer "F.Cu")
		(at 37.338 -299.339 180)
		(property "Reference" "R5186"
			(at 0 0 180)
			(layer "F.SilkS")
			(hide yes)
			(effects
				(font
					(size 1.27 1.27)
				)
			)
		)
		(property "Value" ""
			(at 0 0 180)
			(layer "F.Fab")
			(effects
				(font
					(size 1.27 1.27)
				)
			)
		)
		(duplicate_pad_numbers_are_jumpers no)
		(fp_line
			(start 0.7874 0.4064)
			(end -0.7874 0.4064)
			(stroke
				(width 0.1524)
				(type default)
			)
			(layer "F.SilkS")
		)
		(fp_line
			(start 0.7874 -0.4064)
			(end 0.7874 0.4064)
			(stroke
				(width 0.1524)
				(type default)
			)
			(layer "F.SilkS")
		)
		(fp_line
			(start -0.7874 0.4064)
			(end -0.7874 -0.4064)
			(stroke
				(width 0.1524)
				(type default)
			)
			(layer "F.SilkS")
		)
		(fp_line
			(start -0.7874 -0.4064)
			(end 0.7874 -0.4064)
			(stroke
				(width 0.1524)
				(type default)
			)
			(layer "F.SilkS")
		)
		(fp_line
			(start 0.67945 0.3048)
			(end 0.120396 0.3048)
			(stroke
				(width 0.1)
				(type default)
			)
			(layer "F.Fab")
		)
		(fp_line
			(start 0.67945 -0.3048)
			(end 0.67945 0.3048)
			(stroke
				(width 0.1)
				(type default)
			)
			(layer "F.Fab")
		)
		(fp_line
			(start 0.12065 -0.2794)
			(end 0.12065 -0.3048)
			(stroke
				(width 0.1)
				(type default)
			)
			(layer "F.Fab")
		)
		(fp_line
			(start 0.12065 -0.3048)
			(end 0.67945 -0.3048)
			(stroke
				(width 0.1)
				(type default)
			)
			(layer "F.Fab")
		)
		(fp_line
			(start 0.120396 0.3048)
			(end 0.120396 0.2794)
			(stroke
				(width 0.1)
				(type default)
			)
			(layer "F.Fab")
		)
		(fp_line
			(start 0.120396 0.2794)
			(end -0.12065 0.2794)
			(stroke
				(width 0.1)
				(type default)
			)
			(layer "F.Fab")
		)
		(fp_line
			(start -0.12065 0.3048)
			(end -0.67945 0.3048)
			(stroke
				(width 0.1)
				(type default)
			)
			(layer "F.Fab")
		)
		(fp_line
			(start -0.12065 0.2794)
			(end -0.12065 0.3048)
			(stroke
				(width 0.1)
				(type default)
			)
			(layer "F.Fab")
		)
		(fp_line
			(start -0.12065 -0.2794)
			(end 0.12065 -0.2794)
			(stroke
				(width 0.1)
				(type default)
			)
			(layer "F.Fab")
		)
		(fp_line
			(start -0.12065 -0.305054)
			(end -0.12065 -0.2794)
			(stroke
				(width 0.1)
				(type default)
			)
			(layer "F.Fab")
		)
		(fp_line
			(start -0.67945 0.3048)
			(end -0.67945 -0.305054)
			(stroke
				(width 0.1)
				(type default)
			)
			(layer "F.Fab")
		)
		(fp_line
			(start -0.67945 -0.305054)
			(end -0.12065 -0.305054)
			(stroke
				(width 0.1)
				(type default)
			)
			(layer "F.Fab")
		)
		(pad "1" smd circle
			(at -0.40005 0 180)
			(size 0 0)
			(layers "F.Cu" "F.Mask" "F.Paste")
			(net "FAN_0_PWM_IL_R")
		)
		(pad "2" smd circle
			(at 0.40005 0 180)
			(size 0 0)
			(layers "F.Cu" "F.Mask" "F.Paste")
			(net "FAN_0_PWM_IL")
		)
	)
	(footprint ""
		(layer "F.Cu")
		(at 30.353 -191.008 180)
		(property "Reference" "R4959"
			(at 0 0 180)
			(layer "F.SilkS")
			(hide yes)
			(effects
				(font
					(size 1.27 1.27)
				)
			)
		)
		(property "Value" ""
			(at 0 0 180)
			(layer "F.Fab")
			(effects
				(font
					(size 1.27 1.27)
				)
			)
		)
		(duplicate_pad_numbers_are_jumpers no)
		(fp_line
			(start 0.7874 0.4064)
			(end -0.7874 0.4064)
			(stroke
				(width 0.1524)
				(type default)
			)
			(layer "F.SilkS")
		)
		(fp_line
			(start 0.7874 -0.4064)
			(end 0.7874 0.4064)
			(stroke
				(width 0.1524)
				(type default)
			)
			(layer "F.SilkS")
		)
		(fp_line
			(start -0.7874 0.4064)
			(end -0.7874 -0.4064)
			(stroke
				(width 0.1524)
				(type default)
			)
			(layer "F.SilkS")
		)
		(fp_line
			(start -0.7874 -0.4064)
			(end 0.7874 -0.4064)
			(stroke
				(width 0.1524)
				(type default)
			)
			(layer "F.SilkS")
		)
		(fp_line
			(start 0.67945 0.3048)
			(end 0.120396 0.3048)
			(stroke
				(width 0.1)
				(type default)
			)
			(layer "F.Fab")
		)
		(fp_line
			(start 0.67945 -0.3048)
			(end 0.67945 0.3048)
			(stroke
				(width 0.1)
				(type default)
			)
			(layer "F.Fab")
		)
		(fp_line
			(start 0.12065 -0.2794)
			(end 0.12065 -0.3048)
			(stroke
				(width 0.1)
				(type default)
			)
			(layer "F.Fab")
		)
		(fp_line
			(start 0.12065 -0.3048)
			(end 0.67945 -0.3048)
			(stroke
				(width 0.1)
				(type default)
			)
			(layer "F.Fab")
		)
		(fp_line
			(start 0.120396 0.3048)
			(end 0.120396 0.2794)
			(stroke
				(width 0.1)
				(type default)
			)
			(layer "F.Fab")
		)
		(fp_line
			(start 0.120396 0.2794)
			(end -0.12065 0.2794)
			(stroke
				(width 0.1)
				(type default)
			)
			(layer "F.Fab")
		)
		(fp_line
			(start -0.12065 0.3048)
			(end -0.67945 0.3048)
			(stroke
				(width 0.1)
				(type default)
			)
			(layer "F.Fab")
		)
		(fp_line
			(start -0.12065 0.2794)
			(end -0.12065 0.3048)
			(stroke
				(width 0.1)
				(type default)
			)
			(layer "F.Fab")
		)
		(fp_line
			(start -0.12065 -0.2794)
			(end 0.12065 -0.2794)
			(stroke
				(width 0.1)
				(type default)
			)
			(layer "F.Fab")
		)
		(fp_line
			(start -0.12065 -0.305054)
			(end -0.12065 -0.2794)
			(stroke
				(width 0.1)
				(type default)
			)
			(layer "F.Fab")
		)
		(fp_line
			(start -0.67945 0.3048)
			(end -0.67945 -0.305054)
			(stroke
				(width 0.1)
				(type default)
			)
			(layer "F.Fab")
		)
		(fp_line
			(start -0.67945 -0.305054)
			(end -0.12065 -0.305054)
			(stroke
				(width 0.1)
				(type default)
			)
			(layer "F.Fab")
		)
		(pad "1" smd circle
			(at -0.40005 0 180)
			(size 0 0)
			(layers "F.Cu" "F.Mask" "F.Paste")
			(net "P52V_FAN_BUFF_EN_R")
		)
		(pad "2" smd circle
			(at 0.40005 0 180)
			(size 0 0)
			(layers "F.Cu" "F.Mask" "F.Paste")
			(net "P52V_FAN_EN")
		)
	)
	(footprint ""
		(layer "F.Cu")
		(at 50.165 -221.234 -90)
		(property "Reference" "C2025"
			(at 0 0 270)
			(layer "F.SilkS")
			(hide yes)
			(effects
				(font
					(size 1.27 1.27)
				)
			)
		)
		(property "Value" ""
			(at 0 0 270)
			(layer "F.Fab")
			(effects
				(font
					(size 1.27 1.27)
				)
			)
		)
		(duplicate_pad_numbers_are_jumpers no)
		(fp_line
			(start -0.7874 0.4064)
			(end -0.7874 -0.4064)
			(stroke
				(width 0.1524)
				(type default)
			)
			(layer "F.SilkS")
		)
		(fp_line
			(start 0.7874 0.4064)
			(end -0.7874 0.4064)
			(stroke
				(width 0.1524)
				(type default)
			)
			(layer "F.SilkS")
		)
		(fp_line
			(start -0.7874 -0.4064)
			(end 0.7874 -0.4064)
			(stroke
				(width 0.1524)
				(type default)
			)
			(layer "F.SilkS")
		)
		(fp_line
			(start 0.7874 -0.4064)
			(end 0.7874 0.4064)
			(stroke
				(width 0.1524)
				(type default)
			)
			(layer "F.SilkS")
		)
		(fp_line
			(start -0.6858 0.3048)
			(end -0.6858 -0.3048)
			(stroke
				(width 0.1)
				(type default)
			)
			(layer "F.Fab")
		)
		(fp_line
			(start -0.1016 0.3048)
			(end -0.6858 0.3048)
			(stroke
				(width 0.1)
				(type default)
			)
			(layer "F.Fab")
		)
		(fp_line
			(start 0.1016 0.3048)
			(end 0.1016 0.2794)
			(stroke
				(width 0.1)
				(type default)
			)
			(layer "F.Fab")
		)
		(fp_line
			(start 0.6858 0.3048)
			(end 0.1016 0.3048)
			(stroke
				(width 0.1)
				(type default)
			)
			(layer "F.Fab")
		)
		(fp_line
			(start -0.1016 0.2794)
			(end -0.1016 0.3048)
			(stroke
				(width 0.1)
				(type default)
			)
			(layer "F.Fab")
		)
		(fp_line
			(start 0.1016 0.2794)
			(end -0.1016 0.2794)
			(stroke
				(width 0.1)
				(type default)
			)
			(layer "F.Fab")
		)
		(fp_line
			(start -0.1016 -0.2794)
			(end 0.1016 -0.2794)
			(stroke
				(width 0.1)
				(type default)
			)
			(layer "F.Fab")
		)
		(fp_line
			(start 0.1016 -0.2794)
			(end 0.1016 -0.3048)
			(stroke
				(width 0.1)
				(type default)
			)
			(layer "F.Fab")
		)
		(fp_line
			(start -0.6858 -0.3048)
			(end -0.1016 -0.3048)
			(stroke
				(width 0.1)
				(type default)
			)
			(layer "F.Fab")
		)
		(fp_line
			(start -0.1016 -0.3048)
			(end -0.1016 -0.2794)
			(stroke
				(width 0.1)
				(type default)
			)
			(layer "F.Fab")
		)
		(fp_line
			(start 0.1016 -0.3048)
			(end 0.6858 -0.3048)
			(stroke
				(width 0.1)
				(type default)
			)
			(layer "F.Fab")
		)
		(fp_line
			(start 0.6858 -0.3048)
			(end 0.6858 0.3048)
			(stroke
				(width 0.1)
				(type default)
			)
			(layer "F.Fab")
		)
		(pad "1" smd rect
			(at -0.40005 0 90)
			(size 0.4572 0.508)
			(layers "F.Cu" "F.Mask" "F.Paste")
			(net "GND")
		)
		(pad "2" smd rect
			(at 0.40005 0 90)
			(size 0.4572 0.508)
			(layers "F.Cu" "F.Mask" "F.Paste")
			(net "P12V_LED_FAN1")
		)
	)
	(footprint ""
		(layer "F.Cu")
		(at 14.351 -204.47 180)
		(property "Reference" "R5374"
			(at 0 0 180)
			(layer "F.SilkS")
			(hide yes)
			(effects
				(font
					(size 1.27 1.27)
				)
			)
		)
		(property "Value" ""
			(at 0 0 180)
			(layer "F.Fab")
			(effects
				(font
					(size 1.27 1.27)
				)
			)
		)
		(duplicate_pad_numbers_are_jumpers no)
		(fp_line
			(start 0.7874 0.4064)
			(end -0.7874 0.4064)
			(stroke
				(width 0.1524)
				(type default)
			)
			(layer "F.SilkS")
		)
		(fp_line
			(start 0.7874 -0.4064)
			(end 0.7874 0.4064)
			(stroke
				(width 0.1524)
				(type default)
			)
			(layer "F.SilkS")
		)
		(fp_line
			(start -0.7874 0.4064)
			(end -0.7874 -0.4064)
			(stroke
				(width 0.1524)
				(type default)
			)
			(layer "F.SilkS")
		)
		(fp_line
			(start -0.7874 -0.4064)
			(end 0.7874 -0.4064)
			(stroke
				(width 0.1524)
				(type default)
			)
			(layer "F.SilkS")
		)
		(fp_line
			(start 0.67945 0.3048)
			(end 0.120396 0.3048)
			(stroke
				(width 0.1)
				(type default)
			)
			(layer "F.Fab")
		)
		(fp_line
			(start 0.67945 -0.3048)
			(end 0.67945 0.3048)
			(stroke
				(width 0.1)
				(type default)
			)
			(layer "F.Fab")
		)
		(fp_line
			(start 0.12065 -0.2794)
			(end 0.12065 -0.3048)
			(stroke
				(width 0.1)
				(type default)
			)
			(layer "F.Fab")
		)
		(fp_line
			(start 0.12065 -0.3048)
			(end 0.67945 -0.3048)
			(stroke
				(width 0.1)
				(type default)
			)
			(layer "F.Fab")
		)
		(fp_line
			(start 0.120396 0.3048)
			(end 0.120396 0.2794)
			(stroke
				(width 0.1)
				(type default)
			)
			(layer "F.Fab")
		)
		(fp_line
			(start 0.120396 0.2794)
			(end -0.12065 0.2794)
			(stroke
				(width 0.1)
				(type default)
			)
			(layer "F.Fab")
		)
		(fp_line
			(start -0.12065 0.3048)
			(end -0.67945 0.3048)
			(stroke
				(width 0.1)
				(type default)
			)
			(layer "F.Fab")
		)
		(fp_line
			(start -0.12065 0.2794)
			(end -0.12065 0.3048)
			(stroke
				(width 0.1)
				(type default)
			)
			(layer "F.Fab")
		)
		(fp_line
			(start -0.12065 -0.2794)
			(end 0.12065 -0.2794)
			(stroke
				(width 0.1)
				(type default)
			)
			(layer "F.Fab")
		)
		(fp_line
			(start -0.12065 -0.305054)
			(end -0.12065 -0.2794)
			(stroke
				(width 0.1)
				(type default)
			)
			(layer "F.Fab")
		)
		(fp_line
			(start -0.67945 0.3048)
			(end -0.67945 -0.305054)
			(stroke
				(width 0.1)
				(type default)
			)
			(layer "F.Fab")
		)
		(fp_line
			(start -0.67945 -0.305054)
			(end -0.12065 -0.305054)
			(stroke
				(width 0.1)
				(type default)
			)
			(layer "F.Fab")
		)
		(pad "1" smd rect
			(at -0.40005 0)
			(size 0.4572 0.508)
			(layers "F.Cu" "F.Mask" "F.Paste")
			(net "FAN_6_FAIL_LED_R_N")
		)
		(pad "2" smd rect
			(at 0.40005 0)
			(size 0.4572 0.508)
			(layers "F.Cu" "F.Mask" "F.Paste")
			(net "FAN_6_FAIL_R_LED_N")
		)
	)
	(footprint ""
		(layer "F.Cu")
		(at 42.037 -191.516)
		(property "Reference" "C1953"
			(at 0 0 0)
			(layer "F.SilkS")
			(hide yes)
			(effects
				(font
					(size 1.27 1.27)
				)
			)
		)
		(property "Value" ""
			(at 0 0 0)
			(layer "F.Fab")
			(effects
				(font
					(size 1.27 1.27)
				)
			)
		)
		(duplicate_pad_numbers_are_jumpers no)
		(fp_line
			(start -0.7874 -0.4064)
			(end 0.7874 -0.4064)
			(stroke
				(width 0.1524)
				(type default)
			)
			(layer "F.SilkS")
		)
		(fp_line
			(start -0.7874 0.4064)
			(end -0.7874 -0.4064)
			(stroke
				(width 0.1524)
				(type default)
			)
			(layer "F.SilkS")
		)
		(fp_line
			(start 0.7874 -0.4064)
			(end 0.7874 0.4064)
			(stroke
				(width 0.1524)
				(type default)
			)
			(layer "F.SilkS")
		)
		(fp_line
			(start 0.7874 0.4064)
			(end -0.7874 0.4064)
			(stroke
				(width 0.1524)
				(type default)
			)
			(layer "F.SilkS")
		)
		(fp_line
			(start -0.67945 -0.305054)
			(end -0.12065 -0.305054)
			(stroke
				(width 0.1)
				(type default)
			)
			(layer "F.Fab")
		)
		(fp_line
			(start -0.67945 0.3048)
			(end -0.67945 -0.305054)
			(stroke
				(width 0.1)
				(type default)
			)
			(layer "F.Fab")
		)
		(fp_line
			(start -0.12065 -0.305054)
			(end -0.12065 -0.2794)
			(stroke
				(width 0.1)
				(type default)
			)
			(layer "F.Fab")
		)
		(fp_line
			(start -0.12065 -0.2794)
			(end 0.12065 -0.2794)
			(stroke
				(width 0.1)
				(type default)
			)
			(layer "F.Fab")
		)
		(fp_line
			(start -0.12065 0.2794)
			(end -0.12065 0.3048)
			(stroke
				(width 0.1)
				(type default)
			)
			(layer "F.Fab")
		)
		(fp_line
			(start -0.12065 0.3048)
			(end -0.67945 0.3048)
			(stroke
				(width 0.1)
				(type default)
			)
			(layer "F.Fab")
		)
		(fp_line
			(start 0.120396 0.2794)
			(end -0.12065 0.2794)
			(stroke
				(width 0.1)
				(type default)
			)
			(layer "F.Fab")
		)
		(fp_line
			(start 0.120396 0.3048)
			(end 0.120396 0.2794)
			(stroke
				(width 0.1)
				(type default)
			)
			(layer "F.Fab")
		)
		(fp_line
			(start 0.12065 -0.3048)
			(end 0.67945 -0.3048)
			(stroke
				(width 0.1)
				(type default)
			)
			(layer "F.Fab")
		)
		(fp_line
			(start 0.12065 -0.2794)
			(end 0.12065 -0.3048)
			(stroke
				(width 0.1)
				(type default)
			)
			(layer "F.Fab")
		)
		(fp_line
			(start 0.67945 -0.3048)
			(end 0.67945 0.3048)
			(stroke
				(width 0.1)
				(type default)
			)
			(layer "F.Fab")
		)
		(fp_line
			(start 0.67945 0.3048)
			(end 0.120396 0.3048)
			(stroke
				(width 0.1)
				(type default)
			)
			(layer "F.Fab")
		)
		(pad "1" smd circle
			(at -0.40005 0)
			(size 0 0)
			(layers "F.Cu" "F.Mask" "F.Paste")
			(net "P3V3_AUX")
		)
		(pad "2" smd circle
			(at 0.40005 0)
			(size 0 0)
			(layers "F.Cu" "F.Mask" "F.Paste")
			(net "GND")
		)
	)
	(footprint ""
		(layer "F.Cu")
		(at 17.907 -167.005 180)
		(property "Reference" "R5498"
			(at 0 0 180)
			(layer "F.SilkS")
			(hide yes)
			(effects
				(font
					(size 1.27 1.27)
				)
			)
		)
		(property "Value" ""
			(at 0 0 180)
			(layer "F.Fab")
			(effects
				(font
					(size 1.27 1.27)
				)
			)
		)
		(duplicate_pad_numbers_are_jumpers no)
		(fp_line
			(start 0.7874 0.4064)
			(end -0.7874 0.4064)
			(stroke
				(width 0.1524)
				(type default)
			)
			(layer "F.SilkS")
		)
		(fp_line
			(start 0.7874 -0.4064)
			(end 0.7874 0.4064)
			(stroke
				(width 0.1524)
				(type default)
			)
			(layer "F.SilkS")
		)
		(fp_line
			(start -0.7874 0.4064)
			(end -0.7874 -0.4064)
			(stroke
				(width 0.1524)
				(type default)
			)
			(layer "F.SilkS")
		)
		(fp_line
			(start -0.7874 -0.4064)
			(end 0.7874 -0.4064)
			(stroke
				(width 0.1524)
				(type default)
			)
			(layer "F.SilkS")
		)
		(fp_line
			(start 0.67945 0.3048)
			(end 0.120396 0.3048)
			(stroke
				(width 0.1)
				(type default)
			)
			(layer "F.Fab")
		)
		(fp_line
			(start 0.67945 -0.3048)
			(end 0.67945 0.3048)
			(stroke
				(width 0.1)
				(type default)
			)
			(layer "F.Fab")
		)
		(fp_line
			(start 0.12065 -0.2794)
			(end 0.12065 -0.3048)
			(stroke
				(width 0.1)
				(type default)
			)
			(layer "F.Fab")
		)
		(fp_line
			(start 0.12065 -0.3048)
			(end 0.67945 -0.3048)
			(stroke
				(width 0.1)
				(type default)
			)
			(layer "F.Fab")
		)
		(fp_line
			(start 0.120396 0.3048)
			(end 0.120396 0.2794)
			(stroke
				(width 0.1)
				(type default)
			)
			(layer "F.Fab")
		)
		(fp_line
			(start 0.120396 0.2794)
			(end -0.12065 0.2794)
			(stroke
				(width 0.1)
				(type default)
			)
			(layer "F.Fab")
		)
		(fp_line
			(start -0.12065 0.3048)
			(end -0.67945 0.3048)
			(stroke
				(width 0.1)
				(type default)
			)
			(layer "F.Fab")
		)
		(fp_line
			(start -0.12065 0.2794)
			(end -0.12065 0.3048)
			(stroke
				(width 0.1)
				(type default)
			)
			(layer "F.Fab")
		)
		(fp_line
			(start -0.12065 -0.2794)
			(end 0.12065 -0.2794)
			(stroke
				(width 0.1)
				(type default)
			)
			(layer "F.Fab")
		)
		(fp_line
			(start -0.12065 -0.305054)
			(end -0.12065 -0.2794)
			(stroke
				(width 0.1)
				(type default)
			)
			(layer "F.Fab")
		)
		(fp_line
			(start -0.67945 0.3048)
			(end -0.67945 -0.305054)
			(stroke
				(width 0.1)
				(type default)
			)
			(layer "F.Fab")
		)
		(fp_line
			(start -0.67945 -0.305054)
			(end -0.12065 -0.305054)
			(stroke
				(width 0.1)
				(type default)
			)
			(layer "F.Fab")
		)
		(pad "1" smd circle
			(at -0.40005 0 180)
			(size 0 0)
			(layers "F.Cu" "F.Mask" "F.Paste")
			(net "FAN_3_PRESENT_R_N")
		)
		(pad "2" smd circle
			(at 0.40005 0 180)
			(size 0 0)
			(layers "F.Cu" "F.Mask" "F.Paste")
			(net "FAN_3_PRESENT_N")
		)
	)
	(footprint ""
		(layer "F.Cu")
		(at 17.907 -173.99 180)
		(property "Reference" "R5502"
			(at 0 0 180)
			(layer "F.SilkS")
			(hide yes)
			(effects
				(font
					(size 1.27 1.27)
				)
			)
		)
		(property "Value" ""
			(at 0 0 180)
			(layer "F.Fab")
			(effects
				(font
					(size 1.27 1.27)
				)
			)
		)
		(duplicate_pad_numbers_are_jumpers no)
		(fp_line
			(start 0.7874 0.4064)
			(end -0.7874 0.4064)
			(stroke
				(width 0.1524)
				(type default)
			)
			(layer "F.SilkS")
		)
		(fp_line
			(start 0.7874 -0.4064)
			(end 0.7874 0.4064)
			(stroke
				(width 0.1524)
				(type default)
			)
			(layer "F.SilkS")
		)
		(fp_line
			(start -0.7874 0.4064)
			(end -0.7874 -0.4064)
			(stroke
				(width 0.1524)
				(type default)
			)
			(layer "F.SilkS")
		)
		(fp_line
			(start -0.7874 -0.4064)
			(end 0.7874 -0.4064)
			(stroke
				(width 0.1524)
				(type default)
			)
			(layer "F.SilkS")
		)
		(fp_line
			(start 0.67945 0.3048)
			(end 0.120396 0.3048)
			(stroke
				(width 0.1)
				(type default)
			)
			(layer "F.Fab")
		)
		(fp_line
			(start 0.67945 -0.3048)
			(end 0.67945 0.3048)
			(stroke
				(width 0.1)
				(type default)
			)
			(layer "F.Fab")
		)
		(fp_line
			(start 0.12065 -0.2794)
			(end 0.12065 -0.3048)
			(stroke
				(width 0.1)
				(type default)
			)
			(layer "F.Fab")
		)
		(fp_line
			(start 0.12065 -0.3048)
			(end 0.67945 -0.3048)
			(stroke
				(width 0.1)
				(type default)
			)
			(layer "F.Fab")
		)
		(fp_line
			(start 0.120396 0.3048)
			(end 0.120396 0.2794)
			(stroke
				(width 0.1)
				(type default)
			)
			(layer "F.Fab")
		)
		(fp_line
			(start 0.120396 0.2794)
			(end -0.12065 0.2794)
			(stroke
				(width 0.1)
				(type default)
			)
			(layer "F.Fab")
		)
		(fp_line
			(start -0.12065 0.3048)
			(end -0.67945 0.3048)
			(stroke
				(width 0.1)
				(type default)
			)
			(layer "F.Fab")
		)
		(fp_line
			(start -0.12065 0.2794)
			(end -0.12065 0.3048)
			(stroke
				(width 0.1)
				(type default)
			)
			(layer "F.Fab")
		)
		(fp_line
			(start -0.12065 -0.2794)
			(end 0.12065 -0.2794)
			(stroke
				(width 0.1)
				(type default)
			)
			(layer "F.Fab")
		)
		(fp_line
			(start -0.12065 -0.305054)
			(end -0.12065 -0.2794)
			(stroke
				(width 0.1)
				(type default)
			)
			(layer "F.Fab")
		)
		(fp_line
			(start -0.67945 0.3048)
			(end -0.67945 -0.305054)
			(stroke
				(width 0.1)
				(type default)
			)
			(layer "F.Fab")
		)
		(fp_line
			(start -0.67945 -0.305054)
			(end -0.12065 -0.305054)
			(stroke
				(width 0.1)
				(type default)
			)
			(layer "F.Fab")
		)
		(pad "1" smd circle
			(at -0.40005 0 180)
			(size 0 0)
			(layers "F.Cu" "F.Mask" "F.Paste")
			(net "FAN_7_PRESENT_R_N")
		)
		(pad "2" smd circle
			(at 0.40005 0 180)
			(size 0 0)
			(layers "F.Cu" "F.Mask" "F.Paste")
			(net "FAN_7_PRESENT_N")
		)
	)
	(footprint ""
		(layer "F.Cu")
		(at 36.195 -16.256)
		(property "Reference" "D143"
			(at 2.286 -0.86233 0)
			(unlocked yes)
			(layer "F.SilkS")
			(effects
				(font
					(size 0.7874 0.5842)
					(thickness 0.1524)
				)
				(justify left)
			)
		)
		(property "Value" ""
			(at 0 0 0)
			(layer "F.Fab")
			(effects
				(font
					(size 1.27 1.27)
				)
			)
		)
		(duplicate_pad_numbers_are_jumpers no)
		(fp_line
			(start -1.651 -0.7112)
			(end 2.032 -0.7112)
			(stroke
				(width 0.1524)
				(type default)
			)
			(layer "F.SilkS")
		)
		(fp_line
			(start -1.651 0.7112)
			(end -1.651 -0.7112)
			(stroke
				(width 0.1524)
				(type default)
			)
			(layer "F.SilkS")
		)
		(fp_line
			(start -0.299974 -0.500126)
			(end -0.299974 0.500126)
			(stroke
				(width 0.1524)
				(type default)
			)
			(layer "F.SilkS")
		)
		(fp_line
			(start -0.299974 0.500126)
			(end 0.199898 0)
			(stroke
				(width 0.1524)
				(type default)
			)
			(layer "F.SilkS")
		)
		(fp_line
			(start 0.199898 0)
			(end -0.299974 -0.500126)
			(stroke
				(width 0.1524)
				(type default)
			)
			(layer "F.SilkS")
		)
		(fp_line
			(start 0.299974 -0.500126)
			(end 0.299974 0.500126)
			(stroke
				(width 0.1524)
				(type default)
			)
			(layer "F.SilkS")
		)
		(fp_line
			(start 1.651 -0.6858)
			(end 1.651 0.6858)
			(stroke
				(width 0.1524)
				(type default)
			)
			(layer "F.SilkS")
		)
		(fp_line
			(start 1.778 0.6858)
			(end 1.778 -0.6858)
			(stroke
				(width 0.1524)
				(type default)
			)
			(layer "F.SilkS")
		)
		(fp_line
			(start 1.905 -0.6858)
			(end 1.905 0.6858)
			(stroke
				(width 0.1524)
				(type default)
			)
			(layer "F.SilkS")
		)
		(fp_line
			(start 2.032 -0.7112)
			(end 2.032 0.7112)
			(stroke
				(width 0.1524)
				(type default)
			)
			(layer "F.SilkS")
		)
		(fp_line
			(start 2.032 0.7112)
			(end -1.651 0.7112)
			(stroke
				(width 0.1524)
				(type default)
			)
			(layer "F.SilkS")
		)
		(fp_line
			(start -1.35001 -0.225044)
			(end -0.899922 -0.225044)
			(stroke
				(width 0.1)
				(type default)
			)
			(layer "F.Fab")
		)
		(fp_line
			(start -1.35001 0.175006)
			(end -1.35001 -0.225044)
			(stroke
				(width 0.1)
				(type default)
			)
			(layer "F.Fab")
		)
		(fp_line
			(start -0.899922 -0.700024)
			(end 0.899922 -0.700024)
			(stroke
				(width 0.1)
				(type default)
			)
			(layer "F.Fab")
		)
		(fp_line
			(start -0.899922 -0.225044)
			(end -0.899922 -0.700024)
			(stroke
				(width 0.1)
				(type default)
			)
			(layer "F.Fab")
		)
		(fp_line
			(start -0.899922 0.175006)
			(end -1.35001 0.175006)
			(stroke
				(width 0.1)
				(type default)
			)
			(layer "F.Fab")
		)
		(fp_line
			(start -0.899922 0.700024)
			(end -0.899922 0.175006)
			(stroke
				(width 0.1)
				(type default)
			)
			(layer "F.Fab")
		)
		(fp_line
			(start -0.299974 -0.500126)
			(end -0.299974 0.500126)
			(stroke
				(width 0.1)
				(type default)
			)
			(layer "F.Fab")
		)
		(fp_line
			(start -0.299974 0.500126)
			(end 0.199898 0)
			(stroke
				(width 0.1)
				(type default)
			)
			(layer "F.Fab")
		)
		(fp_line
			(start 0.199898 0)
			(end -0.299974 -0.500126)
			(stroke
				(width 0.1)
				(type default)
			)
			(layer "F.Fab")
		)
		(fp_line
			(start 0.299974 -0.500126)
			(end 0.299974 0.500126)
			(stroke
				(width 0.1)
				(type default)
			)
			(layer "F.Fab")
		)
		(fp_line
			(start 0.899922 -0.700024)
			(end 0.899922 -0.225044)
			(stroke
				(width 0.1)
				(type default)
			)
			(layer "F.Fab")
		)
		(fp_line
			(start 0.899922 -0.225044)
			(end 1.35001 -0.225044)
			(stroke
				(width 0.1)
				(type default)
			)
			(layer "F.Fab")
		)
		(fp_line
			(start 0.899922 0.175006)
			(end 0.899922 0.700024)
			(stroke
				(width 0.1)
				(type default)
			)
			(layer "F.Fab")
		)
		(fp_line
			(start 0.899922 0.700024)
			(end -0.899922 0.700024)
			(stroke
				(width 0.1)
				(type default)
			)
			(layer "F.Fab")
		)
		(fp_line
			(start 1.35001 -0.225044)
			(end 1.35001 0.175006)
			(stroke
				(width 0.1)
				(type default)
			)
			(layer "F.Fab")
		)
		(fp_line
			(start 1.35001 0.175006)
			(end 0.899922 0.175006)
			(stroke
				(width 0.1)
				(type default)
			)
			(layer "F.Fab")
		)
		(fp_text user "+"
			(at -1.37795 0.381 270)
			(unlocked yes)
			(layer "F.SilkS")
			(effects
				(font
					(size 1.905 1.4224)
					(thickness 0.1524)
				)
				(justify left)
			)
		)
		(fp_text user "-"
			(at 1.905 -0.22225 0)
			(unlocked yes)
			(layer "F.SilkS")
			(effects
				(font
					(size 1.905 1.4224)
					(thickness 0.1524)
				)
				(justify left)
			)
		)
		(fp_text user "+"
			(at -2.794 -0.19685 0)
			(unlocked yes)
			(layer "F.Fab")
			(effects
				(font
					(size 1.905 1.4224)
					(thickness 0.1524)
				)
				(justify left)
			)
		)
		(fp_text user "-"
			(at 1.8288 -0.24765 0)
			(unlocked yes)
			(layer "F.Fab")
			(effects
				(font
					(size 1.905 1.4224)
					(thickness 0.1524)
				)
				(justify left)
			)
		)
		(pad "1" smd rect
			(at -1.0922 0 180)
			(size 0.8128 0.8636)
			(layers "F.Cu" "F.Mask" "F.Paste")
			(net "FAN_3_TACH_OL_R")
		)
		(pad "2" smd rect
			(at 1.0922 0)
			(size 0.8128 0.8636)
			(layers "F.Cu" "F.Mask" "F.Paste")
			(net "FAN_3_TACH_OL_D")
		)
	)
	(footprint ""
		(layer "F.Cu")
		(at 5.842 -135.255 -90)
		(property "Reference" "R5569"
			(at 0 0 270)
			(layer "F.SilkS")
			(hide yes)
			(effects
				(font
					(size 1.27 1.27)
				)
			)
		)
		(property "Value" ""
			(at 0 0 270)
			(layer "F.Fab")
			(effects
				(font
					(size 1.27 1.27)
				)
			)
		)
		(duplicate_pad_numbers_are_jumpers no)
		(fp_line
			(start -0.7874 0.4064)
			(end -0.7874 -0.4064)
			(stroke
				(width 0.1524)
				(type default)
			)
			(layer "F.SilkS")
		)
		(fp_line
			(start 0.7874 0.4064)
			(end -0.7874 0.4064)
			(stroke
				(width 0.1524)
				(type default)
			)
			(layer "F.SilkS")
		)
		(fp_line
			(start -0.7874 -0.4064)
			(end 0.7874 -0.4064)
			(stroke
				(width 0.1524)
				(type default)
			)
			(layer "F.SilkS")
		)
		(fp_line
			(start 0.7874 -0.4064)
			(end 0.7874 0.4064)
			(stroke
				(width 0.1524)
				(type default)
			)
			(layer "F.SilkS")
		)
		(fp_line
			(start -0.67945 0.3048)
			(end -0.67945 -0.305054)
			(stroke
				(width 0.1)
				(type default)
			)
			(layer "F.Fab")
		)
		(fp_line
			(start -0.12065 0.3048)
			(end -0.67945 0.3048)
			(stroke
				(width 0.1)
				(type default)
			)
			(layer "F.Fab")
		)
		(fp_line
			(start 0.120396 0.3048)
			(end 0.120396 0.2794)
			(stroke
				(width 0.1)
				(type default)
			)
			(layer "F.Fab")
		)
		(fp_line
			(start 0.67945 0.3048)
			(end 0.120396 0.3048)
			(stroke
				(width 0.1)
				(type default)
			)
			(layer "F.Fab")
		)
		(fp_line
			(start -0.12065 0.2794)
			(end -0.12065 0.3048)
			(stroke
				(width 0.1)
				(type default)
			)
			(layer "F.Fab")
		)
		(fp_line
			(start 0.120396 0.2794)
			(end -0.12065 0.2794)
			(stroke
				(width 0.1)
				(type default)
			)
			(layer "F.Fab")
		)
		(fp_line
			(start -0.12065 -0.2794)
			(end 0.12065 -0.2794)
			(stroke
				(width 0.1)
				(type default)
			)
			(layer "F.Fab")
		)
		(fp_line
			(start 0.12065 -0.2794)
			(end 0.12065 -0.3048)
			(stroke
				(width 0.1)
				(type default)
			)
			(layer "F.Fab")
		)
		(fp_line
			(start 0.12065 -0.3048)
			(end 0.67945 -0.3048)
			(stroke
				(width 0.1)
				(type default)
			)
			(layer "F.Fab")
		)
		(fp_line
			(start 0.67945 -0.3048)
			(end 0.67945 0.3048)
			(stroke
				(width 0.1)
				(type default)
			)
			(layer "F.Fab")
		)
		(fp_line
			(start -0.67945 -0.305054)
			(end -0.12065 -0.305054)
			(stroke
				(width 0.1)
				(type default)
			)
			(layer "F.Fab")
		)
		(fp_line
			(start -0.12065 -0.305054)
			(end -0.12065 -0.2794)
			(stroke
				(width 0.1)
				(type default)
			)
			(layer "F.Fab")
		)
		(pad "1" smd circle
			(at -0.40005 0 270)
			(size 0 0)
			(layers "F.Cu" "F.Mask" "F.Paste")
			(net "SMB_PDBV_FAN_SCL")
		)
		(pad "2" smd circle
			(at 0.40005 0 270)
			(size 0 0)
			(layers "F.Cu" "F.Mask" "F.Paste")
			(net "SMB_PDBV_FAN_R_U404_SCL")
		)
	)
	(footprint ""
		(layer "F.Cu")
		(at 42.037 -181.102)
		(property "Reference" "R518"
			(at 0 0 0)
			(layer "F.SilkS")
			(hide yes)
			(effects
				(font
					(size 1.27 1.27)
				)
			)
		)
		(property "Value" ""
			(at 0 0 0)
			(layer "F.Fab")
			(effects
				(font
					(size 1.27 1.27)
				)
			)
		)
		(duplicate_pad_numbers_are_jumpers no)
		(fp_line
			(start -0.7874 -0.4064)
			(end 0.7874 -0.4064)
			(stroke
				(width 0.1524)
				(type default)
			)
			(layer "F.SilkS")
		)
		(fp_line
			(start -0.7874 0.4064)
			(end -0.7874 -0.4064)
			(stroke
				(width 0.1524)
				(type default)
			)
			(layer "F.SilkS")
		)
		(fp_line
			(start 0.7874 -0.4064)
			(end 0.7874 0.4064)
			(stroke
				(width 0.1524)
				(type default)
			)
			(layer "F.SilkS")
		)
		(fp_line
			(start 0.7874 0.4064)
			(end -0.7874 0.4064)
			(stroke
				(width 0.1524)
				(type default)
			)
			(layer "F.SilkS")
		)
		(fp_line
			(start -0.67945 -0.305054)
			(end -0.12065 -0.305054)
			(stroke
				(width 0.1)
				(type default)
			)
			(layer "F.Fab")
		)
		(fp_line
			(start -0.67945 0.3048)
			(end -0.67945 -0.305054)
			(stroke
				(width 0.1)
				(type default)
			)
			(layer "F.Fab")
		)
		(fp_line
			(start -0.12065 -0.305054)
			(end -0.12065 -0.2794)
			(stroke
				(width 0.1)
				(type default)
			)
			(layer "F.Fab")
		)
		(fp_line
			(start -0.12065 -0.2794)
			(end 0.12065 -0.2794)
			(stroke
				(width 0.1)
				(type default)
			)
			(layer "F.Fab")
		)
		(fp_line
			(start -0.12065 0.2794)
			(end -0.12065 0.3048)
			(stroke
				(width 0.1)
				(type default)
			)
			(layer "F.Fab")
		)
		(fp_line
			(start -0.12065 0.3048)
			(end -0.67945 0.3048)
			(stroke
				(width 0.1)
				(type default)
			)
			(layer "F.Fab")
		)
		(fp_line
			(start 0.120396 0.2794)
			(end -0.12065 0.2794)
			(stroke
				(width 0.1)
				(type default)
			)
			(layer "F.Fab")
		)
		(fp_line
			(start 0.120396 0.3048)
			(end 0.120396 0.2794)
			(stroke
				(width 0.1)
				(type default)
			)
			(layer "F.Fab")
		)
		(fp_line
			(start 0.12065 -0.3048)
			(end 0.67945 -0.3048)
			(stroke
				(width 0.1)
				(type default)
			)
			(layer "F.Fab")
		)
		(fp_line
			(start 0.12065 -0.2794)
			(end 0.12065 -0.3048)
			(stroke
				(width 0.1)
				(type default)
			)
			(layer "F.Fab")
		)
		(fp_line
			(start 0.67945 -0.3048)
			(end 0.67945 0.3048)
			(stroke
				(width 0.1)
				(type default)
			)
			(layer "F.Fab")
		)
		(fp_line
			(start 0.67945 0.3048)
			(end 0.120396 0.3048)
			(stroke
				(width 0.1)
				(type default)
			)
			(layer "F.Fab")
		)
		(pad "1" smd circle
			(at -0.40005 0)
			(size 0 0)
			(layers "F.Cu" "F.Mask" "F.Paste")
			(net "PD_FAN_BUFF_INPUT_U336E")
		)
		(pad "2" smd circle
			(at 0.40005 0)
			(size 0 0)
			(layers "F.Cu" "F.Mask" "F.Paste")
			(net "P3V3_AUX")
		)
	)
	(footprint ""
		(layer "F.Cu")
		(at 18.679922 -101.950012 180)
		(property "Reference" "D249"
			(at 1.407922 -1.646682 0)
			(unlocked yes)
			(layer "F.SilkS")
			(effects
				(font
					(size 0.7874 0.5842)
					(thickness 0.1524)
				)
				(justify left)
			)
		)
		(property "Value" ""
			(at 0 0 180)
			(layer "F.Fab")
			(effects
				(font
					(size 1.27 1.27)
				)
			)
		)
		(duplicate_pad_numbers_are_jumpers no)
		(fp_line
			(start 0.94488 0.450088)
			(end 0.94488 -0.450088)
			(stroke
				(width 0.1524)
				(type default)
			)
			(layer "F.SilkS")
		)
		(fp_line
			(start 0.94488 -0.450088)
			(end -0.854964 -0.450088)
			(stroke
				(width 0.1524)
				(type default)
			)
			(layer "F.SilkS")
		)
		(fp_line
			(start 0.870458 -0.2794)
			(end 0.845058 0.4064)
			(stroke
				(width 0.1524)
				(type default)
			)
			(layer "F.SilkS")
		)
		(fp_line
			(start 0.845058 0.4064)
			(end 0.845058 -0.381)
			(stroke
				(width 0.1524)
				(type default)
			)
			(layer "F.SilkS")
		)
		(fp_line
			(start -0.854964 0.450088)
			(end 0.925068 0.450088)
			(stroke
				(width 0.1524)
				(type default)
			)
			(layer "F.SilkS")
		)
		(fp_line
			(start -0.854964 -0.450088)
			(end -0.854964 0.450088)
			(stroke
				(width 0.1524)
				(type default)
			)
			(layer "F.SilkS")
		)
		(fp_line
			(start 0.54991 0.350012)
			(end 0.54991 -0.350012)
			(stroke
				(width 0.1)
				(type default)
			)
			(layer "F.Fab")
		)
		(fp_line
			(start 0.54991 -0.350012)
			(end -0.54991 -0.350012)
			(stroke
				(width 0.1)
				(type default)
			)
			(layer "F.Fab")
		)
		(fp_line
			(start -0.54991 0.350012)
			(end 0.54991 0.350012)
			(stroke
				(width 0.1)
				(type default)
			)
			(layer "F.Fab")
		)
		(fp_line
			(start -0.54991 -0.350012)
			(end -0.54991 0.350012)
			(stroke
				(width 0.1)
				(type default)
			)
			(layer "F.Fab")
		)
		(fp_text user "-"
			(at 1.915922 -0.635762 0)
			(unlocked yes)
			(layer "F.SilkS")
			(effects
				(font
					(size 1.905 1.4224)
					(thickness 0.1524)
				)
				(justify left)
			)
		)
		(fp_text user "+"
			(at -0.751078 0.761238 0)
			(unlocked yes)
			(layer "F.SilkS")
			(effects
				(font
					(size 1.905 1.4224)
					(thickness 0.1524)
				)
				(justify left)
			)
		)
		(fp_text user "-"
			(at 2.48539 0.239014 0)
			(unlocked yes)
			(layer "F.Fab")
			(effects
				(font
					(size 1.905 1.4224)
					(thickness 0.1524)
				)
				(justify left)
			)
		)
		(fp_text user "+"
			(at -0.808228 0.239014 0)
			(unlocked yes)
			(layer "F.Fab")
			(effects
				(font
					(size 1.905 1.4224)
					(thickness 0.1524)
				)
				(justify left)
			)
		)
		(pad "A" smd rect
			(at -0.424942 0 180)
			(size 0.5588 0.6096)
			(layers "F.Cu" "F.Mask" "F.Paste")
			(net "GND")
		)
		(pad "C" smd rect
			(at 0.424942 0)
			(size 0.5588 0.6096)
			(layers "F.Cu" "F.Mask" "F.Paste")
			(net "FAN_5_PWM_OL_R")
		)
	)
	(footprint ""
		(layer "F.Cu")
		(at 9.144 -184.785 180)
		(property "Reference" "R5486"
			(at 0 0 180)
			(layer "F.SilkS")
			(hide yes)
			(effects
				(font
					(size 1.27 1.27)
				)
			)
		)
		(property "Value" ""
			(at 0 0 180)
			(layer "F.Fab")
			(effects
				(font
					(size 1.27 1.27)
				)
			)
		)
		(duplicate_pad_numbers_are_jumpers no)
		(fp_line
			(start 0.7874 0.4064)
			(end -0.7874 0.4064)
			(stroke
				(width 0.1524)
				(type default)
			)
			(layer "F.SilkS")
		)
		(fp_line
			(start 0.7874 -0.4064)
			(end 0.7874 0.4064)
			(stroke
				(width 0.1524)
				(type default)
			)
			(layer "F.SilkS")
		)
		(fp_line
			(start -0.7874 0.4064)
			(end -0.7874 -0.4064)
			(stroke
				(width 0.1524)
				(type default)
			)
			(layer "F.SilkS")
		)
		(fp_line
			(start -0.7874 -0.4064)
			(end 0.7874 -0.4064)
			(stroke
				(width 0.1524)
				(type default)
			)
			(layer "F.SilkS")
		)
		(fp_line
			(start 0.67945 0.3048)
			(end 0.120396 0.3048)
			(stroke
				(width 0.1)
				(type default)
			)
			(layer "F.Fab")
		)
		(fp_line
			(start 0.67945 -0.3048)
			(end 0.67945 0.3048)
			(stroke
				(width 0.1)
				(type default)
			)
			(layer "F.Fab")
		)
		(fp_line
			(start 0.12065 -0.2794)
			(end 0.12065 -0.3048)
			(stroke
				(width 0.1)
				(type default)
			)
			(layer "F.Fab")
		)
		(fp_line
			(start 0.12065 -0.3048)
			(end 0.67945 -0.3048)
			(stroke
				(width 0.1)
				(type default)
			)
			(layer "F.Fab")
		)
		(fp_line
			(start 0.120396 0.3048)
			(end 0.120396 0.2794)
			(stroke
				(width 0.1)
				(type default)
			)
			(layer "F.Fab")
		)
		(fp_line
			(start 0.120396 0.2794)
			(end -0.12065 0.2794)
			(stroke
				(width 0.1)
				(type default)
			)
			(layer "F.Fab")
		)
		(fp_line
			(start -0.12065 0.3048)
			(end -0.67945 0.3048)
			(stroke
				(width 0.1)
				(type default)
			)
			(layer "F.Fab")
		)
		(fp_line
			(start -0.12065 0.2794)
			(end -0.12065 0.3048)
			(stroke
				(width 0.1)
				(type default)
			)
			(layer "F.Fab")
		)
		(fp_line
			(start -0.12065 -0.2794)
			(end 0.12065 -0.2794)
			(stroke
				(width 0.1)
				(type default)
			)
			(layer "F.Fab")
		)
		(fp_line
			(start -0.12065 -0.305054)
			(end -0.12065 -0.2794)
			(stroke
				(width 0.1)
				(type default)
			)
			(layer "F.Fab")
		)
		(fp_line
			(start -0.67945 0.3048)
			(end -0.67945 -0.305054)
			(stroke
				(width 0.1)
				(type default)
			)
			(layer "F.Fab")
		)
		(fp_line
			(start -0.67945 -0.305054)
			(end -0.12065 -0.305054)
			(stroke
				(width 0.1)
				(type default)
			)
			(layer "F.Fab")
		)
		(pad "1" smd circle
			(at -0.40005 0 180)
			(size 0 0)
			(layers "F.Cu" "F.Mask" "F.Paste")
			(net "P3V3_AUX")
		)
		(pad "2" smd circle
			(at 0.40005 0 180)
			(size 0 0)
			(layers "F.Cu" "F.Mask" "F.Paste")
			(net "PU_U7_PIN2")
		)
	)
	(footprint ""
		(layer "F.Cu")
		(at 31.496 -176.403)
		(property "Reference" "R5103"
			(at 0 0 0)
			(layer "F.SilkS")
			(hide yes)
			(effects
				(font
					(size 1.27 1.27)
				)
			)
		)
		(property "Value" ""
			(at 0 0 0)
			(layer "F.Fab")
			(effects
				(font
					(size 1.27 1.27)
				)
			)
		)
		(duplicate_pad_numbers_are_jumpers no)
		(fp_line
			(start -0.7874 -0.4064)
			(end 0.7874 -0.4064)
			(stroke
				(width 0.1524)
				(type default)
			)
			(layer "F.SilkS")
		)
		(fp_line
			(start -0.7874 0.4064)
			(end -0.7874 -0.4064)
			(stroke
				(width 0.1524)
				(type default)
			)
			(layer "F.SilkS")
		)
		(fp_line
			(start 0.7874 -0.4064)
			(end 0.7874 0.4064)
			(stroke
				(width 0.1524)
				(type default)
			)
			(layer "F.SilkS")
		)
		(fp_line
			(start 0.7874 0.4064)
			(end -0.7874 0.4064)
			(stroke
				(width 0.1524)
				(type default)
			)
			(layer "F.SilkS")
		)
		(fp_line
			(start -0.67945 -0.305054)
			(end -0.12065 -0.305054)
			(stroke
				(width 0.1)
				(type default)
			)
			(layer "F.Fab")
		)
		(fp_line
			(start -0.67945 0.3048)
			(end -0.67945 -0.305054)
			(stroke
				(width 0.1)
				(type default)
			)
			(layer "F.Fab")
		)
		(fp_line
			(start -0.12065 -0.305054)
			(end -0.12065 -0.2794)
			(stroke
				(width 0.1)
				(type default)
			)
			(layer "F.Fab")
		)
		(fp_line
			(start -0.12065 -0.2794)
			(end 0.12065 -0.2794)
			(stroke
				(width 0.1)
				(type default)
			)
			(layer "F.Fab")
		)
		(fp_line
			(start -0.12065 0.2794)
			(end -0.12065 0.3048)
			(stroke
				(width 0.1)
				(type default)
			)
			(layer "F.Fab")
		)
		(fp_line
			(start -0.12065 0.3048)
			(end -0.67945 0.3048)
			(stroke
				(width 0.1)
				(type default)
			)
			(layer "F.Fab")
		)
		(fp_line
			(start 0.120396 0.2794)
			(end -0.12065 0.2794)
			(stroke
				(width 0.1)
				(type default)
			)
			(layer "F.Fab")
		)
		(fp_line
			(start 0.120396 0.3048)
			(end 0.120396 0.2794)
			(stroke
				(width 0.1)
				(type default)
			)
			(layer "F.Fab")
		)
		(fp_line
			(start 0.12065 -0.3048)
			(end 0.67945 -0.3048)
			(stroke
				(width 0.1)
				(type default)
			)
			(layer "F.Fab")
		)
		(fp_line
			(start 0.12065 -0.2794)
			(end 0.12065 -0.3048)
			(stroke
				(width 0.1)
				(type default)
			)
			(layer "F.Fab")
		)
		(fp_line
			(start 0.67945 -0.3048)
			(end 0.67945 0.3048)
			(stroke
				(width 0.1)
				(type default)
			)
			(layer "F.Fab")
		)
		(fp_line
			(start 0.67945 0.3048)
			(end 0.120396 0.3048)
			(stroke
				(width 0.1)
				(type default)
			)
			(layer "F.Fab")
		)
		(pad "1" smd circle
			(at -0.40005 0)
			(size 0 0)
			(layers "F.Cu" "F.Mask" "F.Paste")
			(net "FAN_4_FAIL_LED")
		)
		(pad "2" smd circle
			(at 0.40005 0)
			(size 0 0)
			(layers "F.Cu" "F.Mask" "F.Paste")
			(net "FAN_4_FAIL_R_LED")
		)
	)
	(footprint ""
		(layer "F.Cu")
		(at 5.969 -249.301)
		(property "Reference" "PR67"
			(at 0 0 0)
			(layer "F.SilkS")
			(hide yes)
			(effects
				(font
					(size 1.27 1.27)
				)
			)
		)
		(property "Value" ""
			(at 0 0 0)
			(layer "F.Fab")
			(effects
				(font
					(size 1.27 1.27)
				)
			)
		)
		(duplicate_pad_numbers_are_jumpers no)
		(fp_line
			(start -0.7874 -0.4064)
			(end 0.7874 -0.4064)
			(stroke
				(width 0.1524)
				(type default)
			)
			(layer "F.SilkS")
		)
		(fp_line
			(start -0.7874 0.4064)
			(end -0.7874 -0.4064)
			(stroke
				(width 0.1524)
				(type default)
			)
			(layer "F.SilkS")
		)
		(fp_line
			(start 0.7874 -0.4064)
			(end 0.7874 0.4064)
			(stroke
				(width 0.1524)
				(type default)
			)
			(layer "F.SilkS")
		)
		(fp_line
			(start 0.7874 0.4064)
			(end -0.7874 0.4064)
			(stroke
				(width 0.1524)
				(type default)
			)
			(layer "F.SilkS")
		)
		(fp_line
			(start -0.67945 -0.305054)
			(end -0.12065 -0.305054)
			(stroke
				(width 0.1)
				(type default)
			)
			(layer "F.Fab")
		)
		(fp_line
			(start -0.67945 0.3048)
			(end -0.67945 -0.305054)
			(stroke
				(width 0.1)
				(type default)
			)
			(layer "F.Fab")
		)
		(fp_line
			(start -0.12065 -0.305054)
			(end -0.12065 -0.2794)
			(stroke
				(width 0.1)
				(type default)
			)
			(layer "F.Fab")
		)
		(fp_line
			(start -0.12065 -0.2794)
			(end 0.12065 -0.2794)
			(stroke
				(width 0.1)
				(type default)
			)
			(layer "F.Fab")
		)
		(fp_line
			(start -0.12065 0.2794)
			(end -0.12065 0.3048)
			(stroke
				(width 0.1)
				(type default)
			)
			(layer "F.Fab")
		)
		(fp_line
			(start -0.12065 0.3048)
			(end -0.67945 0.3048)
			(stroke
				(width 0.1)
				(type default)
			)
			(layer "F.Fab")
		)
		(fp_line
			(start 0.120396 0.2794)
			(end -0.12065 0.2794)
			(stroke
				(width 0.1)
				(type default)
			)
			(layer "F.Fab")
		)
		(fp_line
			(start 0.120396 0.3048)
			(end 0.120396 0.2794)
			(stroke
				(width 0.1)
				(type default)
			)
			(layer "F.Fab")
		)
		(fp_line
			(start 0.12065 -0.3048)
			(end 0.67945 -0.3048)
			(stroke
				(width 0.1)
				(type default)
			)
			(layer "F.Fab")
		)
		(fp_line
			(start 0.12065 -0.2794)
			(end 0.12065 -0.3048)
			(stroke
				(width 0.1)
				(type default)
			)
			(layer "F.Fab")
		)
		(fp_line
			(start 0.67945 -0.3048)
			(end 0.67945 0.3048)
			(stroke
				(width 0.1)
				(type default)
			)
			(layer "F.Fab")
		)
		(fp_line
			(start 0.67945 0.3048)
			(end 0.120396 0.3048)
			(stroke
				(width 0.1)
				(type default)
			)
			(layer "F.Fab")
		)
		(pad "1" smd circle
			(at -0.40005 0)
			(size 0 0)
			(layers "F.Cu" "F.Mask" "F.Paste")
			(net "FAN_6_MODE")
		)
		(pad "2" smd circle
			(at 0.40005 0)
			(size 0 0)
			(layers "F.Cu" "F.Mask" "F.Paste")
			(net "GND")
		)
	)
	(footprint ""
		(layer "F.Cu")
		(at 30.099 -287.02 -90)
		(property "Reference" "C2093"
			(at 0 0 270)
			(layer "F.SilkS")
			(hide yes)
			(effects
				(font
					(size 1.27 1.27)
				)
			)
		)
		(property "Value" ""
			(at 0 0 270)
			(layer "F.Fab")
			(effects
				(font
					(size 1.27 1.27)
				)
			)
		)
		(duplicate_pad_numbers_are_jumpers no)
		(fp_line
			(start -0.7874 0.4064)
			(end -0.7874 -0.4064)
			(stroke
				(width 0.1524)
				(type default)
			)
			(layer "F.SilkS")
		)
		(fp_line
			(start 0.7874 0.4064)
			(end -0.7874 0.4064)
			(stroke
				(width 0.1524)
				(type default)
			)
			(layer "F.SilkS")
		)
		(fp_line
			(start -0.7874 -0.4064)
			(end 0.7874 -0.4064)
			(stroke
				(width 0.1524)
				(type default)
			)
			(layer "F.SilkS")
		)
		(fp_line
			(start 0.7874 -0.4064)
			(end 0.7874 0.4064)
			(stroke
				(width 0.1524)
				(type default)
			)
			(layer "F.SilkS")
		)
		(fp_line
			(start -0.67945 0.3048)
			(end -0.67945 -0.305054)
			(stroke
				(width 0.1)
				(type default)
			)
			(layer "F.Fab")
		)
		(fp_line
			(start -0.12065 0.3048)
			(end -0.67945 0.3048)
			(stroke
				(width 0.1)
				(type default)
			)
			(layer "F.Fab")
		)
		(fp_line
			(start 0.120396 0.3048)
			(end 0.120396 0.2794)
			(stroke
				(width 0.1)
				(type default)
			)
			(layer "F.Fab")
		)
		(fp_line
			(start 0.67945 0.3048)
			(end 0.120396 0.3048)
			(stroke
				(width 0.1)
				(type default)
			)
			(layer "F.Fab")
		)
		(fp_line
			(start -0.12065 0.2794)
			(end -0.12065 0.3048)
			(stroke
				(width 0.1)
				(type default)
			)
			(layer "F.Fab")
		)
		(fp_line
			(start 0.120396 0.2794)
			(end -0.12065 0.2794)
			(stroke
				(width 0.1)
				(type default)
			)
			(layer "F.Fab")
		)
		(fp_line
			(start -0.12065 -0.2794)
			(end 0.12065 -0.2794)
			(stroke
				(width 0.1)
				(type default)
			)
			(layer "F.Fab")
		)
		(fp_line
			(start 0.12065 -0.2794)
			(end 0.12065 -0.3048)
			(stroke
				(width 0.1)
				(type default)
			)
			(layer "F.Fab")
		)
		(fp_line
			(start 0.12065 -0.3048)
			(end 0.67945 -0.3048)
			(stroke
				(width 0.1)
				(type default)
			)
			(layer "F.Fab")
		)
		(fp_line
			(start 0.67945 -0.3048)
			(end 0.67945 0.3048)
			(stroke
				(width 0.1)
				(type default)
			)
			(layer "F.Fab")
		)
		(fp_line
			(start -0.67945 -0.305054)
			(end -0.12065 -0.305054)
			(stroke
				(width 0.1)
				(type default)
			)
			(layer "F.Fab")
		)
		(fp_line
			(start -0.12065 -0.305054)
			(end -0.12065 -0.2794)
			(stroke
				(width 0.1)
				(type default)
			)
			(layer "F.Fab")
		)
		(pad "1" smd circle
			(at -0.40005 0 270)
			(size 0 0)
			(layers "F.Cu" "F.Mask" "F.Paste")
			(net "P3V3_AUX")
		)
		(pad "2" smd circle
			(at 0.40005 0 270)
			(size 0 0)
			(layers "F.Cu" "F.Mask" "F.Paste")
			(net "GND")
		)
	)
	(footprint ""
		(layer "F.Cu")
		(at 19.177 -215.392 -90)
		(property "Reference" "R5660"
			(at 0 0 270)
			(layer "F.SilkS")
			(hide yes)
			(effects
				(font
					(size 1.27 1.27)
				)
			)
		)
		(property "Value" ""
			(at 0 0 270)
			(layer "F.Fab")
			(effects
				(font
					(size 1.27 1.27)
				)
			)
		)
		(duplicate_pad_numbers_are_jumpers no)
		(fp_line
			(start -0.7874 0.4064)
			(end -0.7874 -0.4064)
			(stroke
				(width 0.1524)
				(type default)
			)
			(layer "F.SilkS")
		)
		(fp_line
			(start 0.7874 0.4064)
			(end -0.7874 0.4064)
			(stroke
				(width 0.1524)
				(type default)
			)
			(layer "F.SilkS")
		)
		(fp_line
			(start -0.7874 -0.4064)
			(end 0.7874 -0.4064)
			(stroke
				(width 0.1524)
				(type default)
			)
			(layer "F.SilkS")
		)
		(fp_line
			(start 0.7874 -0.4064)
			(end 0.7874 0.4064)
			(stroke
				(width 0.1524)
				(type default)
			)
			(layer "F.SilkS")
		)
		(fp_line
			(start -0.67945 0.3048)
			(end -0.67945 -0.305054)
			(stroke
				(width 0.1)
				(type default)
			)
			(layer "F.Fab")
		)
		(fp_line
			(start -0.12065 0.3048)
			(end -0.67945 0.3048)
			(stroke
				(width 0.1)
				(type default)
			)
			(layer "F.Fab")
		)
		(fp_line
			(start 0.120396 0.3048)
			(end 0.120396 0.2794)
			(stroke
				(width 0.1)
				(type default)
			)
			(layer "F.Fab")
		)
		(fp_line
			(start 0.67945 0.3048)
			(end 0.120396 0.3048)
			(stroke
				(width 0.1)
				(type default)
			)
			(layer "F.Fab")
		)
		(fp_line
			(start -0.12065 0.2794)
			(end -0.12065 0.3048)
			(stroke
				(width 0.1)
				(type default)
			)
			(layer "F.Fab")
		)
		(fp_line
			(start 0.120396 0.2794)
			(end -0.12065 0.2794)
			(stroke
				(width 0.1)
				(type default)
			)
			(layer "F.Fab")
		)
		(fp_line
			(start -0.12065 -0.2794)
			(end 0.12065 -0.2794)
			(stroke
				(width 0.1)
				(type default)
			)
			(layer "F.Fab")
		)
		(fp_line
			(start 0.12065 -0.2794)
			(end 0.12065 -0.3048)
			(stroke
				(width 0.1)
				(type default)
			)
			(layer "F.Fab")
		)
		(fp_line
			(start 0.12065 -0.3048)
			(end 0.67945 -0.3048)
			(stroke
				(width 0.1)
				(type default)
			)
			(layer "F.Fab")
		)
		(fp_line
			(start 0.67945 -0.3048)
			(end 0.67945 0.3048)
			(stroke
				(width 0.1)
				(type default)
			)
			(layer "F.Fab")
		)
		(fp_line
			(start -0.67945 -0.305054)
			(end -0.12065 -0.305054)
			(stroke
				(width 0.1)
				(type default)
			)
			(layer "F.Fab")
		)
		(fp_line
			(start -0.12065 -0.305054)
			(end -0.12065 -0.2794)
			(stroke
				(width 0.1)
				(type default)
			)
			(layer "F.Fab")
		)
		(pad "1" smd rect
			(at -0.40005 0 90)
			(size 0.4572 0.508)
			(layers "F.Cu" "F.Mask" "F.Paste")
			(net "P12V_LED")
		)
		(pad "2" smd rect
			(at 0.40005 0 90)
			(size 0.4572 0.508)
			(layers "F.Cu" "F.Mask" "F.Paste")
			(net "U411_D1")
		)
	)
	(footprint ""
		(layer "F.Cu")
		(at 18.669 -302.514 180)
		(property "Reference" "R5321"
			(at 0 0 180)
			(layer "F.SilkS")
			(hide yes)
			(effects
				(font
					(size 1.27 1.27)
				)
			)
		)
		(property "Value" ""
			(at 0 0 180)
			(layer "F.Fab")
			(effects
				(font
					(size 1.27 1.27)
				)
			)
		)
		(duplicate_pad_numbers_are_jumpers no)
		(fp_line
			(start 1.2954 0.5842)
			(end -1.2954 0.5842)
			(stroke
				(width 0.1524)
				(type default)
			)
			(layer "F.SilkS")
		)
		(fp_line
			(start 1.2954 -0.5842)
			(end 1.2954 0.5842)
			(stroke
				(width 0.1524)
				(type default)
			)
			(layer "F.SilkS")
		)
		(fp_line
			(start -1.2954 0.5842)
			(end -1.2954 -0.5842)
			(stroke
				(width 0.1524)
				(type default)
			)
			(layer "F.SilkS")
		)
		(fp_line
			(start -1.2954 -0.5842)
			(end 1.2954 -0.5842)
			(stroke
				(width 0.1524)
				(type default)
			)
			(layer "F.SilkS")
		)
		(fp_line
			(start 1.1938 0.4064)
			(end 0.8636 0.4064)
			(stroke
				(width 0.1)
				(type default)
			)
			(layer "F.Fab")
		)
		(fp_line
			(start 1.1938 -0.406654)
			(end 1.1938 0.4064)
			(stroke
				(width 0.1)
				(type default)
			)
			(layer "F.Fab")
		)
		(fp_line
			(start 0.8636 0.4572)
			(end -0.8636 0.4572)
			(stroke
				(width 0.1)
				(type default)
			)
			(layer "F.Fab")
		)
		(fp_line
			(start 0.8636 0.4064)
			(end 0.8636 0.4572)
			(stroke
				(width 0.1)
				(type default)
			)
			(layer "F.Fab")
		)
		(fp_line
			(start 0.8636 -0.406654)
			(end 1.1938 -0.406654)
			(stroke
				(width 0.1)
				(type default)
			)
			(layer "F.Fab")
		)
		(fp_line
			(start 0.8636 -0.4572)
			(end 0.8636 -0.406654)
			(stroke
				(width 0.1)
				(type default)
			)
			(layer "F.Fab")
		)
		(fp_line
			(start -0.8636 0.4572)
			(end -0.8636 0.4318)
			(stroke
				(width 0.1)
				(type default)
			)
			(layer "F.Fab")
		)
		(fp_line
			(start -0.8636 0.4318)
			(end -0.8636 0.4064)
			(stroke
				(width 0.1)
				(type default)
			)
			(layer "F.Fab")
		)
		(fp_line
			(start -0.8636 0.4064)
			(end -1.1938 0.4064)
			(stroke
				(width 0.1)
				(type default)
			)
			(layer "F.Fab")
		)
		(fp_line
			(start -0.8636 -0.406654)
			(end -0.8636 -0.4572)
			(stroke
				(width 0.1)
				(type default)
			)
			(layer "F.Fab")
		)
		(fp_line
			(start -0.8636 -0.4572)
			(end 0.8636 -0.4572)
			(stroke
				(width 0.1)
				(type default)
			)
			(layer "F.Fab")
		)
		(fp_line
			(start -1.1938 0.4064)
			(end -1.1938 -0.406654)
			(stroke
				(width 0.1)
				(type default)
			)
			(layer "F.Fab")
		)
		(fp_line
			(start -1.1938 -0.406654)
			(end -0.8636 -0.406654)
			(stroke
				(width 0.1)
				(type default)
			)
			(layer "F.Fab")
		)
		(pad "1" smd rect
			(at -0.7366 0 90)
			(size 0.7112 0.8128)
			(layers "F.Cu" "F.Mask" "F.Paste")
			(net "P52V_FAN_7")
		)
		(pad "2" smd rect
			(at 0.7366 0 90)
			(size 0.7112 0.8128)
			(layers "F.Cu" "F.Mask" "F.Paste")
			(net "FAN_7_TACH_OL_R")
		)
	)
	(footprint ""
		(layer "F.Cu")
		(at 16.139922 -91.0082)
		(property "Reference" "PC42"
			(at -5.344922 5.94487 0)
			(unlocked yes)
			(layer "F.SilkS")
			(effects
				(font
					(size 0.7874 0.5842)
					(thickness 0.1524)
				)
				(justify left)
			)
		)
		(property "Value" ""
			(at 0 0 0)
			(layer "F.Fab")
			(effects
				(font
					(size 1.27 1.27)
				)
			)
		)
		(duplicate_pad_numbers_are_jumpers no)
		(fp_line
			(start -5.249926 -3.979926)
			(end -5.249926 -1.2446)
			(stroke
				(width 0.1524)
				(type default)
			)
			(layer "F.SilkS")
		)
		(fp_line
			(start -5.249926 1.2446)
			(end -5.249926 3.979926)
			(stroke
				(width 0.1524)
				(type default)
			)
			(layer "F.SilkS")
		)
		(fp_line
			(start -5.249926 3.979926)
			(end -3.979926 5.249926)
			(stroke
				(width 0.1524)
				(type default)
			)
			(layer "F.SilkS")
		)
		(fp_line
			(start -3.979926 -5.249926)
			(end -5.249926 -3.979926)
			(stroke
				(width 0.1524)
				(type default)
			)
			(layer "F.SilkS")
		)
		(fp_line
			(start -3.979926 5.249926)
			(end 5.249926 5.249926)
			(stroke
				(width 0.1524)
				(type default)
			)
			(layer "F.SilkS")
		)
		(fp_line
			(start 5.249926 -5.249926)
			(end -3.979926 -5.249926)
			(stroke
				(width 0.1524)
				(type default)
			)
			(layer "F.SilkS")
		)
		(fp_line
			(start 5.249926 -1.2446)
			(end 5.249926 -5.249926)
			(stroke
				(width 0.1524)
				(type default)
			)
			(layer "F.SilkS")
		)
		(fp_line
			(start 5.249926 5.249926)
			(end 5.249926 1.2446)
			(stroke
				(width 0.1524)
				(type default)
			)
			(layer "F.SilkS")
		)
		(fp_line
			(start -5.249926 -5.249926)
			(end -5.249926 5.249926)
			(stroke
				(width 0.1)
				(type default)
			)
			(layer "F.Fab")
		)
		(fp_line
			(start -5.249926 5.249926)
			(end 5.249926 5.249926)
			(stroke
				(width 0.1)
				(type default)
			)
			(layer "F.Fab")
		)
		(fp_line
			(start 5.249926 -5.249926)
			(end -5.249926 -5.249926)
			(stroke
				(width 0.1)
				(type default)
			)
			(layer "F.Fab")
		)
		(fp_line
			(start 5.249926 5.249926)
			(end 5.249926 -5.249926)
			(stroke
				(width 0.1)
				(type default)
			)
			(layer "F.Fab")
		)
		(pad "1" smd rect
			(at -4.45008 0 90)
			(size 2.2098 4.4196)
			(layers "F.Cu" "F.Mask" "F.Paste")
			(net "P52V_FAN_5")
		)
		(pad "2" smd rect
			(at 4.45008 0 90)
			(size 2.2098 4.4196)
			(layers "F.Cu" "F.Mask" "F.Paste")
			(net "GND")
		)
	)
	(footprint ""
		(layer "F.Cu")
		(at 18.161 -32.004 90)
		(property "Reference" "R5311"
			(at 0 0 90)
			(layer "F.SilkS")
			(hide yes)
			(effects
				(font
					(size 1.27 1.27)
				)
			)
		)
		(property "Value" ""
			(at 0 0 90)
			(layer "F.Fab")
			(effects
				(font
					(size 1.27 1.27)
				)
			)
		)
		(duplicate_pad_numbers_are_jumpers no)
		(fp_line
			(start 0.7874 -0.4064)
			(end 0.7874 0.4064)
			(stroke
				(width 0.1524)
				(type default)
			)
			(layer "F.SilkS")
		)
		(fp_line
			(start -0.7874 -0.4064)
			(end 0.7874 -0.4064)
			(stroke
				(width 0.1524)
				(type default)
			)
			(layer "F.SilkS")
		)
		(fp_line
			(start 0.7874 0.4064)
			(end -0.7874 0.4064)
			(stroke
				(width 0.1524)
				(type default)
			)
			(layer "F.SilkS")
		)
		(fp_line
			(start -0.7874 0.4064)
			(end -0.7874 -0.4064)
			(stroke
				(width 0.1524)
				(type default)
			)
			(layer "F.SilkS")
		)
		(fp_line
			(start -0.12065 -0.305054)
			(end -0.12065 -0.2794)
			(stroke
				(width 0.1)
				(type default)
			)
			(layer "F.Fab")
		)
		(fp_line
			(start -0.67945 -0.305054)
			(end -0.12065 -0.305054)
			(stroke
				(width 0.1)
				(type default)
			)
			(layer "F.Fab")
		)
		(fp_line
			(start 0.67945 -0.3048)
			(end 0.67945 0.3048)
			(stroke
				(width 0.1)
				(type default)
			)
			(layer "F.Fab")
		)
		(fp_line
			(start 0.12065 -0.3048)
			(end 0.67945 -0.3048)
			(stroke
				(width 0.1)
				(type default)
			)
			(layer "F.Fab")
		)
		(fp_line
			(start 0.12065 -0.2794)
			(end 0.12065 -0.3048)
			(stroke
				(width 0.1)
				(type default)
			)
			(layer "F.Fab")
		)
		(fp_line
			(start -0.12065 -0.2794)
			(end 0.12065 -0.2794)
			(stroke
				(width 0.1)
				(type default)
			)
			(layer "F.Fab")
		)
		(fp_line
			(start 0.120396 0.2794)
			(end -0.12065 0.2794)
			(stroke
				(width 0.1)
				(type default)
			)
			(layer "F.Fab")
		)
		(fp_line
			(start -0.12065 0.2794)
			(end -0.12065 0.3048)
			(stroke
				(width 0.1)
				(type default)
			)
			(layer "F.Fab")
		)
		(fp_line
			(start 0.67945 0.3048)
			(end 0.120396 0.3048)
			(stroke
				(width 0.1)
				(type default)
			)
			(layer "F.Fab")
		)
		(fp_line
			(start 0.120396 0.3048)
			(end 0.120396 0.2794)
			(stroke
				(width 0.1)
				(type default)
			)
			(layer "F.Fab")
		)
		(fp_line
			(start -0.12065 0.3048)
			(end -0.67945 0.3048)
			(stroke
				(width 0.1)
				(type default)
			)
			(layer "F.Fab")
		)
		(fp_line
			(start -0.67945 0.3048)
			(end -0.67945 -0.305054)
			(stroke
				(width 0.1)
				(type default)
			)
			(layer "F.Fab")
		)
		(pad "1" smd rect
			(at -0.40005 0 270)
			(size 0.4572 0.508)
			(layers "F.Cu" "F.Mask" "F.Paste")
			(net "FAN_4_TACH_OL_R")
		)
		(pad "2" smd rect
			(at 0.40005 0 270)
			(size 0.4572 0.508)
			(layers "F.Cu" "F.Mask" "F.Paste")
			(net "FAN_4_TACH_OL")
		)
	)
	(footprint ""
		(layer "F.Cu")
		(at 40.127428 -68.256912)
		(property "Reference" "R506"
			(at 0 0 0)
			(layer "F.SilkS")
			(hide yes)
			(effects
				(font
					(size 1.27 1.27)
				)
			)
		)
		(property "Value" ""
			(at 0 0 0)
			(layer "F.Fab")
			(effects
				(font
					(size 1.27 1.27)
				)
			)
		)
		(duplicate_pad_numbers_are_jumpers no)
		(fp_line
			(start -0.7874 -0.4064)
			(end 0.7874 -0.4064)
			(stroke
				(width 0.1524)
				(type default)
			)
			(layer "F.SilkS")
		)
		(fp_line
			(start -0.7874 0.4064)
			(end -0.7874 -0.4064)
			(stroke
				(width 0.1524)
				(type default)
			)
			(layer "F.SilkS")
		)
		(fp_line
			(start 0.7874 -0.4064)
			(end 0.7874 0.4064)
			(stroke
				(width 0.1524)
				(type default)
			)
			(layer "F.SilkS")
		)
		(fp_line
			(start 0.7874 0.4064)
			(end -0.7874 0.4064)
			(stroke
				(width 0.1524)
				(type default)
			)
			(layer "F.SilkS")
		)
		(fp_line
			(start -0.67945 -0.305054)
			(end -0.12065 -0.305054)
			(stroke
				(width 0.1)
				(type default)
			)
			(layer "F.Fab")
		)
		(fp_line
			(start -0.67945 0.3048)
			(end -0.67945 -0.305054)
			(stroke
				(width 0.1)
				(type default)
			)
			(layer "F.Fab")
		)
		(fp_line
			(start -0.12065 -0.305054)
			(end -0.12065 -0.2794)
			(stroke
				(width 0.1)
				(type default)
			)
			(layer "F.Fab")
		)
		(fp_line
			(start -0.12065 -0.2794)
			(end 0.12065 -0.2794)
			(stroke
				(width 0.1)
				(type default)
			)
			(layer "F.Fab")
		)
		(fp_line
			(start -0.12065 0.2794)
			(end -0.12065 0.3048)
			(stroke
				(width 0.1)
				(type default)
			)
			(layer "F.Fab")
		)
		(fp_line
			(start -0.12065 0.3048)
			(end -0.67945 0.3048)
			(stroke
				(width 0.1)
				(type default)
			)
			(layer "F.Fab")
		)
		(fp_line
			(start 0.120396 0.2794)
			(end -0.12065 0.2794)
			(stroke
				(width 0.1)
				(type default)
			)
			(layer "F.Fab")
		)
		(fp_line
			(start 0.120396 0.3048)
			(end 0.120396 0.2794)
			(stroke
				(width 0.1)
				(type default)
			)
			(layer "F.Fab")
		)
		(fp_line
			(start 0.12065 -0.3048)
			(end 0.67945 -0.3048)
			(stroke
				(width 0.1)
				(type default)
			)
			(layer "F.Fab")
		)
		(fp_line
			(start 0.12065 -0.2794)
			(end 0.12065 -0.3048)
			(stroke
				(width 0.1)
				(type default)
			)
			(layer "F.Fab")
		)
		(fp_line
			(start 0.67945 -0.3048)
			(end 0.67945 0.3048)
			(stroke
				(width 0.1)
				(type default)
			)
			(layer "F.Fab")
		)
		(fp_line
			(start 0.67945 0.3048)
			(end 0.120396 0.3048)
			(stroke
				(width 0.1)
				(type default)
			)
			(layer "F.Fab")
		)
		(pad "1" smd circle
			(at -0.40005 0)
			(size 0 0)
			(layers "F.Cu" "F.Mask" "F.Paste")
			(net "FAN_3_ON")
		)
		(pad "2" smd circle
			(at 0.40005 0)
			(size 0 0)
			(layers "F.Cu" "F.Mask" "F.Paste")
			(net "P52V_FAN_3_EN")
		)
	)
	(footprint ""
		(layer "F.Cu")
		(at 20.828 -174.752)
		(property "Reference" "R5675"
			(at 0 0 0)
			(layer "F.SilkS")
			(hide yes)
			(effects
				(font
					(size 1.27 1.27)
				)
			)
		)
		(property "Value" ""
			(at 0 0 0)
			(layer "F.Fab")
			(effects
				(font
					(size 1.27 1.27)
				)
			)
		)
		(duplicate_pad_numbers_are_jumpers no)
		(fp_line
			(start -0.7874 -0.4064)
			(end 0.7874 -0.4064)
			(stroke
				(width 0.1524)
				(type default)
			)
			(layer "F.SilkS")
		)
		(fp_line
			(start -0.7874 0.4064)
			(end -0.7874 -0.4064)
			(stroke
				(width 0.1524)
				(type default)
			)
			(layer "F.SilkS")
		)
		(fp_line
			(start 0.7874 -0.4064)
			(end 0.7874 0.4064)
			(stroke
				(width 0.1524)
				(type default)
			)
			(layer "F.SilkS")
		)
		(fp_line
			(start 0.7874 0.4064)
			(end -0.7874 0.4064)
			(stroke
				(width 0.1524)
				(type default)
			)
			(layer "F.SilkS")
		)
		(fp_line
			(start -0.67945 -0.305054)
			(end -0.12065 -0.305054)
			(stroke
				(width 0.1)
				(type default)
			)
			(layer "F.Fab")
		)
		(fp_line
			(start -0.67945 0.3048)
			(end -0.67945 -0.305054)
			(stroke
				(width 0.1)
				(type default)
			)
			(layer "F.Fab")
		)
		(fp_line
			(start -0.12065 -0.305054)
			(end -0.12065 -0.2794)
			(stroke
				(width 0.1)
				(type default)
			)
			(layer "F.Fab")
		)
		(fp_line
			(start -0.12065 -0.2794)
			(end 0.12065 -0.2794)
			(stroke
				(width 0.1)
				(type default)
			)
			(layer "F.Fab")
		)
		(fp_line
			(start -0.12065 0.2794)
			(end -0.12065 0.3048)
			(stroke
				(width 0.1)
				(type default)
			)
			(layer "F.Fab")
		)
		(fp_line
			(start -0.12065 0.3048)
			(end -0.67945 0.3048)
			(stroke
				(width 0.1)
				(type default)
			)
			(layer "F.Fab")
		)
		(fp_line
			(start 0.120396 0.2794)
			(end -0.12065 0.2794)
			(stroke
				(width 0.1)
				(type default)
			)
			(layer "F.Fab")
		)
		(fp_line
			(start 0.120396 0.3048)
			(end 0.120396 0.2794)
			(stroke
				(width 0.1)
				(type default)
			)
			(layer "F.Fab")
		)
		(fp_line
			(start 0.12065 -0.3048)
			(end 0.67945 -0.3048)
			(stroke
				(width 0.1)
				(type default)
			)
			(layer "F.Fab")
		)
		(fp_line
			(start 0.12065 -0.2794)
			(end 0.12065 -0.3048)
			(stroke
				(width 0.1)
				(type default)
			)
			(layer "F.Fab")
		)
		(fp_line
			(start 0.67945 -0.3048)
			(end 0.67945 0.3048)
			(stroke
				(width 0.1)
				(type default)
			)
			(layer "F.Fab")
		)
		(fp_line
			(start 0.67945 0.3048)
			(end 0.120396 0.3048)
			(stroke
				(width 0.1)
				(type default)
			)
			(layer "F.Fab")
		)
		(pad "1" smd circle
			(at -0.40005 0)
			(size 0 0)
			(layers "F.Cu" "F.Mask" "F.Paste")
			(net "FM_BOARD_SKU_ID2")
		)
		(pad "2" smd circle
			(at 0.40005 0)
			(size 0 0)
			(layers "F.Cu" "F.Mask" "F.Paste")
			(net "GND")
		)
	)
	(footprint ""
		(layer "F.Cu")
		(at 24.765 -152.019 90)
		(property "Reference" "U321"
			(at -2.032 -4.67233 90)
			(unlocked yes)
			(layer "F.SilkS")
			(effects
				(font
					(size 0.7874 0.5842)
					(thickness 0.1524)
				)
				(justify left)
			)
		)
		(property "Value" ""
			(at 0 0 90)
			(layer "F.Fab")
			(effects
				(font
					(size 1.27 1.27)
				)
			)
		)
		(duplicate_pad_numbers_are_jumpers no)
		(fp_line
			(start 2.0066 -3.9624)
			(end 2.0066 3.9624)
			(stroke
				(width 0.1524)
				(type default)
			)
			(layer "F.SilkS")
		)
		(fp_line
			(start 0.5842 -3.9624)
			(end 2.0066 -3.9624)
			(stroke
				(width 0.1524)
				(type default)
			)
			(layer "F.SilkS")
		)
		(fp_line
			(start -0.5842 -3.9624)
			(end 0 -3.3782)
			(stroke
				(width 0.1524)
				(type default)
			)
			(layer "F.SilkS")
		)
		(fp_line
			(start -2.0066 -3.9624)
			(end -0.5842 -3.9624)
			(stroke
				(width 0.1524)
				(type default)
			)
			(layer "F.SilkS")
		)
		(fp_line
			(start 0 -3.3782)
			(end 0.5842 -3.9624)
			(stroke
				(width 0.1524)
				(type default)
			)
			(layer "F.SilkS")
		)
		(fp_line
			(start 2.0066 3.9624)
			(end -2.0066 3.9624)
			(stroke
				(width 0.1524)
				(type default)
			)
			(layer "F.SilkS")
		)
		(fp_line
			(start -2.0066 3.9624)
			(end -2.0066 -3.9624)
			(stroke
				(width 0.1524)
				(type default)
			)
			(layer "F.SilkS")
		)
		(fp_poly
			(pts
				(xy -3.8862 -3.570986) (xy -4.6482 -3.189986) (xy -4.6482 -3.951986)
			)
			(stroke
				(width 0)
				(type default)
			)
			(fill yes)
			(layer "F.SilkS")
		)
		(fp_line
			(start 2.2479 -3.974846)
			(end -2.2479 -3.974846)
			(stroke
				(width 0.1)
				(type default)
			)
			(layer "F.Fab")
		)
		(fp_line
			(start -2.2479 -3.974846)
			(end -2.2479 -3.80365)
			(stroke
				(width 0.1)
				(type default)
			)
			(layer "F.Fab")
		)
		(fp_line
			(start 3.7211 -3.80365)
			(end 2.2479 -3.80365)
			(stroke
				(width 0.1)
				(type default)
			)
			(layer "F.Fab")
		)
		(fp_line
			(start 2.2479 -3.80365)
			(end 2.2479 -3.974846)
			(stroke
				(width 0.1)
				(type default)
			)
			(layer "F.Fab")
		)
		(fp_line
			(start -2.2479 -3.80365)
			(end -3.724402 -3.80365)
			(stroke
				(width 0.1)
				(type default)
			)
			(layer "F.Fab")
		)
		(fp_line
			(start -3.724402 -3.80365)
			(end -3.724402 3.80365)
			(stroke
				(width 0.1)
				(type default)
			)
			(layer "F.Fab")
		)
		(fp_line
			(start -3.7211 -3.34645)
			(end -3.7211 -3.80365)
			(stroke
				(width 0.1)
				(type default)
			)
			(layer "F.Fab")
		)
		(fp_line
			(start 3.7211 3.80365)
			(end 3.7211 -3.80365)
			(stroke
				(width 0.1)
				(type default)
			)
			(layer "F.Fab")
		)
		(fp_line
			(start 2.2479 3.80365)
			(end 3.7211 3.80365)
			(stroke
				(width 0.1)
				(type default)
			)
			(layer "F.Fab")
		)
		(fp_line
			(start -2.2479 3.80365)
			(end -2.2479 3.9624)
			(stroke
				(width 0.1)
				(type default)
			)
			(layer "F.Fab")
		)
		(fp_line
			(start -3.724402 3.80365)
			(end -2.2479 3.80365)
			(stroke
				(width 0.1)
				(type default)
			)
			(layer "F.Fab")
		)
		(fp_line
			(start 2.2479 3.9624)
			(end 2.2479 3.80365)
			(stroke
				(width 0.1)
				(type default)
			)
			(layer "F.Fab")
		)
		(fp_line
			(start -2.2479 3.9624)
			(end 2.2479 3.9624)
			(stroke
				(width 0.1)
				(type default)
			)
			(layer "F.Fab")
		)
		(fp_poly
			(pts
				(xy -3.8862 -3.570986) (xy -4.6482 -3.189986) (xy -4.6482 -3.951986)
			)
			(stroke
				(width 0)
				(type default)
			)
			(fill yes)
			(layer "F.Fab")
		)
		(pad "1" smd rect
			(at -2.921 -3.57505)
			(size 0.3556 1.4986)
			(layers "F.Cu" "F.Mask" "F.Paste")
			(net "PD_TCA9548_SML1_U321_A0")
		)
		(pad "2" smd rect
			(at -2.921 -2.925064)
			(size 0.3556 1.4986)
			(layers "F.Cu" "F.Mask" "F.Paste")
			(net "PD_TCA9548_SML1_U321_A1")
		)
		(pad "3" smd rect
			(at -2.921 -2.275078)
			(size 0.3556 1.4986)
			(layers "F.Cu" "F.Mask" "F.Paste")
			(net "RST_SMB_PDB_R_N")
		)
		(pad "4" smd rect
			(at -2.921 -1.625092)
			(size 0.3556 1.4986)
			(layers "F.Cu" "F.Mask" "F.Paste")
			(net "SMB_FAN0_R_SDA")
		)
		(pad "5" smd rect
			(at -2.921 -0.975106)
			(size 0.3556 1.4986)
			(layers "F.Cu" "F.Mask" "F.Paste")
			(net "SMB_FAN0_R_SCL")
		)
		(pad "6" smd rect
			(at -2.921 -0.32512)
			(size 0.3556 1.4986)
			(layers "F.Cu" "F.Mask" "F.Paste")
			(net "SMB_FAN1_R_SDA")
		)
		(pad "7" smd rect
			(at -2.921 0.32512)
			(size 0.3556 1.4986)
			(layers "F.Cu" "F.Mask" "F.Paste")
			(net "SMB_FAN1_R_SCL")
		)
		(pad "8" smd rect
			(at -2.921 0.975106)
			(size 0.3556 1.4986)
			(layers "F.Cu" "F.Mask" "F.Paste")
			(net "SMB_FAN2_R_SDA")
		)
		(pad "9" smd rect
			(at -2.921 1.625092)
			(size 0.3556 1.4986)
			(layers "F.Cu" "F.Mask" "F.Paste")
			(net "SMB_FAN2_R_SCL")
		)
		(pad "10" smd rect
			(at -2.921 2.275078)
			(size 0.3556 1.4986)
			(layers "F.Cu" "F.Mask" "F.Paste")
			(net "SMB_FAN3_R_SDA")
		)
		(pad "11" smd rect
			(at -2.921 2.925064)
			(size 0.3556 1.4986)
			(layers "F.Cu" "F.Mask" "F.Paste")
			(net "SMB_FAN3_R_SCL")
		)
		(pad "12" smd rect
			(at -2.921 3.57505)
			(size 0.3556 1.4986)
			(layers "F.Cu" "F.Mask" "F.Paste")
			(net "GND")
		)
		(pad "13" smd rect
			(at 2.921 3.57505)
			(size 0.3556 1.4986)
			(layers "F.Cu" "F.Mask" "F.Paste")
			(net "SMB_FAN4_R_SDA")
		)
		(pad "14" smd rect
			(at 2.921 2.925064)
			(size 0.3556 1.4986)
			(layers "F.Cu" "F.Mask" "F.Paste")
			(net "SMB_FAN4_R_SCL")
		)
		(pad "15" smd rect
			(at 2.921 2.275078)
			(size 0.3556 1.4986)
			(layers "F.Cu" "F.Mask" "F.Paste")
			(net "SMB_FAN5_R_SDA")
		)
		(pad "16" smd rect
			(at 2.921 1.625092)
			(size 0.3556 1.4986)
			(layers "F.Cu" "F.Mask" "F.Paste")
			(net "SMB_FAN5_R_SCL")
		)
		(pad "17" smd rect
			(at 2.921 0.975106)
			(size 0.3556 1.4986)
			(layers "F.Cu" "F.Mask" "F.Paste")
			(net "SMB_FAN6_R_SDA")
		)
		(pad "18" smd rect
			(at 2.921 0.32512)
			(size 0.3556 1.4986)
			(layers "F.Cu" "F.Mask" "F.Paste")
			(net "SMB_FAN6_R_SCL")
		)
		(pad "19" smd rect
			(at 2.921 -0.32512)
			(size 0.3556 1.4986)
			(layers "F.Cu" "F.Mask" "F.Paste")
			(net "SMB_FAN7_R_SDA")
		)
		(pad "20" smd rect
			(at 2.921 -0.975106)
			(size 0.3556 1.4986)
			(layers "F.Cu" "F.Mask" "F.Paste")
			(net "SMB_FAN7_R_SCL")
		)
		(pad "21" smd rect
			(at 2.921 -1.625092)
			(size 0.3556 1.4986)
			(layers "F.Cu" "F.Mask" "F.Paste")
			(net "PD_TCA9548_SML1_U321_A2")
		)
		(pad "22" smd rect
			(at 2.921 -2.275078)
			(size 0.3556 1.4986)
			(layers "F.Cu" "F.Mask" "F.Paste")
			(net "SMB_PDBV_FAN_R_U321_SCL")
		)
		(pad "23" smd rect
			(at 2.921 -2.925064)
			(size 0.3556 1.4986)
			(layers "F.Cu" "F.Mask" "F.Paste")
			(net "SMB_PDBV_FAN_R_U321_SDA")
		)
		(pad "24" smd rect
			(at 2.921 -3.57505)
			(size 0.3556 1.4986)
			(layers "F.Cu" "F.Mask" "F.Paste")
			(net "P3V3_AUX")
		)
	)
	(footprint ""
		(layer "F.Cu")
		(at 44.831 -135.509 -90)
		(property "Reference" "C2094"
			(at 0 0 270)
			(layer "F.SilkS")
			(hide yes)
			(effects
				(font
					(size 1.27 1.27)
				)
			)
		)
		(property "Value" ""
			(at 0 0 270)
			(layer "F.Fab")
			(effects
				(font
					(size 1.27 1.27)
				)
			)
		)
		(duplicate_pad_numbers_are_jumpers no)
		(fp_line
			(start -0.7874 0.4064)
			(end -0.7874 -0.4064)
			(stroke
				(width 0.1524)
				(type default)
			)
			(layer "F.SilkS")
		)
		(fp_line
			(start 0.7874 0.4064)
			(end -0.7874 0.4064)
			(stroke
				(width 0.1524)
				(type default)
			)
			(layer "F.SilkS")
		)
		(fp_line
			(start -0.7874 -0.4064)
			(end 0.7874 -0.4064)
			(stroke
				(width 0.1524)
				(type default)
			)
			(layer "F.SilkS")
		)
		(fp_line
			(start 0.7874 -0.4064)
			(end 0.7874 0.4064)
			(stroke
				(width 0.1524)
				(type default)
			)
			(layer "F.SilkS")
		)
		(fp_line
			(start -0.67945 0.3048)
			(end -0.67945 -0.305054)
			(stroke
				(width 0.1)
				(type default)
			)
			(layer "F.Fab")
		)
		(fp_line
			(start -0.12065 0.3048)
			(end -0.67945 0.3048)
			(stroke
				(width 0.1)
				(type default)
			)
			(layer "F.Fab")
		)
		(fp_line
			(start 0.120396 0.3048)
			(end 0.120396 0.2794)
			(stroke
				(width 0.1)
				(type default)
			)
			(layer "F.Fab")
		)
		(fp_line
			(start 0.67945 0.3048)
			(end 0.120396 0.3048)
			(stroke
				(width 0.1)
				(type default)
			)
			(layer "F.Fab")
		)
		(fp_line
			(start -0.12065 0.2794)
			(end -0.12065 0.3048)
			(stroke
				(width 0.1)
				(type default)
			)
			(layer "F.Fab")
		)
		(fp_line
			(start 0.120396 0.2794)
			(end -0.12065 0.2794)
			(stroke
				(width 0.1)
				(type default)
			)
			(layer "F.Fab")
		)
		(fp_line
			(start -0.12065 -0.2794)
			(end 0.12065 -0.2794)
			(stroke
				(width 0.1)
				(type default)
			)
			(layer "F.Fab")
		)
		(fp_line
			(start 0.12065 -0.2794)
			(end 0.12065 -0.3048)
			(stroke
				(width 0.1)
				(type default)
			)
			(layer "F.Fab")
		)
		(fp_line
			(start 0.12065 -0.3048)
			(end 0.67945 -0.3048)
			(stroke
				(width 0.1)
				(type default)
			)
			(layer "F.Fab")
		)
		(fp_line
			(start 0.67945 -0.3048)
			(end 0.67945 0.3048)
			(stroke
				(width 0.1)
				(type default)
			)
			(layer "F.Fab")
		)
		(fp_line
			(start -0.67945 -0.305054)
			(end -0.12065 -0.305054)
			(stroke
				(width 0.1)
				(type default)
			)
			(layer "F.Fab")
		)
		(fp_line
			(start -0.12065 -0.305054)
			(end -0.12065 -0.2794)
			(stroke
				(width 0.1)
				(type default)
			)
			(layer "F.Fab")
		)
		(pad "1" smd circle
			(at -0.40005 0 270)
			(size 0 0)
			(layers "F.Cu" "F.Mask" "F.Paste")
			(net "GND")
		)
		(pad "2" smd circle
			(at 0.40005 0 270)
			(size 0 0)
			(layers "F.Cu" "F.Mask" "F.Paste")
			(net "P3V3_AUX")
		)
	)
	(footprint ""
		(layer "F.Cu")
		(at 27.051 -127.508 -90)
		(property "Reference" "R4943"
			(at 0 0 270)
			(layer "F.SilkS")
			(hide yes)
			(effects
				(font
					(size 1.27 1.27)
				)
			)
		)
		(property "Value" ""
			(at 0 0 270)
			(layer "F.Fab")
			(effects
				(font
					(size 1.27 1.27)
				)
			)
		)
		(duplicate_pad_numbers_are_jumpers no)
		(fp_line
			(start -0.7874 0.4064)
			(end -0.7874 -0.4064)
			(stroke
				(width 0.1524)
				(type default)
			)
			(layer "F.SilkS")
		)
		(fp_line
			(start 0.7874 0.4064)
			(end -0.7874 0.4064)
			(stroke
				(width 0.1524)
				(type default)
			)
			(layer "F.SilkS")
		)
		(fp_line
			(start -0.7874 -0.4064)
			(end 0.7874 -0.4064)
			(stroke
				(width 0.1524)
				(type default)
			)
			(layer "F.SilkS")
		)
		(fp_line
			(start 0.7874 -0.4064)
			(end 0.7874 0.4064)
			(stroke
				(width 0.1524)
				(type default)
			)
			(layer "F.SilkS")
		)
		(fp_line
			(start -0.67945 0.3048)
			(end -0.67945 -0.305054)
			(stroke
				(width 0.1)
				(type default)
			)
			(layer "F.Fab")
		)
		(fp_line
			(start -0.12065 0.3048)
			(end -0.67945 0.3048)
			(stroke
				(width 0.1)
				(type default)
			)
			(layer "F.Fab")
		)
		(fp_line
			(start 0.120396 0.3048)
			(end 0.120396 0.2794)
			(stroke
				(width 0.1)
				(type default)
			)
			(layer "F.Fab")
		)
		(fp_line
			(start 0.67945 0.3048)
			(end 0.120396 0.3048)
			(stroke
				(width 0.1)
				(type default)
			)
			(layer "F.Fab")
		)
		(fp_line
			(start -0.12065 0.2794)
			(end -0.12065 0.3048)
			(stroke
				(width 0.1)
				(type default)
			)
			(layer "F.Fab")
		)
		(fp_line
			(start 0.120396 0.2794)
			(end -0.12065 0.2794)
			(stroke
				(width 0.1)
				(type default)
			)
			(layer "F.Fab")
		)
		(fp_line
			(start -0.12065 -0.2794)
			(end 0.12065 -0.2794)
			(stroke
				(width 0.1)
				(type default)
			)
			(layer "F.Fab")
		)
		(fp_line
			(start 0.12065 -0.2794)
			(end 0.12065 -0.3048)
			(stroke
				(width 0.1)
				(type default)
			)
			(layer "F.Fab")
		)
		(fp_line
			(start 0.12065 -0.3048)
			(end 0.67945 -0.3048)
			(stroke
				(width 0.1)
				(type default)
			)
			(layer "F.Fab")
		)
		(fp_line
			(start 0.67945 -0.3048)
			(end 0.67945 0.3048)
			(stroke
				(width 0.1)
				(type default)
			)
			(layer "F.Fab")
		)
		(fp_line
			(start -0.67945 -0.305054)
			(end -0.12065 -0.305054)
			(stroke
				(width 0.1)
				(type default)
			)
			(layer "F.Fab")
		)
		(fp_line
			(start -0.12065 -0.305054)
			(end -0.12065 -0.2794)
			(stroke
				(width 0.1)
				(type default)
			)
			(layer "F.Fab")
		)
		(pad "1" smd circle
			(at -0.40005 0 270)
			(size 0 0)
			(layers "F.Cu" "F.Mask" "F.Paste")
			(net "MAX31790_U317_PWM_START1")
		)
		(pad "2" smd circle
			(at 0.40005 0 270)
			(size 0 0)
			(layers "F.Cu" "F.Mask" "F.Paste")
			(net "P3V3_AUX")
		)
	)
	(footprint ""
		(layer "F.Cu")
		(at 14.0589 -132.334 180)
		(property "Reference" "R5593"
			(at 0 0 180)
			(layer "F.SilkS")
			(hide yes)
			(effects
				(font
					(size 1.27 1.27)
				)
			)
		)
		(property "Value" ""
			(at 0 0 180)
			(layer "F.Fab")
			(effects
				(font
					(size 1.27 1.27)
				)
			)
		)
		(duplicate_pad_numbers_are_jumpers no)
		(fp_line
			(start 0.7874 0.4064)
			(end -0.7874 0.4064)
			(stroke
				(width 0.1524)
				(type default)
			)
			(layer "F.SilkS")
		)
		(fp_line
			(start 0.7874 -0.4064)
			(end 0.7874 0.4064)
			(stroke
				(width 0.1524)
				(type default)
			)
			(layer "F.SilkS")
		)
		(fp_line
			(start -0.7874 0.4064)
			(end -0.7874 -0.4064)
			(stroke
				(width 0.1524)
				(type default)
			)
			(layer "F.SilkS")
		)
		(fp_line
			(start -0.7874 -0.4064)
			(end 0.7874 -0.4064)
			(stroke
				(width 0.1524)
				(type default)
			)
			(layer "F.SilkS")
		)
		(fp_line
			(start 0.67945 0.3048)
			(end 0.120396 0.3048)
			(stroke
				(width 0.1)
				(type default)
			)
			(layer "F.Fab")
		)
		(fp_line
			(start 0.67945 -0.3048)
			(end 0.67945 0.3048)
			(stroke
				(width 0.1)
				(type default)
			)
			(layer "F.Fab")
		)
		(fp_line
			(start 0.12065 -0.2794)
			(end 0.12065 -0.3048)
			(stroke
				(width 0.1)
				(type default)
			)
			(layer "F.Fab")
		)
		(fp_line
			(start 0.12065 -0.3048)
			(end 0.67945 -0.3048)
			(stroke
				(width 0.1)
				(type default)
			)
			(layer "F.Fab")
		)
		(fp_line
			(start 0.120396 0.3048)
			(end 0.120396 0.2794)
			(stroke
				(width 0.1)
				(type default)
			)
			(layer "F.Fab")
		)
		(fp_line
			(start 0.120396 0.2794)
			(end -0.12065 0.2794)
			(stroke
				(width 0.1)
				(type default)
			)
			(layer "F.Fab")
		)
		(fp_line
			(start -0.12065 0.3048)
			(end -0.67945 0.3048)
			(stroke
				(width 0.1)
				(type default)
			)
			(layer "F.Fab")
		)
		(fp_line
			(start -0.12065 0.2794)
			(end -0.12065 0.3048)
			(stroke
				(width 0.1)
				(type default)
			)
			(layer "F.Fab")
		)
		(fp_line
			(start -0.12065 -0.2794)
			(end 0.12065 -0.2794)
			(stroke
				(width 0.1)
				(type default)
			)
			(layer "F.Fab")
		)
		(fp_line
			(start -0.12065 -0.305054)
			(end -0.12065 -0.2794)
			(stroke
				(width 0.1)
				(type default)
			)
			(layer "F.Fab")
		)
		(fp_line
			(start -0.67945 0.3048)
			(end -0.67945 -0.305054)
			(stroke
				(width 0.1)
				(type default)
			)
			(layer "F.Fab")
		)
		(fp_line
			(start -0.67945 -0.305054)
			(end -0.12065 -0.305054)
			(stroke
				(width 0.1)
				(type default)
			)
			(layer "F.Fab")
		)
		(pad "1" smd rect
			(at -0.40005 0)
			(size 0.4572 0.508)
			(layers "F.Cu" "F.Mask" "F.Paste")
			(net "FAN_7_TACH_IL")
		)
		(pad "2" smd rect
			(at 0.40005 0)
			(size 0.4572 0.508)
			(layers "F.Cu" "F.Mask" "F.Paste")
			(net "FAN_7_TACH_IL_R2")
		)
	)
	(footprint ""
		(layer "F.Cu")
		(at 44.667932 -71.304912 -90)
		(property "Reference" "C2068"
			(at 0 0 270)
			(layer "F.SilkS")
			(hide yes)
			(effects
				(font
					(size 1.27 1.27)
				)
			)
		)
		(property "Value" ""
			(at 0 0 270)
			(layer "F.Fab")
			(effects
				(font
					(size 1.27 1.27)
				)
			)
		)
		(duplicate_pad_numbers_are_jumpers no)
		(fp_line
			(start -0.7874 0.4064)
			(end -0.7874 -0.4064)
			(stroke
				(width 0.1524)
				(type default)
			)
			(layer "F.SilkS")
		)
		(fp_line
			(start 0.7874 0.4064)
			(end -0.7874 0.4064)
			(stroke
				(width 0.1524)
				(type default)
			)
			(layer "F.SilkS")
		)
		(fp_line
			(start -0.7874 -0.4064)
			(end 0.7874 -0.4064)
			(stroke
				(width 0.1524)
				(type default)
			)
			(layer "F.SilkS")
		)
		(fp_line
			(start 0.7874 -0.4064)
			(end 0.7874 0.4064)
			(stroke
				(width 0.1524)
				(type default)
			)
			(layer "F.SilkS")
		)
		(fp_line
			(start -0.67945 0.3048)
			(end -0.67945 -0.305054)
			(stroke
				(width 0.1)
				(type default)
			)
			(layer "F.Fab")
		)
		(fp_line
			(start -0.12065 0.3048)
			(end -0.67945 0.3048)
			(stroke
				(width 0.1)
				(type default)
			)
			(layer "F.Fab")
		)
		(fp_line
			(start 0.120396 0.3048)
			(end 0.120396 0.2794)
			(stroke
				(width 0.1)
				(type default)
			)
			(layer "F.Fab")
		)
		(fp_line
			(start 0.67945 0.3048)
			(end 0.120396 0.3048)
			(stroke
				(width 0.1)
				(type default)
			)
			(layer "F.Fab")
		)
		(fp_line
			(start -0.12065 0.2794)
			(end -0.12065 0.3048)
			(stroke
				(width 0.1)
				(type default)
			)
			(layer "F.Fab")
		)
		(fp_line
			(start 0.120396 0.2794)
			(end -0.12065 0.2794)
			(stroke
				(width 0.1)
				(type default)
			)
			(layer "F.Fab")
		)
		(fp_line
			(start -0.12065 -0.2794)
			(end 0.12065 -0.2794)
			(stroke
				(width 0.1)
				(type default)
			)
			(layer "F.Fab")
		)
		(fp_line
			(start 0.12065 -0.2794)
			(end 0.12065 -0.3048)
			(stroke
				(width 0.1)
				(type default)
			)
			(layer "F.Fab")
		)
		(fp_line
			(start 0.12065 -0.3048)
			(end 0.67945 -0.3048)
			(stroke
				(width 0.1)
				(type default)
			)
			(layer "F.Fab")
		)
		(fp_line
			(start 0.67945 -0.3048)
			(end 0.67945 0.3048)
			(stroke
				(width 0.1)
				(type default)
			)
			(layer "F.Fab")
		)
		(fp_line
			(start -0.67945 -0.305054)
			(end -0.12065 -0.305054)
			(stroke
				(width 0.1)
				(type default)
			)
			(layer "F.Fab")
		)
		(fp_line
			(start -0.12065 -0.305054)
			(end -0.12065 -0.2794)
			(stroke
				(width 0.1)
				(type default)
			)
			(layer "F.Fab")
		)
		(pad "1" smd circle
			(at -0.40005 0 270)
			(size 0 0)
			(layers "F.Cu" "F.Mask" "F.Paste")
			(net "P3V3_AUX")
		)
		(pad "2" smd circle
			(at 0.40005 0 270)
			(size 0 0)
			(layers "F.Cu" "F.Mask" "F.Paste")
			(net "GND")
		)
	)
	(footprint ""
		(layer "F.Cu")
		(at 37.846 -127.508 180)
		(property "Reference" "R5605"
			(at 0 0 180)
			(layer "F.SilkS")
			(hide yes)
			(effects
				(font
					(size 1.27 1.27)
				)
			)
		)
		(property "Value" ""
			(at 0 0 180)
			(layer "F.Fab")
			(effects
				(font
					(size 1.27 1.27)
				)
			)
		)
		(duplicate_pad_numbers_are_jumpers no)
		(fp_line
			(start 0.7874 0.4064)
			(end -0.7874 0.4064)
			(stroke
				(width 0.1524)
				(type default)
			)
			(layer "F.SilkS")
		)
		(fp_line
			(start 0.7874 -0.4064)
			(end 0.7874 0.4064)
			(stroke
				(width 0.1524)
				(type default)
			)
			(layer "F.SilkS")
		)
		(fp_line
			(start -0.7874 0.4064)
			(end -0.7874 -0.4064)
			(stroke
				(width 0.1524)
				(type default)
			)
			(layer "F.SilkS")
		)
		(fp_line
			(start -0.7874 -0.4064)
			(end 0.7874 -0.4064)
			(stroke
				(width 0.1524)
				(type default)
			)
			(layer "F.SilkS")
		)
		(fp_line
			(start 0.67945 0.3048)
			(end 0.120396 0.3048)
			(stroke
				(width 0.1)
				(type default)
			)
			(layer "F.Fab")
		)
		(fp_line
			(start 0.67945 -0.3048)
			(end 0.67945 0.3048)
			(stroke
				(width 0.1)
				(type default)
			)
			(layer "F.Fab")
		)
		(fp_line
			(start 0.12065 -0.2794)
			(end 0.12065 -0.3048)
			(stroke
				(width 0.1)
				(type default)
			)
			(layer "F.Fab")
		)
		(fp_line
			(start 0.12065 -0.3048)
			(end 0.67945 -0.3048)
			(stroke
				(width 0.1)
				(type default)
			)
			(layer "F.Fab")
		)
		(fp_line
			(start 0.120396 0.3048)
			(end 0.120396 0.2794)
			(stroke
				(width 0.1)
				(type default)
			)
			(layer "F.Fab")
		)
		(fp_line
			(start 0.120396 0.2794)
			(end -0.12065 0.2794)
			(stroke
				(width 0.1)
				(type default)
			)
			(layer "F.Fab")
		)
		(fp_line
			(start -0.12065 0.3048)
			(end -0.67945 0.3048)
			(stroke
				(width 0.1)
				(type default)
			)
			(layer "F.Fab")
		)
		(fp_line
			(start -0.12065 0.2794)
			(end -0.12065 0.3048)
			(stroke
				(width 0.1)
				(type default)
			)
			(layer "F.Fab")
		)
		(fp_line
			(start -0.12065 -0.2794)
			(end 0.12065 -0.2794)
			(stroke
				(width 0.1)
				(type default)
			)
			(layer "F.Fab")
		)
		(fp_line
			(start -0.12065 -0.305054)
			(end -0.12065 -0.2794)
			(stroke
				(width 0.1)
				(type default)
			)
			(layer "F.Fab")
		)
		(fp_line
			(start -0.67945 0.3048)
			(end -0.67945 -0.305054)
			(stroke
				(width 0.1)
				(type default)
			)
			(layer "F.Fab")
		)
		(fp_line
			(start -0.67945 -0.305054)
			(end -0.12065 -0.305054)
			(stroke
				(width 0.1)
				(type default)
			)
			(layer "F.Fab")
		)
		(pad "1" smd rect
			(at -0.40005 0)
			(size 0.4572 0.508)
			(layers "F.Cu" "F.Mask" "F.Paste")
			(net "FAN_3_TACH_IL")
		)
		(pad "2" smd rect
			(at 0.40005 0)
			(size 0.4572 0.508)
			(layers "F.Cu" "F.Mask" "F.Paste")
			(net "FAN_3_TACH_IL_R1")
		)
	)
	(footprint ""
		(layer "F.Cu")
		(at 32.258 -294.894 90)
		(property "Reference" "R5387"
			(at 0 0 90)
			(layer "F.SilkS")
			(hide yes)
			(effects
				(font
					(size 1.27 1.27)
				)
			)
		)
		(property "Value" ""
			(at 0 0 90)
			(layer "F.Fab")
			(effects
				(font
					(size 1.27 1.27)
				)
			)
		)
		(duplicate_pad_numbers_are_jumpers no)
		(fp_line
			(start 0.7874 -0.4064)
			(end 0.7874 0.4064)
			(stroke
				(width 0.1524)
				(type default)
			)
			(layer "F.SilkS")
		)
		(fp_line
			(start -0.7874 -0.4064)
			(end 0.7874 -0.4064)
			(stroke
				(width 0.1524)
				(type default)
			)
			(layer "F.SilkS")
		)
		(fp_line
			(start 0.7874 0.4064)
			(end -0.7874 0.4064)
			(stroke
				(width 0.1524)
				(type default)
			)
			(layer "F.SilkS")
		)
		(fp_line
			(start -0.7874 0.4064)
			(end -0.7874 -0.4064)
			(stroke
				(width 0.1524)
				(type default)
			)
			(layer "F.SilkS")
		)
		(fp_line
			(start -0.12065 -0.305054)
			(end -0.12065 -0.2794)
			(stroke
				(width 0.1)
				(type default)
			)
			(layer "F.Fab")
		)
		(fp_line
			(start -0.67945 -0.305054)
			(end -0.12065 -0.305054)
			(stroke
				(width 0.1)
				(type default)
			)
			(layer "F.Fab")
		)
		(fp_line
			(start 0.67945 -0.3048)
			(end 0.67945 0.3048)
			(stroke
				(width 0.1)
				(type default)
			)
			(layer "F.Fab")
		)
		(fp_line
			(start 0.12065 -0.3048)
			(end 0.67945 -0.3048)
			(stroke
				(width 0.1)
				(type default)
			)
			(layer "F.Fab")
		)
		(fp_line
			(start 0.12065 -0.2794)
			(end 0.12065 -0.3048)
			(stroke
				(width 0.1)
				(type default)
			)
			(layer "F.Fab")
		)
		(fp_line
			(start -0.12065 -0.2794)
			(end 0.12065 -0.2794)
			(stroke
				(width 0.1)
				(type default)
			)
			(layer "F.Fab")
		)
		(fp_line
			(start 0.120396 0.2794)
			(end -0.12065 0.2794)
			(stroke
				(width 0.1)
				(type default)
			)
			(layer "F.Fab")
		)
		(fp_line
			(start -0.12065 0.2794)
			(end -0.12065 0.3048)
			(stroke
				(width 0.1)
				(type default)
			)
			(layer "F.Fab")
		)
		(fp_line
			(start 0.67945 0.3048)
			(end 0.120396 0.3048)
			(stroke
				(width 0.1)
				(type default)
			)
			(layer "F.Fab")
		)
		(fp_line
			(start 0.120396 0.3048)
			(end 0.120396 0.2794)
			(stroke
				(width 0.1)
				(type default)
			)
			(layer "F.Fab")
		)
		(fp_line
			(start -0.12065 0.3048)
			(end -0.67945 0.3048)
			(stroke
				(width 0.1)
				(type default)
			)
			(layer "F.Fab")
		)
		(fp_line
			(start -0.67945 0.3048)
			(end -0.67945 -0.305054)
			(stroke
				(width 0.1)
				(type default)
			)
			(layer "F.Fab")
		)
		(pad "1" smd circle
			(at -0.40005 0 90)
			(size 0 0)
			(layers "F.Cu" "F.Mask" "F.Paste")
			(net "P3V3_AUX")
		)
		(pad "2" smd circle
			(at 0.40005 0 90)
			(size 0 0)
			(layers "F.Cu" "F.Mask" "F.Paste")
			(net "FAN_0_FAIL_R_LED")
		)
	)
	(footprint ""
		(layer "F.Cu")
		(at 14.234922 -286.6771 180)
		(property "Reference" "R5238"
			(at 0 0 180)
			(layer "F.SilkS")
			(hide yes)
			(effects
				(font
					(size 1.27 1.27)
				)
			)
		)
		(property "Value" ""
			(at 0 0 180)
			(layer "F.Fab")
			(effects
				(font
					(size 1.27 1.27)
				)
			)
		)
		(duplicate_pad_numbers_are_jumpers no)
		(fp_line
			(start 0.7874 0.4064)
			(end -0.7874 0.4064)
			(stroke
				(width 0.1524)
				(type default)
			)
			(layer "F.SilkS")
		)
		(fp_line
			(start 0.7874 -0.4064)
			(end 0.7874 0.4064)
			(stroke
				(width 0.1524)
				(type default)
			)
			(layer "F.SilkS")
		)
		(fp_line
			(start -0.7874 0.4064)
			(end -0.7874 -0.4064)
			(stroke
				(width 0.1524)
				(type default)
			)
			(layer "F.SilkS")
		)
		(fp_line
			(start -0.7874 -0.4064)
			(end 0.7874 -0.4064)
			(stroke
				(width 0.1524)
				(type default)
			)
			(layer "F.SilkS")
		)
		(fp_line
			(start 0.67945 0.3048)
			(end 0.120396 0.3048)
			(stroke
				(width 0.1)
				(type default)
			)
			(layer "F.Fab")
		)
		(fp_line
			(start 0.67945 -0.3048)
			(end 0.67945 0.3048)
			(stroke
				(width 0.1)
				(type default)
			)
			(layer "F.Fab")
		)
		(fp_line
			(start 0.12065 -0.2794)
			(end 0.12065 -0.3048)
			(stroke
				(width 0.1)
				(type default)
			)
			(layer "F.Fab")
		)
		(fp_line
			(start 0.12065 -0.3048)
			(end 0.67945 -0.3048)
			(stroke
				(width 0.1)
				(type default)
			)
			(layer "F.Fab")
		)
		(fp_line
			(start 0.120396 0.3048)
			(end 0.120396 0.2794)
			(stroke
				(width 0.1)
				(type default)
			)
			(layer "F.Fab")
		)
		(fp_line
			(start 0.120396 0.2794)
			(end -0.12065 0.2794)
			(stroke
				(width 0.1)
				(type default)
			)
			(layer "F.Fab")
		)
		(fp_line
			(start -0.12065 0.3048)
			(end -0.67945 0.3048)
			(stroke
				(width 0.1)
				(type default)
			)
			(layer "F.Fab")
		)
		(fp_line
			(start -0.12065 0.2794)
			(end -0.12065 0.3048)
			(stroke
				(width 0.1)
				(type default)
			)
			(layer "F.Fab")
		)
		(fp_line
			(start -0.12065 -0.2794)
			(end 0.12065 -0.2794)
			(stroke
				(width 0.1)
				(type default)
			)
			(layer "F.Fab")
		)
		(fp_line
			(start -0.12065 -0.305054)
			(end -0.12065 -0.2794)
			(stroke
				(width 0.1)
				(type default)
			)
			(layer "F.Fab")
		)
		(fp_line
			(start -0.67945 0.3048)
			(end -0.67945 -0.305054)
			(stroke
				(width 0.1)
				(type default)
			)
			(layer "F.Fab")
		)
		(fp_line
			(start -0.67945 -0.305054)
			(end -0.12065 -0.305054)
			(stroke
				(width 0.1)
				(type default)
			)
			(layer "F.Fab")
		)
		(pad "1" smd circle
			(at -0.40005 0 180)
			(size 0 0)
			(layers "F.Cu" "F.Mask" "F.Paste")
			(net "FAN_7_PWM_OL")
		)
		(pad "2" smd circle
			(at 0.40005 0 180)
			(size 0 0)
			(layers "F.Cu" "F.Mask" "F.Paste")
			(net "FAN_7_PWM_OL_R")
		)
	)
	(footprint ""
		(layer "F.Cu")
		(at 40.894 -217.424 -90)
		(property "Reference" "R5651"
			(at 0 0 270)
			(layer "F.SilkS")
			(hide yes)
			(effects
				(font
					(size 1.27 1.27)
				)
			)
		)
		(property "Value" ""
			(at 0 0 270)
			(layer "F.Fab")
			(effects
				(font
					(size 1.27 1.27)
				)
			)
		)
		(duplicate_pad_numbers_are_jumpers no)
		(fp_line
			(start -0.7874 0.4064)
			(end -0.7874 -0.4064)
			(stroke
				(width 0.1524)
				(type default)
			)
			(layer "F.SilkS")
		)
		(fp_line
			(start 0.7874 0.4064)
			(end -0.7874 0.4064)
			(stroke
				(width 0.1524)
				(type default)
			)
			(layer "F.SilkS")
		)
		(fp_line
			(start -0.7874 -0.4064)
			(end 0.7874 -0.4064)
			(stroke
				(width 0.1524)
				(type default)
			)
			(layer "F.SilkS")
		)
		(fp_line
			(start 0.7874 -0.4064)
			(end 0.7874 0.4064)
			(stroke
				(width 0.1524)
				(type default)
			)
			(layer "F.SilkS")
		)
		(fp_line
			(start -0.67945 0.3048)
			(end -0.67945 -0.305054)
			(stroke
				(width 0.1)
				(type default)
			)
			(layer "F.Fab")
		)
		(fp_line
			(start -0.12065 0.3048)
			(end -0.67945 0.3048)
			(stroke
				(width 0.1)
				(type default)
			)
			(layer "F.Fab")
		)
		(fp_line
			(start 0.120396 0.3048)
			(end 0.120396 0.2794)
			(stroke
				(width 0.1)
				(type default)
			)
			(layer "F.Fab")
		)
		(fp_line
			(start 0.67945 0.3048)
			(end 0.120396 0.3048)
			(stroke
				(width 0.1)
				(type default)
			)
			(layer "F.Fab")
		)
		(fp_line
			(start -0.12065 0.2794)
			(end -0.12065 0.3048)
			(stroke
				(width 0.1)
				(type default)
			)
			(layer "F.Fab")
		)
		(fp_line
			(start 0.120396 0.2794)
			(end -0.12065 0.2794)
			(stroke
				(width 0.1)
				(type default)
			)
			(layer "F.Fab")
		)
		(fp_line
			(start -0.12065 -0.2794)
			(end 0.12065 -0.2794)
			(stroke
				(width 0.1)
				(type default)
			)
			(layer "F.Fab")
		)
		(fp_line
			(start 0.12065 -0.2794)
			(end 0.12065 -0.3048)
			(stroke
				(width 0.1)
				(type default)
			)
			(layer "F.Fab")
		)
		(fp_line
			(start 0.12065 -0.3048)
			(end 0.67945 -0.3048)
			(stroke
				(width 0.1)
				(type default)
			)
			(layer "F.Fab")
		)
		(fp_line
			(start 0.67945 -0.3048)
			(end 0.67945 0.3048)
			(stroke
				(width 0.1)
				(type default)
			)
			(layer "F.Fab")
		)
		(fp_line
			(start -0.67945 -0.305054)
			(end -0.12065 -0.305054)
			(stroke
				(width 0.1)
				(type default)
			)
			(layer "F.Fab")
		)
		(fp_line
			(start -0.12065 -0.305054)
			(end -0.12065 -0.2794)
			(stroke
				(width 0.1)
				(type default)
			)
			(layer "F.Fab")
		)
		(pad "1" smd circle
			(at -0.40005 0 270)
			(size 0 0)
			(layers "F.Cu" "F.Mask" "F.Paste")
			(net "FAN_1_PRESENT")
		)
		(pad "2" smd circle
			(at 0.40005 0 270)
			(size 0 0)
			(layers "F.Cu" "F.Mask" "F.Paste")
			(net "GND")
		)
	)
	(footprint ""
		(layer "F.Cu")
		(at 3.937 -310.134 180)
		(property "Reference" "C2050"
			(at 0 0 180)
			(layer "F.SilkS")
			(hide yes)
			(effects
				(font
					(size 1.27 1.27)
				)
			)
		)
		(property "Value" ""
			(at 0 0 180)
			(layer "F.Fab")
			(effects
				(font
					(size 1.27 1.27)
				)
			)
		)
		(duplicate_pad_numbers_are_jumpers no)
		(fp_line
			(start 1.524 0.762)
			(end -1.524 0.762)
			(stroke
				(width 0.1524)
				(type default)
			)
			(layer "F.SilkS")
		)
		(fp_line
			(start 1.524 -0.762)
			(end 1.524 0.762)
			(stroke
				(width 0.1524)
				(type default)
			)
			(layer "F.SilkS")
		)
		(fp_line
			(start -1.524 0.762)
			(end -1.524 -0.762)
			(stroke
				(width 0.1524)
				(type default)
			)
			(layer "F.SilkS")
		)
		(fp_line
			(start -1.524 -0.762)
			(end 1.524 -0.762)
			(stroke
				(width 0.1524)
				(type default)
			)
			(layer "F.SilkS")
		)
		(fp_line
			(start 1.1049 0.724916)
			(end 1.1049 -0.724916)
			(stroke
				(width 0.1)
				(type default)
			)
			(layer "F.Fab")
		)
		(fp_line
			(start 1.1049 -0.724916)
			(end -1.1049 -0.724916)
			(stroke
				(width 0.1)
				(type default)
			)
			(layer "F.Fab")
		)
		(fp_line
			(start -1.1049 0.724916)
			(end 1.1049 0.724916)
			(stroke
				(width 0.1)
				(type default)
			)
			(layer "F.Fab")
		)
		(fp_line
			(start -1.1049 -0.724916)
			(end -1.1049 0.724916)
			(stroke
				(width 0.1)
				(type default)
			)
			(layer "F.Fab")
		)
		(pad "1" smd rect
			(at -0.889 0)
			(size 1.016 1.27)
			(layers "F.Cu" "F.Mask" "F.Paste")
			(net "P12V_LED_FAN7")
		)
		(pad "2" smd rect
			(at 0.889 0)
			(size 1.016 1.27)
			(layers "F.Cu" "F.Mask" "F.Paste")
			(net "GND")
		)
	)
	(footprint ""
		(layer "F.Cu")
		(at 29.337 -292.1 -90)
		(property "Reference" "R5522"
			(at 0 0 270)
			(layer "F.SilkS")
			(hide yes)
			(effects
				(font
					(size 1.27 1.27)
				)
			)
		)
		(property "Value" ""
			(at 0 0 270)
			(layer "F.Fab")
			(effects
				(font
					(size 1.27 1.27)
				)
			)
		)
		(duplicate_pad_numbers_are_jumpers no)
		(fp_line
			(start -0.7874 0.4064)
			(end -0.7874 -0.4064)
			(stroke
				(width 0.1524)
				(type default)
			)
			(layer "F.SilkS")
		)
		(fp_line
			(start 0.7874 0.4064)
			(end -0.7874 0.4064)
			(stroke
				(width 0.1524)
				(type default)
			)
			(layer "F.SilkS")
		)
		(fp_line
			(start -0.7874 -0.4064)
			(end 0.7874 -0.4064)
			(stroke
				(width 0.1524)
				(type default)
			)
			(layer "F.SilkS")
		)
		(fp_line
			(start 0.7874 -0.4064)
			(end 0.7874 0.4064)
			(stroke
				(width 0.1524)
				(type default)
			)
			(layer "F.SilkS")
		)
		(fp_line
			(start -0.67945 0.3048)
			(end -0.67945 -0.305054)
			(stroke
				(width 0.1)
				(type default)
			)
			(layer "F.Fab")
		)
		(fp_line
			(start -0.12065 0.3048)
			(end -0.67945 0.3048)
			(stroke
				(width 0.1)
				(type default)
			)
			(layer "F.Fab")
		)
		(fp_line
			(start 0.120396 0.3048)
			(end 0.120396 0.2794)
			(stroke
				(width 0.1)
				(type default)
			)
			(layer "F.Fab")
		)
		(fp_line
			(start 0.67945 0.3048)
			(end 0.120396 0.3048)
			(stroke
				(width 0.1)
				(type default)
			)
			(layer "F.Fab")
		)
		(fp_line
			(start -0.12065 0.2794)
			(end -0.12065 0.3048)
			(stroke
				(width 0.1)
				(type default)
			)
			(layer "F.Fab")
		)
		(fp_line
			(start 0.120396 0.2794)
			(end -0.12065 0.2794)
			(stroke
				(width 0.1)
				(type default)
			)
			(layer "F.Fab")
		)
		(fp_line
			(start -0.12065 -0.2794)
			(end 0.12065 -0.2794)
			(stroke
				(width 0.1)
				(type default)
			)
			(layer "F.Fab")
		)
		(fp_line
			(start 0.12065 -0.2794)
			(end 0.12065 -0.3048)
			(stroke
				(width 0.1)
				(type default)
			)
			(layer "F.Fab")
		)
		(fp_line
			(start 0.12065 -0.3048)
			(end 0.67945 -0.3048)
			(stroke
				(width 0.1)
				(type default)
			)
			(layer "F.Fab")
		)
		(fp_line
			(start 0.67945 -0.3048)
			(end 0.67945 0.3048)
			(stroke
				(width 0.1)
				(type default)
			)
			(layer "F.Fab")
		)
		(fp_line
			(start -0.67945 -0.305054)
			(end -0.12065 -0.305054)
			(stroke
				(width 0.1)
				(type default)
			)
			(layer "F.Fab")
		)
		(fp_line
			(start -0.12065 -0.305054)
			(end -0.12065 -0.2794)
			(stroke
				(width 0.1)
				(type default)
			)
			(layer "F.Fab")
		)
		(pad "1" smd circle
			(at -0.40005 0 270)
			(size 0 0)
			(layers "F.Cu" "F.Mask" "F.Paste")
			(net "P3V3_AUX")
		)
		(pad "2" smd circle
			(at 0.40005 0 270)
			(size 0 0)
			(layers "F.Cu" "F.Mask" "F.Paste")
			(net "FAN_7_PWM")
		)
	)
	(footprint ""
		(layer "F.Cu")
		(at 45.339 -4.445)
		(property "Reference" "H14"
			(at -1.143 -3.27533 0)
			(unlocked yes)
			(layer "F.SilkS")
			(effects
				(font
					(size 0.7874 0.5842)
					(thickness 0.1524)
				)
				(justify left)
			)
		)
		(property "Value" ""
			(at 0 0 0)
			(layer "F.Fab")
			(effects
				(font
					(size 1.27 1.27)
				)
			)
		)
		(duplicate_pad_numbers_are_jumpers no)
		(fp_circle
			(center 0 0)
			(end 2.4003 0)
			(stroke
				(width 0.1524)
				(type default)
			)
			(fill no)
			(layer "F.SilkS")
		)
		(fp_circle
			(center 0 0)
			(end 6.5913 0)
			(stroke
				(width 0.1524)
				(type default)
			)
			(fill no)
			(layer "B.SilkS")
		)
		(fp_circle
			(center 0 0)
			(end 6.5913 0)
			(stroke
				(width 0.1)
				(type default)
			)
			(fill no)
			(layer "B.Fab")
		)
		(fp_circle
			(center 0 0)
			(end 2.4003 0)
			(stroke
				(width 0.1)
				(type default)
			)
			(fill no)
			(layer "F.Fab")
		)
		(pad "" np_thru_hole circle
			(at 0 0)
			(size 3.175 3.175)
			(drill 3.175)
			(layers "*.Cu" "*.Mask")
			(clearance 0.381)
			(thermal_gap 0.381)
		)
		(zone
			(layers "F.Cu" "B.Cu" "In1.Cu" "In2.Cu" "In3.Cu" "In4.Cu")
			(hatch none 0.5)
			(connect_pads
				(clearance 0)
			)
			(min_thickness 0.25)
			(keepout
				(tracks not_allowed)
				(vias allowed)
				(pads allowed)
				(copperpour not_allowed)
				(footprints allowed)
			)
			(placement
				(enabled no)
				(sheetname "")
			)
			(fill
				(thermal_gap 0.5)
				(thermal_bridge_width 0.5)
				(island_removal_mode 0)
			)
			(polygon
				(pts
					(arc
						(start 47.4345 -4.445)
						(mid 43.2435 -4.445)
						(end 47.4345 -4.445)
					)
				)
			)
		)
	)
	(footprint ""
		(layer "F.Cu")
		(at 42.037 -189.738)
		(property "Reference" "R4966"
			(at 0 0 0)
			(layer "F.SilkS")
			(hide yes)
			(effects
				(font
					(size 1.27 1.27)
				)
			)
		)
		(property "Value" ""
			(at 0 0 0)
			(layer "F.Fab")
			(effects
				(font
					(size 1.27 1.27)
				)
			)
		)
		(duplicate_pad_numbers_are_jumpers no)
		(fp_line
			(start -0.7874 -0.4064)
			(end 0.7874 -0.4064)
			(stroke
				(width 0.1524)
				(type default)
			)
			(layer "F.SilkS")
		)
		(fp_line
			(start -0.7874 0.4064)
			(end -0.7874 -0.4064)
			(stroke
				(width 0.1524)
				(type default)
			)
			(layer "F.SilkS")
		)
		(fp_line
			(start 0.7874 -0.4064)
			(end 0.7874 0.4064)
			(stroke
				(width 0.1524)
				(type default)
			)
			(layer "F.SilkS")
		)
		(fp_line
			(start 0.7874 0.4064)
			(end -0.7874 0.4064)
			(stroke
				(width 0.1524)
				(type default)
			)
			(layer "F.SilkS")
		)
		(fp_line
			(start -0.67945 -0.305054)
			(end -0.12065 -0.305054)
			(stroke
				(width 0.1)
				(type default)
			)
			(layer "F.Fab")
		)
		(fp_line
			(start -0.67945 0.3048)
			(end -0.67945 -0.305054)
			(stroke
				(width 0.1)
				(type default)
			)
			(layer "F.Fab")
		)
		(fp_line
			(start -0.12065 -0.305054)
			(end -0.12065 -0.2794)
			(stroke
				(width 0.1)
				(type default)
			)
			(layer "F.Fab")
		)
		(fp_line
			(start -0.12065 -0.2794)
			(end 0.12065 -0.2794)
			(stroke
				(width 0.1)
				(type default)
			)
			(layer "F.Fab")
		)
		(fp_line
			(start -0.12065 0.2794)
			(end -0.12065 0.3048)
			(stroke
				(width 0.1)
				(type default)
			)
			(layer "F.Fab")
		)
		(fp_line
			(start -0.12065 0.3048)
			(end -0.67945 0.3048)
			(stroke
				(width 0.1)
				(type default)
			)
			(layer "F.Fab")
		)
		(fp_line
			(start 0.120396 0.2794)
			(end -0.12065 0.2794)
			(stroke
				(width 0.1)
				(type default)
			)
			(layer "F.Fab")
		)
		(fp_line
			(start 0.120396 0.3048)
			(end 0.120396 0.2794)
			(stroke
				(width 0.1)
				(type default)
			)
			(layer "F.Fab")
		)
		(fp_line
			(start 0.12065 -0.3048)
			(end 0.67945 -0.3048)
			(stroke
				(width 0.1)
				(type default)
			)
			(layer "F.Fab")
		)
		(fp_line
			(start 0.12065 -0.2794)
			(end 0.12065 -0.3048)
			(stroke
				(width 0.1)
				(type default)
			)
			(layer "F.Fab")
		)
		(fp_line
			(start 0.67945 -0.3048)
			(end 0.67945 0.3048)
			(stroke
				(width 0.1)
				(type default)
			)
			(layer "F.Fab")
		)
		(fp_line
			(start 0.67945 0.3048)
			(end 0.120396 0.3048)
			(stroke
				(width 0.1)
				(type default)
			)
			(layer "F.Fab")
		)
		(pad "1" smd circle
			(at -0.40005 0)
			(size 0 0)
			(layers "F.Cu" "F.Mask" "F.Paste")
			(net "PD_FAN_BUFF_INPUT_U337F")
		)
		(pad "2" smd circle
			(at 0.40005 0)
			(size 0 0)
			(layers "F.Cu" "F.Mask" "F.Paste")
			(net "P3V3_AUX")
		)
	)
	(footprint ""
		(layer "F.Cu")
		(at 22.479 -300.99 90)
		(property "Reference" "U60"
			(at -0.254 -1.87833 90)
			(unlocked yes)
			(layer "F.SilkS")
			(effects
				(font
					(size 0.7874 0.5842)
					(thickness 0.1524)
				)
				(justify left)
			)
		)
		(property "Value" ""
			(at 0 0 90)
			(layer "F.Fab")
			(effects
				(font
					(size 1.27 1.27)
				)
			)
		)
		(duplicate_pad_numbers_are_jumpers no)
		(fp_line
			(start 1.33096 -1.100074)
			(end 1.33096 1.100074)
			(stroke
				(width 0.1524)
				(type default)
			)
			(layer "F.SilkS")
		)
		(fp_line
			(start 0.381 -1.100074)
			(end 1.33096 -1.100074)
			(stroke
				(width 0.1524)
				(type default)
			)
			(layer "F.SilkS")
		)
		(fp_line
			(start -0.381 -1.100074)
			(end 0 -0.649986)
			(stroke
				(width 0.1524)
				(type default)
			)
			(layer "F.SilkS")
		)
		(fp_line
			(start -1.33096 -1.100074)
			(end -0.381 -1.100074)
			(stroke
				(width 0.1524)
				(type default)
			)
			(layer "F.SilkS")
		)
		(fp_line
			(start 0 -0.649986)
			(end 0.381 -1.100074)
			(stroke
				(width 0.1524)
				(type default)
			)
			(layer "F.SilkS")
		)
		(fp_line
			(start 1.33096 1.100074)
			(end -1.33096 1.100074)
			(stroke
				(width 0.1524)
				(type default)
			)
			(layer "F.SilkS")
		)
		(fp_line
			(start -1.33096 1.100074)
			(end -1.33096 -1.100074)
			(stroke
				(width 0.1524)
				(type default)
			)
			(layer "F.SilkS")
		)
		(fp_poly
			(pts
				(xy -2.017776 -1.336294) (xy -2.271776 -0.896366) (xy -1.484884 -0.73533)
			)
			(stroke
				(width 0)
				(type default)
			)
			(fill yes)
			(layer "F.SilkS")
		)
		(fp_line
			(start 0.674878 -1.100074)
			(end 0.674878 1.100074)
			(stroke
				(width 0.1)
				(type default)
			)
			(layer "F.Fab")
		)
		(fp_line
			(start -0.674878 -1.100074)
			(end 0.674878 -1.100074)
			(stroke
				(width 0.1)
				(type default)
			)
			(layer "F.Fab")
		)
		(fp_line
			(start 0.674878 1.100074)
			(end -0.674878 1.100074)
			(stroke
				(width 0.1)
				(type default)
			)
			(layer "F.Fab")
		)
		(fp_line
			(start -0.674878 1.100074)
			(end -0.674878 -1.100074)
			(stroke
				(width 0.1)
				(type default)
			)
			(layer "F.Fab")
		)
		(fp_poly
			(pts
				(xy -2.209292 -0.902462) (xy -2.209292 -0.394462) (xy -1.447292 -0.648462)
			)
			(stroke
				(width 0)
				(type default)
			)
			(fill yes)
			(layer "F.Fab")
		)
		(pad "1" smd rect
			(at -0.94996 -0.649986 180)
			(size 0.4064 0.508)
			(layers "F.Cu" "F.Mask" "F.Paste")
			(net "NC_U60_P1")
		)
		(pad "2" smd rect
			(at -0.94996 0 180)
			(size 0.4064 0.508)
			(layers "F.Cu" "F.Mask" "F.Paste")
			(net "FAN_0_PWM")
		)
		(pad "3" smd rect
			(at -0.94996 0.649986 180)
			(size 0.4064 0.508)
			(layers "F.Cu" "F.Mask" "F.Paste")
			(net "GND")
		)
		(pad "4" smd rect
			(at 0.94996 0.649986 180)
			(size 0.4064 0.508)
			(layers "F.Cu" "F.Mask" "F.Paste")
			(net "FAN_0_PWM_BUF")
		)
		(pad "5" smd rect
			(at 0.94996 -0.649986 180)
			(size 0.4064 0.508)
			(layers "F.Cu" "F.Mask" "F.Paste")
			(net "P3V3_AUX")
		)
	)
	(footprint ""
		(layer "F.Cu")
		(at 32.131 -34.29)
		(property "Reference" "Q12"
			(at 0.39878 -2.61493 0)
			(unlocked yes)
			(layer "F.SilkS")
			(effects
				(font
					(size 0.7874 0.5842)
					(thickness 0.1524)
				)
				(justify left)
			)
		)
		(property "Value" ""
			(at 0 0 0)
			(layer "F.Fab")
			(effects
				(font
					(size 1.27 1.27)
				)
			)
		)
		(duplicate_pad_numbers_are_jumpers no)
		(fp_line
			(start -1.905 -1.651)
			(end 1.905 -1.651)
			(stroke
				(width 0.1524)
				(type default)
			)
			(layer "F.SilkS")
		)
		(fp_line
			(start -1.905 1.651)
			(end -1.905 -1.651)
			(stroke
				(width 0.1524)
				(type default)
			)
			(layer "F.SilkS")
		)
		(fp_line
			(start 1.905 -1.651)
			(end 1.905 1.651)
			(stroke
				(width 0.1524)
				(type default)
			)
			(layer "F.SilkS")
		)
		(fp_line
			(start 1.905 1.651)
			(end -1.905 1.651)
			(stroke
				(width 0.1524)
				(type default)
			)
			(layer "F.SilkS")
		)
		(fp_line
			(start -1.249934 -1.169924)
			(end -0.6985 -1.169924)
			(stroke
				(width 0.1)
				(type default)
			)
			(layer "F.Fab")
		)
		(fp_line
			(start -1.249934 -0.729996)
			(end -1.249934 -1.169924)
			(stroke
				(width 0.1)
				(type default)
			)
			(layer "F.Fab")
		)
		(fp_line
			(start -1.249934 0.729996)
			(end -0.6985 0.729996)
			(stroke
				(width 0.1)
				(type default)
			)
			(layer "F.Fab")
		)
		(fp_line
			(start -1.249934 1.169924)
			(end -1.249934 0.729996)
			(stroke
				(width 0.1)
				(type default)
			)
			(layer "F.Fab")
		)
		(fp_line
			(start -0.6985 -1.524)
			(end 0.6985 -1.524)
			(stroke
				(width 0.1)
				(type default)
			)
			(layer "F.Fab")
		)
		(fp_line
			(start -0.6985 -1.169924)
			(end -0.6985 -1.524)
			(stroke
				(width 0.1)
				(type default)
			)
			(layer "F.Fab")
		)
		(fp_line
			(start -0.6985 -0.729996)
			(end -1.249934 -0.729996)
			(stroke
				(width 0.1)
				(type default)
			)
			(layer "F.Fab")
		)
		(fp_line
			(start -0.6985 0.729996)
			(end -0.6985 -0.729996)
			(stroke
				(width 0.1)
				(type default)
			)
			(layer "F.Fab")
		)
		(fp_line
			(start -0.6985 1.169924)
			(end -1.249934 1.169924)
			(stroke
				(width 0.1)
				(type default)
			)
			(layer "F.Fab")
		)
		(fp_line
			(start -0.6985 1.524)
			(end -0.6985 1.169924)
			(stroke
				(width 0.1)
				(type default)
			)
			(layer "F.Fab")
		)
		(fp_line
			(start 0.6985 -1.524)
			(end 0.6985 -0.219964)
			(stroke
				(width 0.1)
				(type default)
			)
			(layer "F.Fab")
		)
		(fp_line
			(start 0.6985 -0.219964)
			(end 1.249934 -0.219964)
			(stroke
				(width 0.1)
				(type default)
			)
			(layer "F.Fab")
		)
		(fp_line
			(start 0.6985 0.219964)
			(end 0.6985 1.524)
			(stroke
				(width 0.1)
				(type default)
			)
			(layer "F.Fab")
		)
		(fp_line
			(start 0.6985 1.524)
			(end -0.6985 1.524)
			(stroke
				(width 0.1)
				(type default)
			)
			(layer "F.Fab")
		)
		(fp_line
			(start 1.249934 -0.219964)
			(end 1.249934 0.219964)
			(stroke
				(width 0.1)
				(type default)
			)
			(layer "F.Fab")
		)
		(fp_line
			(start 1.249934 0.219964)
			(end 0.6985 0.219964)
			(stroke
				(width 0.1)
				(type default)
			)
			(layer "F.Fab")
		)
		(fp_rect
			(start -0.6985 1.524)
			(end 0.6985 -1.524)
			(stroke
				(width 0)
				(type default)
			)
			(fill no)
			(layer "F.Fab")
		)
		(pad "D" smd rect
			(at 1.1176 0 270)
			(size 1.016 1.27)
			(layers "F.Cu" "F.Mask" "F.Paste")
			(net "P12V_LED_FAN3")
		)
		(pad "G" smd rect
			(at -1.1176 -1.016 270)
			(size 1.016 1.27)
			(layers "F.Cu" "F.Mask" "F.Paste")
			(net "U408_D1")
		)
		(pad "S" smd rect
			(at -1.1176 1.016 270)
			(size 1.016 1.27)
			(layers "F.Cu" "F.Mask" "F.Paste")
			(net "P12V_LED")
		)
	)
	(footprint ""
		(layer "F.Cu")
		(at 9.906 -173.228 180)
		(property "Reference" "U26"
			(at 2.00533 -1.016 90)
			(unlocked yes)
			(layer "F.SilkS")
			(effects
				(font
					(size 0.7874 0.5842)
					(thickness 0.1524)
				)
				(justify left)
			)
		)
		(property "Value" ""
			(at 0 0 180)
			(layer "F.Fab")
			(effects
				(font
					(size 1.27 1.27)
				)
			)
		)
		(duplicate_pad_numbers_are_jumpers no)
		(fp_line
			(start 1.3462 1.100074)
			(end -1.3462 1.100074)
			(stroke
				(width 0.1524)
				(type default)
			)
			(layer "F.SilkS")
		)
		(fp_line
			(start 1.3462 -1.100074)
			(end 1.3462 1.100074)
			(stroke
				(width 0.1524)
				(type default)
			)
			(layer "F.SilkS")
		)
		(fp_line
			(start 0.670052 -1.100074)
			(end 1.3462 -1.100074)
			(stroke
				(width 0.1524)
				(type default)
			)
			(layer "F.SilkS")
		)
		(fp_line
			(start 0 -0.381)
			(end 0.670052 -1.100074)
			(stroke
				(width 0.1524)
				(type default)
			)
			(layer "F.SilkS")
		)
		(fp_line
			(start -0.670052 -1.100074)
			(end 0 -0.381)
			(stroke
				(width 0.1524)
				(type default)
			)
			(layer "F.SilkS")
		)
		(fp_line
			(start -1.3462 1.100074)
			(end -1.3462 -1.100074)
			(stroke
				(width 0.1524)
				(type default)
			)
			(layer "F.SilkS")
		)
		(fp_line
			(start -1.3462 -1.100074)
			(end -0.670052 -1.100074)
			(stroke
				(width 0.1524)
				(type default)
			)
			(layer "F.SilkS")
		)
		(fp_poly
			(pts
				(xy -1.524 -0.649986) (xy -2.286 -1.030986) (xy -2.286 -0.268986)
			)
			(stroke
				(width 0)
				(type default)
			)
			(fill yes)
			(layer "F.SilkS")
		)
		(fp_line
			(start 1.100074 0.8001)
			(end 0.670052 0.8001)
			(stroke
				(width 0.1)
				(type default)
			)
			(layer "F.Fab")
		)
		(fp_line
			(start 1.100074 -0.8001)
			(end 1.100074 0.8001)
			(stroke
				(width 0.1)
				(type default)
			)
			(layer "F.Fab")
		)
		(fp_line
			(start 0.670052 1.100074)
			(end -0.670052 1.100074)
			(stroke
				(width 0.1)
				(type default)
			)
			(layer "F.Fab")
		)
		(fp_line
			(start 0.670052 0.8001)
			(end 0.670052 1.100074)
			(stroke
				(width 0.1)
				(type default)
			)
			(layer "F.Fab")
		)
		(fp_line
			(start 0.670052 -0.8001)
			(end 1.100074 -0.8001)
			(stroke
				(width 0.1)
				(type default)
			)
			(layer "F.Fab")
		)
		(fp_line
			(start 0.670052 -0.8001)
			(end 0.670052 0.8001)
			(stroke
				(width 0.1)
				(type default)
			)
			(layer "F.Fab")
		)
		(fp_line
			(start 0.670052 -1.100074)
			(end 0.670052 -0.8001)
			(stroke
				(width 0.1)
				(type default)
			)
			(layer "F.Fab")
		)
		(fp_line
			(start -0.670052 1.100074)
			(end -0.670052 0.8001)
			(stroke
				(width 0.1)
				(type default)
			)
			(layer "F.Fab")
		)
		(fp_line
			(start -0.670052 0.8001)
			(end -0.670052 -0.8001)
			(stroke
				(width 0.1)
				(type default)
			)
			(layer "F.Fab")
		)
		(fp_line
			(start -0.670052 0.8001)
			(end -1.100074 0.8001)
			(stroke
				(width 0.1)
				(type default)
			)
			(layer "F.Fab")
		)
		(fp_line
			(start -0.670052 -0.8001)
			(end -0.670052 -1.100074)
			(stroke
				(width 0.1)
				(type default)
			)
			(layer "F.Fab")
		)
		(fp_line
			(start -0.670052 -1.100074)
			(end 0.670052 -1.100074)
			(stroke
				(width 0.1)
				(type default)
			)
			(layer "F.Fab")
		)
		(fp_line
			(start -1.100074 0.8001)
			(end -1.100074 -0.8001)
			(stroke
				(width 0.1)
				(type default)
			)
			(layer "F.Fab")
		)
		(fp_line
			(start -1.100074 -0.8001)
			(end -0.670052 -0.8001)
			(stroke
				(width 0.1)
				(type default)
			)
			(layer "F.Fab")
		)
		(fp_poly
			(pts
				(xy -1.524 -0.649986) (xy -2.286 -1.030986) (xy -2.286 -0.268986)
			)
			(stroke
				(width 0)
				(type default)
			)
			(fill yes)
			(layer "F.Fab")
		)
		(pad "1" smd rect
			(at -0.94996 -0.649986 90)
			(size 0.4064 0.508)
			(layers "F.Cu" "F.Mask" "F.Paste")
			(net "FAN_6_PRESENT_N")
		)
		(pad "2" smd rect
			(at -0.94996 0 90)
			(size 0.4064 0.508)
			(layers "F.Cu" "F.Mask" "F.Paste")
			(net "GND")
		)
		(pad "3" smd rect
			(at -0.94996 0.649986 90)
			(size 0.4064 0.508)
			(layers "F.Cu" "F.Mask" "F.Paste")
			(net "FAN_7_PRESENT_N")
		)
		(pad "4" smd rect
			(at 0.94996 0.649986 90)
			(size 0.4064 0.508)
			(layers "F.Cu" "F.Mask" "F.Paste")
			(net "FAN_7_PRSNT_BUF_R_N")
		)
		(pad "5" smd rect
			(at 0.94996 0 90)
			(size 0.4064 0.508)
			(layers "F.Cu" "F.Mask" "F.Paste")
			(net "P3V3_AUX")
		)
		(pad "6" smd rect
			(at 0.94996 -0.649986 90)
			(size 0.4064 0.508)
			(layers "F.Cu" "F.Mask" "F.Paste")
			(net "FAN_6_PRSNT_BUF_R_N")
		)
	)
	(footprint ""
		(layer "F.Cu")
		(at 27.051 -13.8938 -90)
		(property "Reference" "R4988"
			(at 0 0 270)
			(layer "F.SilkS")
			(hide yes)
			(effects
				(font
					(size 1.27 1.27)
				)
			)
		)
		(property "Value" ""
			(at 0 0 270)
			(layer "F.Fab")
			(effects
				(font
					(size 1.27 1.27)
				)
			)
		)
		(duplicate_pad_numbers_are_jumpers no)
		(fp_line
			(start -0.7874 0.4064)
			(end -0.7874 -0.4064)
			(stroke
				(width 0.1524)
				(type default)
			)
			(layer "F.SilkS")
		)
		(fp_line
			(start 0.7874 0.4064)
			(end -0.7874 0.4064)
			(stroke
				(width 0.1524)
				(type default)
			)
			(layer "F.SilkS")
		)
		(fp_line
			(start -0.7874 -0.4064)
			(end 0.7874 -0.4064)
			(stroke
				(width 0.1524)
				(type default)
			)
			(layer "F.SilkS")
		)
		(fp_line
			(start 0.7874 -0.4064)
			(end 0.7874 0.4064)
			(stroke
				(width 0.1524)
				(type default)
			)
			(layer "F.SilkS")
		)
		(fp_line
			(start -0.67945 0.3048)
			(end -0.67945 -0.305054)
			(stroke
				(width 0.1)
				(type default)
			)
			(layer "F.Fab")
		)
		(fp_line
			(start -0.12065 0.3048)
			(end -0.67945 0.3048)
			(stroke
				(width 0.1)
				(type default)
			)
			(layer "F.Fab")
		)
		(fp_line
			(start 0.120396 0.3048)
			(end 0.120396 0.2794)
			(stroke
				(width 0.1)
				(type default)
			)
			(layer "F.Fab")
		)
		(fp_line
			(start 0.67945 0.3048)
			(end 0.120396 0.3048)
			(stroke
				(width 0.1)
				(type default)
			)
			(layer "F.Fab")
		)
		(fp_line
			(start -0.12065 0.2794)
			(end -0.12065 0.3048)
			(stroke
				(width 0.1)
				(type default)
			)
			(layer "F.Fab")
		)
		(fp_line
			(start 0.120396 0.2794)
			(end -0.12065 0.2794)
			(stroke
				(width 0.1)
				(type default)
			)
			(layer "F.Fab")
		)
		(fp_line
			(start -0.12065 -0.2794)
			(end 0.12065 -0.2794)
			(stroke
				(width 0.1)
				(type default)
			)
			(layer "F.Fab")
		)
		(fp_line
			(start 0.12065 -0.2794)
			(end 0.12065 -0.3048)
			(stroke
				(width 0.1)
				(type default)
			)
			(layer "F.Fab")
		)
		(fp_line
			(start 0.12065 -0.3048)
			(end 0.67945 -0.3048)
			(stroke
				(width 0.1)
				(type default)
			)
			(layer "F.Fab")
		)
		(fp_line
			(start 0.67945 -0.3048)
			(end 0.67945 0.3048)
			(stroke
				(width 0.1)
				(type default)
			)
			(layer "F.Fab")
		)
		(fp_line
			(start -0.67945 -0.305054)
			(end -0.12065 -0.305054)
			(stroke
				(width 0.1)
				(type default)
			)
			(layer "F.Fab")
		)
		(fp_line
			(start -0.12065 -0.305054)
			(end -0.12065 -0.2794)
			(stroke
				(width 0.1)
				(type default)
			)
			(layer "F.Fab")
		)
		(pad "1" smd circle
			(at -0.40005 0 270)
			(size 0 0)
			(layers "F.Cu" "F.Mask" "F.Paste")
			(net "P3V3_AUX")
		)
		(pad "2" smd circle
			(at 0.40005 0 270)
			(size 0 0)
			(layers "F.Cu" "F.Mask" "F.Paste")
			(net "SMB_PDBV_FAN_R_SDA")
		)
	)
	(footprint ""
		(layer "F.Cu")
		(at 35.179 -114.738912 180)
		(property "Reference" "C2041"
			(at 0 0 180)
			(layer "F.SilkS")
			(hide yes)
			(effects
				(font
					(size 1.27 1.27)
				)
			)
		)
		(property "Value" ""
			(at 0 0 180)
			(layer "F.Fab")
			(effects
				(font
					(size 1.27 1.27)
				)
			)
		)
		(duplicate_pad_numbers_are_jumpers no)
		(fp_line
			(start 0.7874 0.4064)
			(end -0.7874 0.4064)
			(stroke
				(width 0.1524)
				(type default)
			)
			(layer "F.SilkS")
		)
		(fp_line
			(start 0.7874 -0.4064)
			(end 0.7874 0.4064)
			(stroke
				(width 0.1524)
				(type default)
			)
			(layer "F.SilkS")
		)
		(fp_line
			(start -0.7874 0.4064)
			(end -0.7874 -0.4064)
			(stroke
				(width 0.1524)
				(type default)
			)
			(layer "F.SilkS")
		)
		(fp_line
			(start -0.7874 -0.4064)
			(end 0.7874 -0.4064)
			(stroke
				(width 0.1524)
				(type default)
			)
			(layer "F.SilkS")
		)
		(fp_line
			(start 0.67945 0.3048)
			(end 0.120396 0.3048)
			(stroke
				(width 0.1)
				(type default)
			)
			(layer "F.Fab")
		)
		(fp_line
			(start 0.67945 -0.3048)
			(end 0.67945 0.3048)
			(stroke
				(width 0.1)
				(type default)
			)
			(layer "F.Fab")
		)
		(fp_line
			(start 0.12065 -0.2794)
			(end 0.12065 -0.3048)
			(stroke
				(width 0.1)
				(type default)
			)
			(layer "F.Fab")
		)
		(fp_line
			(start 0.12065 -0.3048)
			(end 0.67945 -0.3048)
			(stroke
				(width 0.1)
				(type default)
			)
			(layer "F.Fab")
		)
		(fp_line
			(start 0.120396 0.3048)
			(end 0.120396 0.2794)
			(stroke
				(width 0.1)
				(type default)
			)
			(layer "F.Fab")
		)
		(fp_line
			(start 0.120396 0.2794)
			(end -0.12065 0.2794)
			(stroke
				(width 0.1)
				(type default)
			)
			(layer "F.Fab")
		)
		(fp_line
			(start -0.12065 0.3048)
			(end -0.67945 0.3048)
			(stroke
				(width 0.1)
				(type default)
			)
			(layer "F.Fab")
		)
		(fp_line
			(start -0.12065 0.2794)
			(end -0.12065 0.3048)
			(stroke
				(width 0.1)
				(type default)
			)
			(layer "F.Fab")
		)
		(fp_line
			(start -0.12065 -0.2794)
			(end 0.12065 -0.2794)
			(stroke
				(width 0.1)
				(type default)
			)
			(layer "F.Fab")
		)
		(fp_line
			(start -0.12065 -0.305054)
			(end -0.12065 -0.2794)
			(stroke
				(width 0.1)
				(type default)
			)
			(layer "F.Fab")
		)
		(fp_line
			(start -0.67945 0.3048)
			(end -0.67945 -0.305054)
			(stroke
				(width 0.1)
				(type default)
			)
			(layer "F.Fab")
		)
		(fp_line
			(start -0.67945 -0.305054)
			(end -0.12065 -0.305054)
			(stroke
				(width 0.1)
				(type default)
			)
			(layer "F.Fab")
		)
		(pad "1" smd circle
			(at -0.40005 0 180)
			(size 0 0)
			(layers "F.Cu" "F.Mask" "F.Paste")
			(net "FAN_2_PWM_IL_R")
		)
		(pad "2" smd circle
			(at 0.40005 0 180)
			(size 0 0)
			(layers "F.Cu" "F.Mask" "F.Paste")
			(net "GND")
		)
	)
	(footprint ""
		(layer "F.Cu")
		(at 28.956 -167.513)
		(property "Reference" "R5469"
			(at 0 0 0)
			(layer "F.SilkS")
			(hide yes)
			(effects
				(font
					(size 1.27 1.27)
				)
			)
		)
		(property "Value" ""
			(at 0 0 0)
			(layer "F.Fab")
			(effects
				(font
					(size 1.27 1.27)
				)
			)
		)
		(duplicate_pad_numbers_are_jumpers no)
		(fp_line
			(start -0.7874 -0.4064)
			(end 0.7874 -0.4064)
			(stroke
				(width 0.1524)
				(type default)
			)
			(layer "F.SilkS")
		)
		(fp_line
			(start -0.7874 0.4064)
			(end -0.7874 -0.4064)
			(stroke
				(width 0.1524)
				(type default)
			)
			(layer "F.SilkS")
		)
		(fp_line
			(start 0.7874 -0.4064)
			(end 0.7874 0.4064)
			(stroke
				(width 0.1524)
				(type default)
			)
			(layer "F.SilkS")
		)
		(fp_line
			(start 0.7874 0.4064)
			(end -0.7874 0.4064)
			(stroke
				(width 0.1524)
				(type default)
			)
			(layer "F.SilkS")
		)
		(fp_line
			(start -0.67945 -0.305054)
			(end -0.12065 -0.305054)
			(stroke
				(width 0.1)
				(type default)
			)
			(layer "F.Fab")
		)
		(fp_line
			(start -0.67945 0.3048)
			(end -0.67945 -0.305054)
			(stroke
				(width 0.1)
				(type default)
			)
			(layer "F.Fab")
		)
		(fp_line
			(start -0.12065 -0.305054)
			(end -0.12065 -0.2794)
			(stroke
				(width 0.1)
				(type default)
			)
			(layer "F.Fab")
		)
		(fp_line
			(start -0.12065 -0.2794)
			(end 0.12065 -0.2794)
			(stroke
				(width 0.1)
				(type default)
			)
			(layer "F.Fab")
		)
		(fp_line
			(start -0.12065 0.2794)
			(end -0.12065 0.3048)
			(stroke
				(width 0.1)
				(type default)
			)
			(layer "F.Fab")
		)
		(fp_line
			(start -0.12065 0.3048)
			(end -0.67945 0.3048)
			(stroke
				(width 0.1)
				(type default)
			)
			(layer "F.Fab")
		)
		(fp_line
			(start 0.120396 0.2794)
			(end -0.12065 0.2794)
			(stroke
				(width 0.1)
				(type default)
			)
			(layer "F.Fab")
		)
		(fp_line
			(start 0.120396 0.3048)
			(end 0.120396 0.2794)
			(stroke
				(width 0.1)
				(type default)
			)
			(layer "F.Fab")
		)
		(fp_line
			(start 0.12065 -0.3048)
			(end 0.67945 -0.3048)
			(stroke
				(width 0.1)
				(type default)
			)
			(layer "F.Fab")
		)
		(fp_line
			(start 0.12065 -0.2794)
			(end 0.12065 -0.3048)
			(stroke
				(width 0.1)
				(type default)
			)
			(layer "F.Fab")
		)
		(fp_line
			(start 0.67945 -0.3048)
			(end 0.67945 0.3048)
			(stroke
				(width 0.1)
				(type default)
			)
			(layer "F.Fab")
		)
		(fp_line
			(start 0.67945 0.3048)
			(end 0.120396 0.3048)
			(stroke
				(width 0.1)
				(type default)
			)
			(layer "F.Fab")
		)
		(pad "1" smd circle
			(at -0.40005 0)
			(size 0 0)
			(layers "F.Cu" "F.Mask" "F.Paste")
			(net "SMB_PDBV_FAN_SDA")
		)
		(pad "2" smd circle
			(at 0.40005 0)
			(size 0 0)
			(layers "F.Cu" "F.Mask" "F.Paste")
			(net "SMB_PDBV_FAN_R1_IOX_SDA")
		)
	)
	(footprint ""
		(layer "F.Cu")
		(at 45.085 -189.738 180)
		(property "Reference" "R4967"
			(at 0 0 180)
			(layer "F.SilkS")
			(hide yes)
			(effects
				(font
					(size 1.27 1.27)
				)
			)
		)
		(property "Value" ""
			(at 0 0 180)
			(layer "F.Fab")
			(effects
				(font
					(size 1.27 1.27)
				)
			)
		)
		(duplicate_pad_numbers_are_jumpers no)
		(fp_line
			(start 0.7874 0.4064)
			(end -0.7874 0.4064)
			(stroke
				(width 0.1524)
				(type default)
			)
			(layer "F.SilkS")
		)
		(fp_line
			(start 0.7874 -0.4064)
			(end 0.7874 0.4064)
			(stroke
				(width 0.1524)
				(type default)
			)
			(layer "F.SilkS")
		)
		(fp_line
			(start -0.7874 0.4064)
			(end -0.7874 -0.4064)
			(stroke
				(width 0.1524)
				(type default)
			)
			(layer "F.SilkS")
		)
		(fp_line
			(start -0.7874 -0.4064)
			(end 0.7874 -0.4064)
			(stroke
				(width 0.1524)
				(type default)
			)
			(layer "F.SilkS")
		)
		(fp_line
			(start 0.67945 0.3048)
			(end 0.120396 0.3048)
			(stroke
				(width 0.1)
				(type default)
			)
			(layer "F.Fab")
		)
		(fp_line
			(start 0.67945 -0.3048)
			(end 0.67945 0.3048)
			(stroke
				(width 0.1)
				(type default)
			)
			(layer "F.Fab")
		)
		(fp_line
			(start 0.12065 -0.2794)
			(end 0.12065 -0.3048)
			(stroke
				(width 0.1)
				(type default)
			)
			(layer "F.Fab")
		)
		(fp_line
			(start 0.12065 -0.3048)
			(end 0.67945 -0.3048)
			(stroke
				(width 0.1)
				(type default)
			)
			(layer "F.Fab")
		)
		(fp_line
			(start 0.120396 0.3048)
			(end 0.120396 0.2794)
			(stroke
				(width 0.1)
				(type default)
			)
			(layer "F.Fab")
		)
		(fp_line
			(start 0.120396 0.2794)
			(end -0.12065 0.2794)
			(stroke
				(width 0.1)
				(type default)
			)
			(layer "F.Fab")
		)
		(fp_line
			(start -0.12065 0.3048)
			(end -0.67945 0.3048)
			(stroke
				(width 0.1)
				(type default)
			)
			(layer "F.Fab")
		)
		(fp_line
			(start -0.12065 0.2794)
			(end -0.12065 0.3048)
			(stroke
				(width 0.1)
				(type default)
			)
			(layer "F.Fab")
		)
		(fp_line
			(start -0.12065 -0.2794)
			(end 0.12065 -0.2794)
			(stroke
				(width 0.1)
				(type default)
			)
			(layer "F.Fab")
		)
		(fp_line
			(start -0.12065 -0.305054)
			(end -0.12065 -0.2794)
			(stroke
				(width 0.1)
				(type default)
			)
			(layer "F.Fab")
		)
		(fp_line
			(start -0.67945 0.3048)
			(end -0.67945 -0.305054)
			(stroke
				(width 0.1)
				(type default)
			)
			(layer "F.Fab")
		)
		(fp_line
			(start -0.67945 -0.305054)
			(end -0.12065 -0.305054)
			(stroke
				(width 0.1)
				(type default)
			)
			(layer "F.Fab")
		)
		(pad "1" smd circle
			(at -0.40005 0 180)
			(size 0 0)
			(layers "F.Cu" "F.Mask" "F.Paste")
			(net "GND")
		)
		(pad "2" smd circle
			(at 0.40005 0 180)
			(size 0 0)
			(layers "F.Cu" "F.Mask" "F.Paste")
			(net "PD_FAN_BUFF_INPUT_U337F")
		)
	)
	(footprint ""
		(layer "F.Cu")
		(at 47.752 -312.928 -90)
		(property "Reference" "U405"
			(at 1.64338 -2.02311 90)
			(unlocked yes)
			(layer "F.SilkS")
			(effects
				(font
					(size 0.7874 0.5842)
					(thickness 0.1524)
				)
				(justify left)
			)
		)
		(property "Value" ""
			(at 0 0 270)
			(layer "F.Fab")
			(effects
				(font
					(size 1.27 1.27)
				)
			)
		)
		(duplicate_pad_numbers_are_jumpers no)
		(fp_line
			(start -1.335278 1.100074)
			(end 1.335278 1.100074)
			(stroke
				(width 0.1524)
				(type default)
			)
			(layer "F.SilkS")
		)
		(fp_line
			(start 1.335278 1.100074)
			(end 1.335278 -1.100074)
			(stroke
				(width 0.1524)
				(type default)
			)
			(layer "F.SilkS")
		)
		(fp_line
			(start -1.335278 -1.100074)
			(end -1.335278 1.100074)
			(stroke
				(width 0.1524)
				(type default)
			)
			(layer "F.SilkS")
		)
		(fp_line
			(start 1.335278 -1.100074)
			(end -1.335278 -1.100074)
			(stroke
				(width 0.1524)
				(type default)
			)
			(layer "F.SilkS")
		)
		(fp_line
			(start -0.674878 1.100074)
			(end 0.674878 1.100074)
			(stroke
				(width 0.1)
				(type default)
			)
			(layer "F.Fab")
		)
		(fp_line
			(start 0.674878 1.100074)
			(end 0.674878 -1.100074)
			(stroke
				(width 0.1)
				(type default)
			)
			(layer "F.Fab")
		)
		(fp_line
			(start -0.674878 -1.100074)
			(end -0.674878 1.100074)
			(stroke
				(width 0.1)
				(type default)
			)
			(layer "F.Fab")
		)
		(fp_line
			(start 0.674878 -1.100074)
			(end -0.674878 -1.100074)
			(stroke
				(width 0.1)
				(type default)
			)
			(layer "F.Fab")
		)
		(pad "D" smd rect
			(at 0.8001 0 180)
			(size 0.6096 0.8128)
			(layers "F.Cu" "F.Mask" "F.Paste")
			(net "U405_D1")
		)
		(pad "G" smd rect
			(at -0.8001 -0.649986 180)
			(size 0.6096 0.8128)
			(layers "F.Cu" "F.Mask" "F.Paste")
			(net "FAN_0_PRESENT")
		)
		(pad "S" smd rect
			(at -0.8001 0.649986 180)
			(size 0.6096 0.8128)
			(layers "F.Cu" "F.Mask" "F.Paste")
			(net "GND")
		)
	)
	(footprint ""
		(layer "F.Cu")
		(at 5.08 -331.978)
		(property "Reference" "H15"
			(at -1.143 -3.02133 0)
			(unlocked yes)
			(layer "F.SilkS")
			(effects
				(font
					(size 0.7874 0.5842)
					(thickness 0.1524)
				)
				(justify left)
			)
		)
		(property "Value" ""
			(at 0 0 0)
			(layer "F.Fab")
			(effects
				(font
					(size 1.27 1.27)
				)
			)
		)
		(duplicate_pad_numbers_are_jumpers no)
		(fp_circle
			(center 0 0)
			(end 2.4003 0)
			(stroke
				(width 0.1524)
				(type default)
			)
			(fill no)
			(layer "F.SilkS")
		)
		(fp_circle
			(center 0 0)
			(end 6.5913 0)
			(stroke
				(width 0.1524)
				(type default)
			)
			(fill no)
			(layer "B.SilkS")
		)
		(fp_circle
			(center 0 0)
			(end 6.5913 0)
			(stroke
				(width 0.1)
				(type default)
			)
			(fill no)
			(layer "B.Fab")
		)
		(fp_circle
			(center 0 0)
			(end 2.4003 0)
			(stroke
				(width 0.1)
				(type default)
			)
			(fill no)
			(layer "F.Fab")
		)
		(pad "" np_thru_hole circle
			(at 0 0)
			(size 3.175 3.175)
			(drill 3.175)
			(layers "*.Cu" "*.Mask")
			(clearance 0.381)
			(thermal_gap 0.381)
		)
		(zone
			(layers "F.Cu" "B.Cu" "In1.Cu" "In2.Cu" "In3.Cu" "In4.Cu")
			(hatch none 0.5)
			(connect_pads
				(clearance 0)
			)
			(min_thickness 0.25)
			(keepout
				(tracks not_allowed)
				(vias allowed)
				(pads allowed)
				(copperpour not_allowed)
				(footprints allowed)
			)
			(placement
				(enabled no)
				(sheetname "")
			)
			(fill
				(thermal_gap 0.5)
				(thermal_bridge_width 0.5)
				(island_removal_mode 0)
			)
			(polygon
				(pts
					(arc
						(start 7.1755 -331.978)
						(mid 2.9845 -331.978)
						(end 7.1755 -331.978)
					)
				)
			)
		)
	)
	(footprint ""
		(layer "F.Cu")
		(at 18.679922 -194.250056 180)
		(property "Reference" "D255"
			(at 0.772922 -1.236726 0)
			(unlocked yes)
			(layer "F.SilkS")
			(effects
				(font
					(size 0.7874 0.5842)
					(thickness 0.1524)
				)
				(justify left)
			)
		)
		(property "Value" ""
			(at 0 0 180)
			(layer "F.Fab")
			(effects
				(font
					(size 1.27 1.27)
				)
			)
		)
		(duplicate_pad_numbers_are_jumpers no)
		(fp_line
			(start 0.94488 0.450088)
			(end 0.94488 -0.450088)
			(stroke
				(width 0.1524)
				(type default)
			)
			(layer "F.SilkS")
		)
		(fp_line
			(start 0.94488 -0.450088)
			(end -0.854964 -0.450088)
			(stroke
				(width 0.1524)
				(type default)
			)
			(layer "F.SilkS")
		)
		(fp_line
			(start 0.870458 -0.2794)
			(end 0.845058 0.4064)
			(stroke
				(width 0.1524)
				(type default)
			)
			(layer "F.SilkS")
		)
		(fp_line
			(start 0.845058 0.4064)
			(end 0.845058 -0.381)
			(stroke
				(width 0.1524)
				(type default)
			)
			(layer "F.SilkS")
		)
		(fp_line
			(start -0.854964 0.450088)
			(end 0.925068 0.450088)
			(stroke
				(width 0.1524)
				(type default)
			)
			(layer "F.SilkS")
		)
		(fp_line
			(start -0.854964 -0.450088)
			(end -0.854964 0.450088)
			(stroke
				(width 0.1524)
				(type default)
			)
			(layer "F.SilkS")
		)
		(fp_line
			(start 0.54991 0.350012)
			(end 0.54991 -0.350012)
			(stroke
				(width 0.1)
				(type default)
			)
			(layer "F.Fab")
		)
		(fp_line
			(start 0.54991 -0.350012)
			(end -0.54991 -0.350012)
			(stroke
				(width 0.1)
				(type default)
			)
			(layer "F.Fab")
		)
		(fp_line
			(start -0.54991 0.350012)
			(end 0.54991 0.350012)
			(stroke
				(width 0.1)
				(type default)
			)
			(layer "F.Fab")
		)
		(fp_line
			(start -0.54991 -0.350012)
			(end -0.54991 0.350012)
			(stroke
				(width 0.1)
				(type default)
			)
			(layer "F.Fab")
		)
		(fp_text user "-"
			(at 2.169922 -0.733806 0)
			(unlocked yes)
			(layer "F.SilkS")
			(effects
				(font
					(size 1.905 1.4224)
					(thickness 0.1524)
				)
				(justify left)
			)
		)
		(fp_text user "+"
			(at -1.005078 0.028194 0)
			(unlocked yes)
			(layer "F.SilkS")
			(effects
				(font
					(size 1.905 1.4224)
					(thickness 0.1524)
				)
				(justify left)
			)
		)
		(fp_text user "-"
			(at 2.48539 0.239014 0)
			(unlocked yes)
			(layer "F.Fab")
			(effects
				(font
					(size 1.905 1.4224)
					(thickness 0.1524)
				)
				(justify left)
			)
		)
		(fp_text user "+"
			(at -0.808228 0.239014 0)
			(unlocked yes)
			(layer "F.Fab")
			(effects
				(font
					(size 1.905 1.4224)
					(thickness 0.1524)
				)
				(justify left)
			)
		)
		(pad "A" smd rect
			(at -0.424942 0 180)
			(size 0.5588 0.6096)
			(layers "F.Cu" "F.Mask" "F.Paste")
			(net "GND")
		)
		(pad "C" smd rect
			(at 0.424942 0)
			(size 0.5588 0.6096)
			(layers "F.Cu" "F.Mask" "F.Paste")
			(net "FAN_6_PWM_OL_R")
		)
	)
	(footprint ""
		(layer "F.Cu")
		(at 20.828 -175.768 180)
		(property "Reference" "R5672"
			(at 0 0 180)
			(layer "F.SilkS")
			(hide yes)
			(effects
				(font
					(size 1.27 1.27)
				)
			)
		)
		(property "Value" ""
			(at 0 0 180)
			(layer "F.Fab")
			(effects
				(font
					(size 1.27 1.27)
				)
			)
		)
		(duplicate_pad_numbers_are_jumpers no)
		(fp_line
			(start 0.7874 0.4064)
			(end -0.7874 0.4064)
			(stroke
				(width 0.1524)
				(type default)
			)
			(layer "F.SilkS")
		)
		(fp_line
			(start 0.7874 -0.4064)
			(end 0.7874 0.4064)
			(stroke
				(width 0.1524)
				(type default)
			)
			(layer "F.SilkS")
		)
		(fp_line
			(start -0.7874 0.4064)
			(end -0.7874 -0.4064)
			(stroke
				(width 0.1524)
				(type default)
			)
			(layer "F.SilkS")
		)
		(fp_line
			(start -0.7874 -0.4064)
			(end 0.7874 -0.4064)
			(stroke
				(width 0.1524)
				(type default)
			)
			(layer "F.SilkS")
		)
		(fp_line
			(start 0.67945 0.3048)
			(end 0.120396 0.3048)
			(stroke
				(width 0.1)
				(type default)
			)
			(layer "F.Fab")
		)
		(fp_line
			(start 0.67945 -0.3048)
			(end 0.67945 0.3048)
			(stroke
				(width 0.1)
				(type default)
			)
			(layer "F.Fab")
		)
		(fp_line
			(start 0.12065 -0.2794)
			(end 0.12065 -0.3048)
			(stroke
				(width 0.1)
				(type default)
			)
			(layer "F.Fab")
		)
		(fp_line
			(start 0.12065 -0.3048)
			(end 0.67945 -0.3048)
			(stroke
				(width 0.1)
				(type default)
			)
			(layer "F.Fab")
		)
		(fp_line
			(start 0.120396 0.3048)
			(end 0.120396 0.2794)
			(stroke
				(width 0.1)
				(type default)
			)
			(layer "F.Fab")
		)
		(fp_line
			(start 0.120396 0.2794)
			(end -0.12065 0.2794)
			(stroke
				(width 0.1)
				(type default)
			)
			(layer "F.Fab")
		)
		(fp_line
			(start -0.12065 0.3048)
			(end -0.67945 0.3048)
			(stroke
				(width 0.1)
				(type default)
			)
			(layer "F.Fab")
		)
		(fp_line
			(start -0.12065 0.2794)
			(end -0.12065 0.3048)
			(stroke
				(width 0.1)
				(type default)
			)
			(layer "F.Fab")
		)
		(fp_line
			(start -0.12065 -0.2794)
			(end 0.12065 -0.2794)
			(stroke
				(width 0.1)
				(type default)
			)
			(layer "F.Fab")
		)
		(fp_line
			(start -0.12065 -0.305054)
			(end -0.12065 -0.2794)
			(stroke
				(width 0.1)
				(type default)
			)
			(layer "F.Fab")
		)
		(fp_line
			(start -0.67945 0.3048)
			(end -0.67945 -0.305054)
			(stroke
				(width 0.1)
				(type default)
			)
			(layer "F.Fab")
		)
		(fp_line
			(start -0.67945 -0.305054)
			(end -0.12065 -0.305054)
			(stroke
				(width 0.1)
				(type default)
			)
			(layer "F.Fab")
		)
		(pad "1" smd circle
			(at -0.40005 0 180)
			(size 0 0)
			(layers "F.Cu" "F.Mask" "F.Paste")
			(net "P3V3_AUX")
		)
		(pad "2" smd circle
			(at 0.40005 0 180)
			(size 0 0)
			(layers "F.Cu" "F.Mask" "F.Paste")
			(net "FM_BOARD_SKU_ID2")
		)
	)
	(footprint ""
		(layer "F.Cu")
		(at 30.734 -160.02 90)
		(property "Reference" "R4878"
			(at 0 0 90)
			(layer "F.SilkS")
			(hide yes)
			(effects
				(font
					(size 1.27 1.27)
				)
			)
		)
		(property "Value" ""
			(at 0 0 90)
			(layer "F.Fab")
			(effects
				(font
					(size 1.27 1.27)
				)
			)
		)
		(duplicate_pad_numbers_are_jumpers no)
		(fp_line
			(start 0.7874 -0.4064)
			(end 0.7874 0.4064)
			(stroke
				(width 0.1524)
				(type default)
			)
			(layer "F.SilkS")
		)
		(fp_line
			(start -0.7874 -0.4064)
			(end 0.7874 -0.4064)
			(stroke
				(width 0.1524)
				(type default)
			)
			(layer "F.SilkS")
		)
		(fp_line
			(start 0.7874 0.4064)
			(end -0.7874 0.4064)
			(stroke
				(width 0.1524)
				(type default)
			)
			(layer "F.SilkS")
		)
		(fp_line
			(start -0.7874 0.4064)
			(end -0.7874 -0.4064)
			(stroke
				(width 0.1524)
				(type default)
			)
			(layer "F.SilkS")
		)
		(fp_line
			(start -0.12065 -0.305054)
			(end -0.12065 -0.2794)
			(stroke
				(width 0.1)
				(type default)
			)
			(layer "F.Fab")
		)
		(fp_line
			(start -0.67945 -0.305054)
			(end -0.12065 -0.305054)
			(stroke
				(width 0.1)
				(type default)
			)
			(layer "F.Fab")
		)
		(fp_line
			(start 0.67945 -0.3048)
			(end 0.67945 0.3048)
			(stroke
				(width 0.1)
				(type default)
			)
			(layer "F.Fab")
		)
		(fp_line
			(start 0.12065 -0.3048)
			(end 0.67945 -0.3048)
			(stroke
				(width 0.1)
				(type default)
			)
			(layer "F.Fab")
		)
		(fp_line
			(start 0.12065 -0.2794)
			(end 0.12065 -0.3048)
			(stroke
				(width 0.1)
				(type default)
			)
			(layer "F.Fab")
		)
		(fp_line
			(start -0.12065 -0.2794)
			(end 0.12065 -0.2794)
			(stroke
				(width 0.1)
				(type default)
			)
			(layer "F.Fab")
		)
		(fp_line
			(start 0.120396 0.2794)
			(end -0.12065 0.2794)
			(stroke
				(width 0.1)
				(type default)
			)
			(layer "F.Fab")
		)
		(fp_line
			(start -0.12065 0.2794)
			(end -0.12065 0.3048)
			(stroke
				(width 0.1)
				(type default)
			)
			(layer "F.Fab")
		)
		(fp_line
			(start 0.67945 0.3048)
			(end 0.120396 0.3048)
			(stroke
				(width 0.1)
				(type default)
			)
			(layer "F.Fab")
		)
		(fp_line
			(start 0.120396 0.3048)
			(end 0.120396 0.2794)
			(stroke
				(width 0.1)
				(type default)
			)
			(layer "F.Fab")
		)
		(fp_line
			(start -0.12065 0.3048)
			(end -0.67945 0.3048)
			(stroke
				(width 0.1)
				(type default)
			)
			(layer "F.Fab")
		)
		(fp_line
			(start -0.67945 0.3048)
			(end -0.67945 -0.305054)
			(stroke
				(width 0.1)
				(type default)
			)
			(layer "F.Fab")
		)
		(pad "1" smd circle
			(at -0.40005 0 90)
			(size 0 0)
			(layers "F.Cu" "F.Mask" "F.Paste")
			(net "SMB_FAN5_R_SDA")
		)
		(pad "2" smd circle
			(at 0.40005 0 90)
			(size 0 0)
			(layers "F.Cu" "F.Mask" "F.Paste")
			(net "SMB_FAN5_SDA")
		)
	)
	(footprint ""
		(layer "F.Cu")
		(at 20.828 -180.213)
		(property "Reference" "R5688"
			(at 0 0 0)
			(layer "F.SilkS")
			(hide yes)
			(effects
				(font
					(size 1.27 1.27)
				)
			)
		)
		(property "Value" ""
			(at 0 0 0)
			(layer "F.Fab")
			(effects
				(font
					(size 1.27 1.27)
				)
			)
		)
		(duplicate_pad_numbers_are_jumpers no)
		(fp_line
			(start -0.7874 -0.4064)
			(end 0.7874 -0.4064)
			(stroke
				(width 0.1524)
				(type default)
			)
			(layer "F.SilkS")
		)
		(fp_line
			(start -0.7874 0.4064)
			(end -0.7874 -0.4064)
			(stroke
				(width 0.1524)
				(type default)
			)
			(layer "F.SilkS")
		)
		(fp_line
			(start 0.7874 -0.4064)
			(end 0.7874 0.4064)
			(stroke
				(width 0.1524)
				(type default)
			)
			(layer "F.SilkS")
		)
		(fp_line
			(start 0.7874 0.4064)
			(end -0.7874 0.4064)
			(stroke
				(width 0.1524)
				(type default)
			)
			(layer "F.SilkS")
		)
		(fp_line
			(start -0.67945 -0.305054)
			(end -0.12065 -0.305054)
			(stroke
				(width 0.1)
				(type default)
			)
			(layer "F.Fab")
		)
		(fp_line
			(start -0.67945 0.3048)
			(end -0.67945 -0.305054)
			(stroke
				(width 0.1)
				(type default)
			)
			(layer "F.Fab")
		)
		(fp_line
			(start -0.12065 -0.305054)
			(end -0.12065 -0.2794)
			(stroke
				(width 0.1)
				(type default)
			)
			(layer "F.Fab")
		)
		(fp_line
			(start -0.12065 -0.2794)
			(end 0.12065 -0.2794)
			(stroke
				(width 0.1)
				(type default)
			)
			(layer "F.Fab")
		)
		(fp_line
			(start -0.12065 0.2794)
			(end -0.12065 0.3048)
			(stroke
				(width 0.1)
				(type default)
			)
			(layer "F.Fab")
		)
		(fp_line
			(start -0.12065 0.3048)
			(end -0.67945 0.3048)
			(stroke
				(width 0.1)
				(type default)
			)
			(layer "F.Fab")
		)
		(fp_line
			(start 0.120396 0.2794)
			(end -0.12065 0.2794)
			(stroke
				(width 0.1)
				(type default)
			)
			(layer "F.Fab")
		)
		(fp_line
			(start 0.120396 0.3048)
			(end 0.120396 0.2794)
			(stroke
				(width 0.1)
				(type default)
			)
			(layer "F.Fab")
		)
		(fp_line
			(start 0.12065 -0.3048)
			(end 0.67945 -0.3048)
			(stroke
				(width 0.1)
				(type default)
			)
			(layer "F.Fab")
		)
		(fp_line
			(start 0.12065 -0.2794)
			(end 0.12065 -0.3048)
			(stroke
				(width 0.1)
				(type default)
			)
			(layer "F.Fab")
		)
		(fp_line
			(start 0.67945 -0.3048)
			(end 0.67945 0.3048)
			(stroke
				(width 0.1)
				(type default)
			)
			(layer "F.Fab")
		)
		(fp_line
			(start 0.67945 0.3048)
			(end 0.120396 0.3048)
			(stroke
				(width 0.1)
				(type default)
			)
			(layer "F.Fab")
		)
		(pad "1" smd circle
			(at -0.40005 0)
			(size 0 0)
			(layers "F.Cu" "F.Mask" "F.Paste")
			(net "FM_BOARD_ID2")
		)
		(pad "2" smd circle
			(at 0.40005 0)
			(size 0 0)
			(layers "F.Cu" "F.Mask" "F.Paste")
			(net "GND")
		)
	)
	(footprint ""
		(layer "F.Cu")
		(at 12.954 -74.422)
		(property "Reference" "PR59"
			(at 0 0 0)
			(layer "F.SilkS")
			(hide yes)
			(effects
				(font
					(size 1.27 1.27)
				)
			)
		)
		(property "Value" ""
			(at 0 0 0)
			(layer "F.Fab")
			(effects
				(font
					(size 1.27 1.27)
				)
			)
		)
		(duplicate_pad_numbers_are_jumpers no)
		(fp_line
			(start -0.7874 -0.4064)
			(end 0.7874 -0.4064)
			(stroke
				(width 0.1524)
				(type default)
			)
			(layer "F.SilkS")
		)
		(fp_line
			(start -0.7874 0.4064)
			(end -0.7874 -0.4064)
			(stroke
				(width 0.1524)
				(type default)
			)
			(layer "F.SilkS")
		)
		(fp_line
			(start 0.7874 -0.4064)
			(end 0.7874 0.4064)
			(stroke
				(width 0.1524)
				(type default)
			)
			(layer "F.SilkS")
		)
		(fp_line
			(start 0.7874 0.4064)
			(end -0.7874 0.4064)
			(stroke
				(width 0.1524)
				(type default)
			)
			(layer "F.SilkS")
		)
		(fp_line
			(start -0.67945 -0.305054)
			(end -0.12065 -0.305054)
			(stroke
				(width 0.1)
				(type default)
			)
			(layer "F.Fab")
		)
		(fp_line
			(start -0.67945 0.3048)
			(end -0.67945 -0.305054)
			(stroke
				(width 0.1)
				(type default)
			)
			(layer "F.Fab")
		)
		(fp_line
			(start -0.12065 -0.305054)
			(end -0.12065 -0.2794)
			(stroke
				(width 0.1)
				(type default)
			)
			(layer "F.Fab")
		)
		(fp_line
			(start -0.12065 -0.2794)
			(end 0.12065 -0.2794)
			(stroke
				(width 0.1)
				(type default)
			)
			(layer "F.Fab")
		)
		(fp_line
			(start -0.12065 0.2794)
			(end -0.12065 0.3048)
			(stroke
				(width 0.1)
				(type default)
			)
			(layer "F.Fab")
		)
		(fp_line
			(start -0.12065 0.3048)
			(end -0.67945 0.3048)
			(stroke
				(width 0.1)
				(type default)
			)
			(layer "F.Fab")
		)
		(fp_line
			(start 0.120396 0.2794)
			(end -0.12065 0.2794)
			(stroke
				(width 0.1)
				(type default)
			)
			(layer "F.Fab")
		)
		(fp_line
			(start 0.120396 0.3048)
			(end 0.120396 0.2794)
			(stroke
				(width 0.1)
				(type default)
			)
			(layer "F.Fab")
		)
		(fp_line
			(start 0.12065 -0.3048)
			(end 0.67945 -0.3048)
			(stroke
				(width 0.1)
				(type default)
			)
			(layer "F.Fab")
		)
		(fp_line
			(start 0.12065 -0.2794)
			(end 0.12065 -0.3048)
			(stroke
				(width 0.1)
				(type default)
			)
			(layer "F.Fab")
		)
		(fp_line
			(start 0.67945 -0.3048)
			(end 0.67945 0.3048)
			(stroke
				(width 0.1)
				(type default)
			)
			(layer "F.Fab")
		)
		(fp_line
			(start 0.67945 0.3048)
			(end 0.120396 0.3048)
			(stroke
				(width 0.1)
				(type default)
			)
			(layer "F.Fab")
		)
		(pad "1" smd circle
			(at -0.40005 0)
			(size 0 0)
			(layers "F.Cu" "F.Mask" "F.Paste")
			(net "FAN_5_MODE")
		)
		(pad "2" smd circle
			(at 0.40005 0)
			(size 0 0)
			(layers "F.Cu" "F.Mask" "F.Paste")
			(net "GND")
		)
	)
	(footprint ""
		(layer "F.Cu")
		(at 15.504922 -32.217868 180)
		(property "Reference" "D241"
			(at 6.056122 0.000762 0)
			(unlocked yes)
			(layer "F.SilkS")
			(effects
				(font
					(size 0.7874 0.5842)
					(thickness 0.1524)
				)
				(justify left)
			)
		)
		(property "Value" ""
			(at 0 0 180)
			(layer "F.Fab")
			(effects
				(font
					(size 1.27 1.27)
				)
			)
		)
		(duplicate_pad_numbers_are_jumpers no)
		(fp_line
			(start 0.94488 0.450088)
			(end 0.94488 -0.450088)
			(stroke
				(width 0.1524)
				(type default)
			)
			(layer "F.SilkS")
		)
		(fp_line
			(start 0.94488 -0.450088)
			(end -0.854964 -0.450088)
			(stroke
				(width 0.1524)
				(type default)
			)
			(layer "F.SilkS")
		)
		(fp_line
			(start 0.870458 -0.2794)
			(end 0.845058 0.4064)
			(stroke
				(width 0.1524)
				(type default)
			)
			(layer "F.SilkS")
		)
		(fp_line
			(start 0.845058 0.4064)
			(end 0.845058 -0.381)
			(stroke
				(width 0.1524)
				(type default)
			)
			(layer "F.SilkS")
		)
		(fp_line
			(start -0.854964 0.450088)
			(end 0.925068 0.450088)
			(stroke
				(width 0.1524)
				(type default)
			)
			(layer "F.SilkS")
		)
		(fp_line
			(start -0.854964 -0.450088)
			(end -0.854964 0.450088)
			(stroke
				(width 0.1524)
				(type default)
			)
			(layer "F.SilkS")
		)
		(fp_line
			(start 0.54991 0.350012)
			(end 0.54991 -0.350012)
			(stroke
				(width 0.1)
				(type default)
			)
			(layer "F.Fab")
		)
		(fp_line
			(start 0.54991 -0.350012)
			(end -0.54991 -0.350012)
			(stroke
				(width 0.1)
				(type default)
			)
			(layer "F.Fab")
		)
		(fp_line
			(start -0.54991 0.350012)
			(end 0.54991 0.350012)
			(stroke
				(width 0.1)
				(type default)
			)
			(layer "F.Fab")
		)
		(fp_line
			(start -0.54991 -0.350012)
			(end -0.54991 0.350012)
			(stroke
				(width 0.1)
				(type default)
			)
			(layer "F.Fab")
		)
		(fp_text user "-"
			(at 2.48539 0.239014 0)
			(unlocked yes)
			(layer "F.SilkS")
			(effects
				(font
					(size 1.905 1.4224)
					(thickness 0.1524)
				)
				(justify left)
			)
		)
		(fp_text user "+"
			(at 0.264922 1.278382 0)
			(unlocked yes)
			(layer "F.SilkS")
			(effects
				(font
					(size 1.905 1.4224)
					(thickness 0.1524)
				)
				(justify left)
			)
		)
		(fp_text user "-"
			(at 2.48539 0.239014 0)
			(unlocked yes)
			(layer "F.Fab")
			(effects
				(font
					(size 1.905 1.4224)
					(thickness 0.1524)
				)
				(justify left)
			)
		)
		(fp_text user "+"
			(at -0.808228 0.239014 0)
			(unlocked yes)
			(layer "F.Fab")
			(effects
				(font
					(size 1.905 1.4224)
					(thickness 0.1524)
				)
				(justify left)
			)
		)
		(pad "A" smd rect
			(at -0.424942 0 180)
			(size 0.5588 0.6096)
			(layers "F.Cu" "F.Mask" "F.Paste")
			(net "GND")
		)
		(pad "C" smd rect
			(at 0.424942 0)
			(size 0.5588 0.6096)
			(layers "F.Cu" "F.Mask" "F.Paste")
			(net "FAN_4_TACH_OL_D")
		)
	)
	(footprint ""
		(layer "F.Cu")
		(at 3.937 -314.833 180)
		(property "Reference" "R5669"
			(at 0 0 180)
			(layer "F.SilkS")
			(hide yes)
			(effects
				(font
					(size 1.27 1.27)
				)
			)
		)
		(property "Value" ""
			(at 0 0 180)
			(layer "F.Fab")
			(effects
				(font
					(size 1.27 1.27)
				)
			)
		)
		(duplicate_pad_numbers_are_jumpers no)
		(fp_line
			(start 0.7874 0.4064)
			(end -0.7874 0.4064)
			(stroke
				(width 0.1524)
				(type default)
			)
			(layer "F.SilkS")
		)
		(fp_line
			(start 0.7874 -0.4064)
			(end 0.7874 0.4064)
			(stroke
				(width 0.1524)
				(type default)
			)
			(layer "F.SilkS")
		)
		(fp_line
			(start -0.7874 0.4064)
			(end -0.7874 -0.4064)
			(stroke
				(width 0.1524)
				(type default)
			)
			(layer "F.SilkS")
		)
		(fp_line
			(start -0.7874 -0.4064)
			(end 0.7874 -0.4064)
			(stroke
				(width 0.1524)
				(type default)
			)
			(layer "F.SilkS")
		)
		(fp_line
			(start 0.67945 0.3048)
			(end 0.120396 0.3048)
			(stroke
				(width 0.1)
				(type default)
			)
			(layer "F.Fab")
		)
		(fp_line
			(start 0.67945 -0.3048)
			(end 0.67945 0.3048)
			(stroke
				(width 0.1)
				(type default)
			)
			(layer "F.Fab")
		)
		(fp_line
			(start 0.12065 -0.2794)
			(end 0.12065 -0.3048)
			(stroke
				(width 0.1)
				(type default)
			)
			(layer "F.Fab")
		)
		(fp_line
			(start 0.12065 -0.3048)
			(end 0.67945 -0.3048)
			(stroke
				(width 0.1)
				(type default)
			)
			(layer "F.Fab")
		)
		(fp_line
			(start 0.120396 0.3048)
			(end 0.120396 0.2794)
			(stroke
				(width 0.1)
				(type default)
			)
			(layer "F.Fab")
		)
		(fp_line
			(start 0.120396 0.2794)
			(end -0.12065 0.2794)
			(stroke
				(width 0.1)
				(type default)
			)
			(layer "F.Fab")
		)
		(fp_line
			(start -0.12065 0.3048)
			(end -0.67945 0.3048)
			(stroke
				(width 0.1)
				(type default)
			)
			(layer "F.Fab")
		)
		(fp_line
			(start -0.12065 0.2794)
			(end -0.12065 0.3048)
			(stroke
				(width 0.1)
				(type default)
			)
			(layer "F.Fab")
		)
		(fp_line
			(start -0.12065 -0.2794)
			(end 0.12065 -0.2794)
			(stroke
				(width 0.1)
				(type default)
			)
			(layer "F.Fab")
		)
		(fp_line
			(start -0.12065 -0.305054)
			(end -0.12065 -0.2794)
			(stroke
				(width 0.1)
				(type default)
			)
			(layer "F.Fab")
		)
		(fp_line
			(start -0.67945 0.3048)
			(end -0.67945 -0.305054)
			(stroke
				(width 0.1)
				(type default)
			)
			(layer "F.Fab")
		)
		(fp_line
			(start -0.67945 -0.305054)
			(end -0.12065 -0.305054)
			(stroke
				(width 0.1)
				(type default)
			)
			(layer "F.Fab")
		)
		(pad "1" smd circle
			(at -0.40005 0 180)
			(size 0 0)
			(layers "F.Cu" "F.Mask" "F.Paste")
			(net "FAN_7_PRESENT")
		)
		(pad "2" smd circle
			(at 0.40005 0 180)
			(size 0 0)
			(layers "F.Cu" "F.Mask" "F.Paste")
			(net "GND")
		)
	)
	(footprint ""
		(layer "F.Cu")
		(at 36.698428 -66.732912 180)
		(property "Reference" "R503"
			(at 0 0 180)
			(layer "F.SilkS")
			(hide yes)
			(effects
				(font
					(size 1.27 1.27)
				)
			)
		)
		(property "Value" ""
			(at 0 0 180)
			(layer "F.Fab")
			(effects
				(font
					(size 1.27 1.27)
				)
			)
		)
		(duplicate_pad_numbers_are_jumpers no)
		(fp_line
			(start 0.7874 0.4064)
			(end -0.7874 0.4064)
			(stroke
				(width 0.1524)
				(type default)
			)
			(layer "F.SilkS")
		)
		(fp_line
			(start 0.7874 -0.4064)
			(end 0.7874 0.4064)
			(stroke
				(width 0.1524)
				(type default)
			)
			(layer "F.SilkS")
		)
		(fp_line
			(start -0.7874 0.4064)
			(end -0.7874 -0.4064)
			(stroke
				(width 0.1524)
				(type default)
			)
			(layer "F.SilkS")
		)
		(fp_line
			(start -0.7874 -0.4064)
			(end 0.7874 -0.4064)
			(stroke
				(width 0.1524)
				(type default)
			)
			(layer "F.SilkS")
		)
		(fp_line
			(start 0.67945 0.3048)
			(end 0.120396 0.3048)
			(stroke
				(width 0.1)
				(type default)
			)
			(layer "F.Fab")
		)
		(fp_line
			(start 0.67945 -0.3048)
			(end 0.67945 0.3048)
			(stroke
				(width 0.1)
				(type default)
			)
			(layer "F.Fab")
		)
		(fp_line
			(start 0.12065 -0.2794)
			(end 0.12065 -0.3048)
			(stroke
				(width 0.1)
				(type default)
			)
			(layer "F.Fab")
		)
		(fp_line
			(start 0.12065 -0.3048)
			(end 0.67945 -0.3048)
			(stroke
				(width 0.1)
				(type default)
			)
			(layer "F.Fab")
		)
		(fp_line
			(start 0.120396 0.3048)
			(end 0.120396 0.2794)
			(stroke
				(width 0.1)
				(type default)
			)
			(layer "F.Fab")
		)
		(fp_line
			(start 0.120396 0.2794)
			(end -0.12065 0.2794)
			(stroke
				(width 0.1)
				(type default)
			)
			(layer "F.Fab")
		)
		(fp_line
			(start -0.12065 0.3048)
			(end -0.67945 0.3048)
			(stroke
				(width 0.1)
				(type default)
			)
			(layer "F.Fab")
		)
		(fp_line
			(start -0.12065 0.2794)
			(end -0.12065 0.3048)
			(stroke
				(width 0.1)
				(type default)
			)
			(layer "F.Fab")
		)
		(fp_line
			(start -0.12065 -0.2794)
			(end 0.12065 -0.2794)
			(stroke
				(width 0.1)
				(type default)
			)
			(layer "F.Fab")
		)
		(fp_line
			(start -0.12065 -0.305054)
			(end -0.12065 -0.2794)
			(stroke
				(width 0.1)
				(type default)
			)
			(layer "F.Fab")
		)
		(fp_line
			(start -0.67945 0.3048)
			(end -0.67945 -0.305054)
			(stroke
				(width 0.1)
				(type default)
			)
			(layer "F.Fab")
		)
		(fp_line
			(start -0.67945 -0.305054)
			(end -0.12065 -0.305054)
			(stroke
				(width 0.1)
				(type default)
			)
			(layer "F.Fab")
		)
		(pad "1" smd circle
			(at -0.40005 0 180)
			(size 0 0)
			(layers "F.Cu" "F.Mask" "F.Paste")
			(net "FAN_3_PRESENT_R")
		)
		(pad "2" smd circle
			(at 0.40005 0 180)
			(size 0 0)
			(layers "F.Cu" "F.Mask" "F.Paste")
			(net "FAN_3_PRESENT")
		)
	)
	(footprint ""
		(layer "F.Cu")
		(at 21.5138 -162.941 90)
		(property "Reference" "R5274"
			(at 0 0 90)
			(layer "F.SilkS")
			(hide yes)
			(effects
				(font
					(size 1.27 1.27)
				)
			)
		)
		(property "Value" ""
			(at 0 0 90)
			(layer "F.Fab")
			(effects
				(font
					(size 1.27 1.27)
				)
			)
		)
		(duplicate_pad_numbers_are_jumpers no)
		(fp_line
			(start 0.7874 -0.4064)
			(end 0.7874 0.4064)
			(stroke
				(width 0.1524)
				(type default)
			)
			(layer "F.SilkS")
		)
		(fp_line
			(start -0.7874 -0.4064)
			(end 0.7874 -0.4064)
			(stroke
				(width 0.1524)
				(type default)
			)
			(layer "F.SilkS")
		)
		(fp_line
			(start 0.7874 0.4064)
			(end -0.7874 0.4064)
			(stroke
				(width 0.1524)
				(type default)
			)
			(layer "F.SilkS")
		)
		(fp_line
			(start -0.7874 0.4064)
			(end -0.7874 -0.4064)
			(stroke
				(width 0.1524)
				(type default)
			)
			(layer "F.SilkS")
		)
		(fp_line
			(start -0.12065 -0.305054)
			(end -0.12065 -0.2794)
			(stroke
				(width 0.1)
				(type default)
			)
			(layer "F.Fab")
		)
		(fp_line
			(start -0.67945 -0.305054)
			(end -0.12065 -0.305054)
			(stroke
				(width 0.1)
				(type default)
			)
			(layer "F.Fab")
		)
		(fp_line
			(start 0.67945 -0.3048)
			(end 0.67945 0.3048)
			(stroke
				(width 0.1)
				(type default)
			)
			(layer "F.Fab")
		)
		(fp_line
			(start 0.12065 -0.3048)
			(end 0.67945 -0.3048)
			(stroke
				(width 0.1)
				(type default)
			)
			(layer "F.Fab")
		)
		(fp_line
			(start 0.12065 -0.2794)
			(end 0.12065 -0.3048)
			(stroke
				(width 0.1)
				(type default)
			)
			(layer "F.Fab")
		)
		(fp_line
			(start -0.12065 -0.2794)
			(end 0.12065 -0.2794)
			(stroke
				(width 0.1)
				(type default)
			)
			(layer "F.Fab")
		)
		(fp_line
			(start 0.120396 0.2794)
			(end -0.12065 0.2794)
			(stroke
				(width 0.1)
				(type default)
			)
			(layer "F.Fab")
		)
		(fp_line
			(start -0.12065 0.2794)
			(end -0.12065 0.3048)
			(stroke
				(width 0.1)
				(type default)
			)
			(layer "F.Fab")
		)
		(fp_line
			(start 0.67945 0.3048)
			(end 0.120396 0.3048)
			(stroke
				(width 0.1)
				(type default)
			)
			(layer "F.Fab")
		)
		(fp_line
			(start 0.120396 0.3048)
			(end 0.120396 0.2794)
			(stroke
				(width 0.1)
				(type default)
			)
			(layer "F.Fab")
		)
		(fp_line
			(start -0.12065 0.3048)
			(end -0.67945 0.3048)
			(stroke
				(width 0.1)
				(type default)
			)
			(layer "F.Fab")
		)
		(fp_line
			(start -0.67945 0.3048)
			(end -0.67945 -0.305054)
			(stroke
				(width 0.1)
				(type default)
			)
			(layer "F.Fab")
		)
		(pad "1" smd circle
			(at -0.40005 0 90)
			(size 0 0)
			(layers "F.Cu" "F.Mask" "F.Paste")
			(net "SMB_FAN7_R_SCL")
		)
		(pad "2" smd circle
			(at 0.40005 0 90)
			(size 0 0)
			(layers "F.Cu" "F.Mask" "F.Paste")
			(net "P3V3_AUX")
		)
	)
	(footprint ""
		(layer "F.Cu")
		(at 24.257 -141.605 -90)
		(property "Reference" "R5276"
			(at 0 0 270)
			(layer "F.SilkS")
			(hide yes)
			(effects
				(font
					(size 1.27 1.27)
				)
			)
		)
		(property "Value" ""
			(at 0 0 270)
			(layer "F.Fab")
			(effects
				(font
					(size 1.27 1.27)
				)
			)
		)
		(duplicate_pad_numbers_are_jumpers no)
		(fp_line
			(start -0.7874 0.4064)
			(end -0.7874 -0.4064)
			(stroke
				(width 0.1524)
				(type default)
			)
			(layer "F.SilkS")
		)
		(fp_line
			(start 0.7874 0.4064)
			(end -0.7874 0.4064)
			(stroke
				(width 0.1524)
				(type default)
			)
			(layer "F.SilkS")
		)
		(fp_line
			(start -0.7874 -0.4064)
			(end 0.7874 -0.4064)
			(stroke
				(width 0.1524)
				(type default)
			)
			(layer "F.SilkS")
		)
		(fp_line
			(start 0.7874 -0.4064)
			(end 0.7874 0.4064)
			(stroke
				(width 0.1524)
				(type default)
			)
			(layer "F.SilkS")
		)
		(fp_line
			(start -0.67945 0.3048)
			(end -0.67945 -0.305054)
			(stroke
				(width 0.1)
				(type default)
			)
			(layer "F.Fab")
		)
		(fp_line
			(start -0.12065 0.3048)
			(end -0.67945 0.3048)
			(stroke
				(width 0.1)
				(type default)
			)
			(layer "F.Fab")
		)
		(fp_line
			(start 0.120396 0.3048)
			(end 0.120396 0.2794)
			(stroke
				(width 0.1)
				(type default)
			)
			(layer "F.Fab")
		)
		(fp_line
			(start 0.67945 0.3048)
			(end 0.120396 0.3048)
			(stroke
				(width 0.1)
				(type default)
			)
			(layer "F.Fab")
		)
		(fp_line
			(start -0.12065 0.2794)
			(end -0.12065 0.3048)
			(stroke
				(width 0.1)
				(type default)
			)
			(layer "F.Fab")
		)
		(fp_line
			(start 0.120396 0.2794)
			(end -0.12065 0.2794)
			(stroke
				(width 0.1)
				(type default)
			)
			(layer "F.Fab")
		)
		(fp_line
			(start -0.12065 -0.2794)
			(end 0.12065 -0.2794)
			(stroke
				(width 0.1)
				(type default)
			)
			(layer "F.Fab")
		)
		(fp_line
			(start 0.12065 -0.2794)
			(end 0.12065 -0.3048)
			(stroke
				(width 0.1)
				(type default)
			)
			(layer "F.Fab")
		)
		(fp_line
			(start 0.12065 -0.3048)
			(end 0.67945 -0.3048)
			(stroke
				(width 0.1)
				(type default)
			)
			(layer "F.Fab")
		)
		(fp_line
			(start 0.67945 -0.3048)
			(end 0.67945 0.3048)
			(stroke
				(width 0.1)
				(type default)
			)
			(layer "F.Fab")
		)
		(fp_line
			(start -0.67945 -0.305054)
			(end -0.12065 -0.305054)
			(stroke
				(width 0.1)
				(type default)
			)
			(layer "F.Fab")
		)
		(fp_line
			(start -0.12065 -0.305054)
			(end -0.12065 -0.2794)
			(stroke
				(width 0.1)
				(type default)
			)
			(layer "F.Fab")
		)
		(pad "1" smd circle
			(at -0.40005 0 270)
			(size 0 0)
			(layers "F.Cu" "F.Mask" "F.Paste")
			(net "SMB_FAN0_R_SCL")
		)
		(pad "2" smd circle
			(at 0.40005 0 270)
			(size 0 0)
			(layers "F.Cu" "F.Mask" "F.Paste")
			(net "P3V3_AUX")
		)
	)
	(footprint ""
		(layer "F.Cu")
		(at 38.6461 -135.128)
		(property "Reference" "R5575"
			(at 0 0 0)
			(layer "F.SilkS")
			(hide yes)
			(effects
				(font
					(size 1.27 1.27)
				)
			)
		)
		(property "Value" ""
			(at 0 0 0)
			(layer "F.Fab")
			(effects
				(font
					(size 1.27 1.27)
				)
			)
		)
		(duplicate_pad_numbers_are_jumpers no)
		(fp_line
			(start -0.7874 -0.4064)
			(end 0.7874 -0.4064)
			(stroke
				(width 0.1524)
				(type default)
			)
			(layer "F.SilkS")
		)
		(fp_line
			(start -0.7874 0.4064)
			(end -0.7874 -0.4064)
			(stroke
				(width 0.1524)
				(type default)
			)
			(layer "F.SilkS")
		)
		(fp_line
			(start 0.7874 -0.4064)
			(end 0.7874 0.4064)
			(stroke
				(width 0.1524)
				(type default)
			)
			(layer "F.SilkS")
		)
		(fp_line
			(start 0.7874 0.4064)
			(end -0.7874 0.4064)
			(stroke
				(width 0.1524)
				(type default)
			)
			(layer "F.SilkS")
		)
		(fp_line
			(start -0.67945 -0.305054)
			(end -0.12065 -0.305054)
			(stroke
				(width 0.1)
				(type default)
			)
			(layer "F.Fab")
		)
		(fp_line
			(start -0.67945 0.3048)
			(end -0.67945 -0.305054)
			(stroke
				(width 0.1)
				(type default)
			)
			(layer "F.Fab")
		)
		(fp_line
			(start -0.12065 -0.305054)
			(end -0.12065 -0.2794)
			(stroke
				(width 0.1)
				(type default)
			)
			(layer "F.Fab")
		)
		(fp_line
			(start -0.12065 -0.2794)
			(end 0.12065 -0.2794)
			(stroke
				(width 0.1)
				(type default)
			)
			(layer "F.Fab")
		)
		(fp_line
			(start -0.12065 0.2794)
			(end -0.12065 0.3048)
			(stroke
				(width 0.1)
				(type default)
			)
			(layer "F.Fab")
		)
		(fp_line
			(start -0.12065 0.3048)
			(end -0.67945 0.3048)
			(stroke
				(width 0.1)
				(type default)
			)
			(layer "F.Fab")
		)
		(fp_line
			(start 0.120396 0.2794)
			(end -0.12065 0.2794)
			(stroke
				(width 0.1)
				(type default)
			)
			(layer "F.Fab")
		)
		(fp_line
			(start 0.120396 0.3048)
			(end 0.120396 0.2794)
			(stroke
				(width 0.1)
				(type default)
			)
			(layer "F.Fab")
		)
		(fp_line
			(start 0.12065 -0.3048)
			(end 0.67945 -0.3048)
			(stroke
				(width 0.1)
				(type default)
			)
			(layer "F.Fab")
		)
		(fp_line
			(start 0.12065 -0.2794)
			(end 0.12065 -0.3048)
			(stroke
				(width 0.1)
				(type default)
			)
			(layer "F.Fab")
		)
		(fp_line
			(start 0.67945 -0.3048)
			(end 0.67945 0.3048)
			(stroke
				(width 0.1)
				(type default)
			)
			(layer "F.Fab")
		)
		(fp_line
			(start 0.67945 0.3048)
			(end 0.120396 0.3048)
			(stroke
				(width 0.1)
				(type default)
			)
			(layer "F.Fab")
		)
		(pad "1" smd rect
			(at -0.40005 0 180)
			(size 0.4572 0.508)
			(layers "F.Cu" "F.Mask" "F.Paste")
			(net "FAN_1_TACH_IL")
		)
		(pad "2" smd rect
			(at 0.40005 0 180)
			(size 0.4572 0.508)
			(layers "F.Cu" "F.Mask" "F.Paste")
			(net "FAN_1_TACH_IL_R2")
		)
	)
	(footprint ""
		(layer "F.Cu")
		(at 37.338 -292.354)
		(property "Reference" "D263"
			(at 1.905 0.02667 0)
			(unlocked yes)
			(layer "F.SilkS")
			(effects
				(font
					(size 0.7874 0.5842)
					(thickness 0.1524)
				)
				(justify left)
			)
		)
		(property "Value" ""
			(at 0 0 0)
			(layer "F.Fab")
			(effects
				(font
					(size 1.27 1.27)
				)
			)
		)
		(duplicate_pad_numbers_are_jumpers no)
		(fp_line
			(start -0.854964 -0.450088)
			(end -0.854964 0.450088)
			(stroke
				(width 0.1524)
				(type default)
			)
			(layer "F.SilkS")
		)
		(fp_line
			(start -0.854964 0.450088)
			(end 0.925068 0.450088)
			(stroke
				(width 0.1524)
				(type default)
			)
			(layer "F.SilkS")
		)
		(fp_line
			(start 0.845058 0.4064)
			(end 0.845058 -0.381)
			(stroke
				(width 0.1524)
				(type default)
			)
			(layer "F.SilkS")
		)
		(fp_line
			(start 0.870458 -0.2794)
			(end 0.845058 0.4064)
			(stroke
				(width 0.1524)
				(type default)
			)
			(layer "F.SilkS")
		)
		(fp_line
			(start 0.94488 -0.450088)
			(end -0.854964 -0.450088)
			(stroke
				(width 0.1524)
				(type default)
			)
			(layer "F.SilkS")
		)
		(fp_line
			(start 0.94488 0.450088)
			(end 0.94488 -0.450088)
			(stroke
				(width 0.1524)
				(type default)
			)
			(layer "F.SilkS")
		)
		(fp_line
			(start -0.54991 -0.350012)
			(end -0.54991 0.350012)
			(stroke
				(width 0.1)
				(type default)
			)
			(layer "F.Fab")
		)
		(fp_line
			(start -0.54991 0.350012)
			(end 0.54991 0.350012)
			(stroke
				(width 0.1)
				(type default)
			)
			(layer "F.Fab")
		)
		(fp_line
			(start 0.54991 -0.350012)
			(end -0.54991 -0.350012)
			(stroke
				(width 0.1)
				(type default)
			)
			(layer "F.Fab")
		)
		(fp_line
			(start 0.54991 0.350012)
			(end 0.54991 -0.350012)
			(stroke
				(width 0.1)
				(type default)
			)
			(layer "F.Fab")
		)
		(fp_text user "+"
			(at -0.635 0.09525 180)
			(unlocked yes)
			(layer "F.SilkS")
			(effects
				(font
					(size 1.905 1.4224)
					(thickness 0.1524)
				)
				(justify left)
			)
		)
		(fp_text user "-"
			(at 2.159 0.22225 180)
			(unlocked yes)
			(layer "F.SilkS")
			(effects
				(font
					(size 1.905 1.4224)
					(thickness 0.1524)
				)
				(justify left)
			)
		)
		(fp_text user "+"
			(at -0.808228 0.239014 180)
			(unlocked yes)
			(layer "F.Fab")
			(effects
				(font
					(size 1.905 1.4224)
					(thickness 0.1524)
				)
				(justify left)
			)
		)
		(fp_text user "-"
			(at 2.48539 0.239014 180)
			(unlocked yes)
			(layer "F.Fab")
			(effects
				(font
					(size 1.905 1.4224)
					(thickness 0.1524)
				)
				(justify left)
			)
		)
		(pad "A" smd rect
			(at -0.424942 0)
			(size 0.5588 0.6096)
			(layers "F.Cu" "F.Mask" "F.Paste")
			(net "GND")
		)
		(pad "C" smd rect
			(at 0.424942 0 180)
			(size 0.5588 0.6096)
			(layers "F.Cu" "F.Mask" "F.Paste")
			(net "FAN_0_FAIL_R_LED_N")
		)
	)
	(footprint ""
		(layer "F.Cu")
		(at 19.431 -17.526 90)
		(property "Reference" "C2016"
			(at 0 0 90)
			(layer "F.SilkS")
			(hide yes)
			(effects
				(font
					(size 1.27 1.27)
				)
			)
		)
		(property "Value" ""
			(at 0 0 90)
			(layer "F.Fab")
			(effects
				(font
					(size 1.27 1.27)
				)
			)
		)
		(duplicate_pad_numbers_are_jumpers no)
		(fp_line
			(start 0.7874 -0.4064)
			(end 0.7874 0.4064)
			(stroke
				(width 0.1524)
				(type default)
			)
			(layer "F.SilkS")
		)
		(fp_line
			(start -0.7874 -0.4064)
			(end 0.7874 -0.4064)
			(stroke
				(width 0.1524)
				(type default)
			)
			(layer "F.SilkS")
		)
		(fp_line
			(start 0.7874 0.4064)
			(end -0.7874 0.4064)
			(stroke
				(width 0.1524)
				(type default)
			)
			(layer "F.SilkS")
		)
		(fp_line
			(start -0.7874 0.4064)
			(end -0.7874 -0.4064)
			(stroke
				(width 0.1524)
				(type default)
			)
			(layer "F.SilkS")
		)
		(fp_line
			(start -0.12065 -0.305054)
			(end -0.12065 -0.2794)
			(stroke
				(width 0.1)
				(type default)
			)
			(layer "F.Fab")
		)
		(fp_line
			(start -0.67945 -0.305054)
			(end -0.12065 -0.305054)
			(stroke
				(width 0.1)
				(type default)
			)
			(layer "F.Fab")
		)
		(fp_line
			(start 0.67945 -0.3048)
			(end 0.67945 0.3048)
			(stroke
				(width 0.1)
				(type default)
			)
			(layer "F.Fab")
		)
		(fp_line
			(start 0.12065 -0.3048)
			(end 0.67945 -0.3048)
			(stroke
				(width 0.1)
				(type default)
			)
			(layer "F.Fab")
		)
		(fp_line
			(start 0.12065 -0.2794)
			(end 0.12065 -0.3048)
			(stroke
				(width 0.1)
				(type default)
			)
			(layer "F.Fab")
		)
		(fp_line
			(start -0.12065 -0.2794)
			(end 0.12065 -0.2794)
			(stroke
				(width 0.1)
				(type default)
			)
			(layer "F.Fab")
		)
		(fp_line
			(start 0.120396 0.2794)
			(end -0.12065 0.2794)
			(stroke
				(width 0.1)
				(type default)
			)
			(layer "F.Fab")
		)
		(fp_line
			(start -0.12065 0.2794)
			(end -0.12065 0.3048)
			(stroke
				(width 0.1)
				(type default)
			)
			(layer "F.Fab")
		)
		(fp_line
			(start 0.67945 0.3048)
			(end 0.120396 0.3048)
			(stroke
				(width 0.1)
				(type default)
			)
			(layer "F.Fab")
		)
		(fp_line
			(start 0.120396 0.3048)
			(end 0.120396 0.2794)
			(stroke
				(width 0.1)
				(type default)
			)
			(layer "F.Fab")
		)
		(fp_line
			(start -0.12065 0.3048)
			(end -0.67945 0.3048)
			(stroke
				(width 0.1)
				(type default)
			)
			(layer "F.Fab")
		)
		(fp_line
			(start -0.67945 0.3048)
			(end -0.67945 -0.305054)
			(stroke
				(width 0.1)
				(type default)
			)
			(layer "F.Fab")
		)
		(pad "1" smd circle
			(at -0.40005 0 90)
			(size 0 0)
			(layers "F.Cu" "F.Mask" "F.Paste")
			(net "FAN_4_TACH_IL_R")
		)
		(pad "2" smd circle
			(at 0.40005 0 90)
			(size 0 0)
			(layers "F.Cu" "F.Mask" "F.Paste")
			(net "GND")
		)
	)
	(footprint ""
		(layer "F.Cu")
		(at 34.417 -124.206 -90)
		(property "Reference" "R4937"
			(at 0 0 270)
			(layer "F.SilkS")
			(hide yes)
			(effects
				(font
					(size 1.27 1.27)
				)
			)
		)
		(property "Value" ""
			(at 0 0 270)
			(layer "F.Fab")
			(effects
				(font
					(size 1.27 1.27)
				)
			)
		)
		(duplicate_pad_numbers_are_jumpers no)
		(fp_line
			(start -0.7874 0.4064)
			(end -0.7874 -0.4064)
			(stroke
				(width 0.1524)
				(type default)
			)
			(layer "F.SilkS")
		)
		(fp_line
			(start 0.7874 0.4064)
			(end -0.7874 0.4064)
			(stroke
				(width 0.1524)
				(type default)
			)
			(layer "F.SilkS")
		)
		(fp_line
			(start -0.7874 -0.4064)
			(end 0.7874 -0.4064)
			(stroke
				(width 0.1524)
				(type default)
			)
			(layer "F.SilkS")
		)
		(fp_line
			(start 0.7874 -0.4064)
			(end 0.7874 0.4064)
			(stroke
				(width 0.1524)
				(type default)
			)
			(layer "F.SilkS")
		)
		(fp_line
			(start -0.67945 0.3048)
			(end -0.67945 -0.305054)
			(stroke
				(width 0.1)
				(type default)
			)
			(layer "F.Fab")
		)
		(fp_line
			(start -0.12065 0.3048)
			(end -0.67945 0.3048)
			(stroke
				(width 0.1)
				(type default)
			)
			(layer "F.Fab")
		)
		(fp_line
			(start 0.120396 0.3048)
			(end 0.120396 0.2794)
			(stroke
				(width 0.1)
				(type default)
			)
			(layer "F.Fab")
		)
		(fp_line
			(start 0.67945 0.3048)
			(end 0.120396 0.3048)
			(stroke
				(width 0.1)
				(type default)
			)
			(layer "F.Fab")
		)
		(fp_line
			(start -0.12065 0.2794)
			(end -0.12065 0.3048)
			(stroke
				(width 0.1)
				(type default)
			)
			(layer "F.Fab")
		)
		(fp_line
			(start 0.120396 0.2794)
			(end -0.12065 0.2794)
			(stroke
				(width 0.1)
				(type default)
			)
			(layer "F.Fab")
		)
		(fp_line
			(start -0.12065 -0.2794)
			(end 0.12065 -0.2794)
			(stroke
				(width 0.1)
				(type default)
			)
			(layer "F.Fab")
		)
		(fp_line
			(start 0.12065 -0.2794)
			(end 0.12065 -0.3048)
			(stroke
				(width 0.1)
				(type default)
			)
			(layer "F.Fab")
		)
		(fp_line
			(start 0.12065 -0.3048)
			(end 0.67945 -0.3048)
			(stroke
				(width 0.1)
				(type default)
			)
			(layer "F.Fab")
		)
		(fp_line
			(start 0.67945 -0.3048)
			(end 0.67945 0.3048)
			(stroke
				(width 0.1)
				(type default)
			)
			(layer "F.Fab")
		)
		(fp_line
			(start -0.67945 -0.305054)
			(end -0.12065 -0.305054)
			(stroke
				(width 0.1)
				(type default)
			)
			(layer "F.Fab")
		)
		(fp_line
			(start -0.12065 -0.305054)
			(end -0.12065 -0.2794)
			(stroke
				(width 0.1)
				(type default)
			)
			(layer "F.Fab")
		)
		(pad "1" smd circle
			(at -0.40005 0 270)
			(size 0 0)
			(layers "F.Cu" "F.Mask" "F.Paste")
			(net "MAX31790_U317_WD_START")
		)
		(pad "2" smd circle
			(at 0.40005 0 270)
			(size 0 0)
			(layers "F.Cu" "F.Mask" "F.Paste")
			(net "P3V3_AUX")
		)
	)
	(footprint ""
		(layer "F.Cu")
		(at 36.322 -286.639)
		(property "Reference" "D265"
			(at 2.286 0.53467 0)
			(unlocked yes)
			(layer "F.SilkS")
			(effects
				(font
					(size 0.7874 0.5842)
					(thickness 0.1524)
				)
				(justify left)
			)
		)
		(property "Value" ""
			(at 0 0 0)
			(layer "F.Fab")
			(effects
				(font
					(size 1.27 1.27)
				)
			)
		)
		(duplicate_pad_numbers_are_jumpers no)
		(fp_line
			(start -0.854964 -0.450088)
			(end -0.854964 0.450088)
			(stroke
				(width 0.1524)
				(type default)
			)
			(layer "F.SilkS")
		)
		(fp_line
			(start -0.854964 0.450088)
			(end 0.925068 0.450088)
			(stroke
				(width 0.1524)
				(type default)
			)
			(layer "F.SilkS")
		)
		(fp_line
			(start 0.845058 0.4064)
			(end 0.845058 -0.381)
			(stroke
				(width 0.1524)
				(type default)
			)
			(layer "F.SilkS")
		)
		(fp_line
			(start 0.870458 -0.2794)
			(end 0.845058 0.4064)
			(stroke
				(width 0.1524)
				(type default)
			)
			(layer "F.SilkS")
		)
		(fp_line
			(start 0.94488 -0.450088)
			(end -0.854964 -0.450088)
			(stroke
				(width 0.1524)
				(type default)
			)
			(layer "F.SilkS")
		)
		(fp_line
			(start 0.94488 0.450088)
			(end 0.94488 -0.450088)
			(stroke
				(width 0.1524)
				(type default)
			)
			(layer "F.SilkS")
		)
		(fp_line
			(start -0.54991 -0.350012)
			(end -0.54991 0.350012)
			(stroke
				(width 0.1)
				(type default)
			)
			(layer "F.Fab")
		)
		(fp_line
			(start -0.54991 0.350012)
			(end 0.54991 0.350012)
			(stroke
				(width 0.1)
				(type default)
			)
			(layer "F.Fab")
		)
		(fp_line
			(start 0.54991 -0.350012)
			(end -0.54991 -0.350012)
			(stroke
				(width 0.1)
				(type default)
			)
			(layer "F.Fab")
		)
		(fp_line
			(start 0.54991 0.350012)
			(end 0.54991 -0.350012)
			(stroke
				(width 0.1)
				(type default)
			)
			(layer "F.Fab")
		)
		(fp_text user "+"
			(at -0.5334 0.90805 180)
			(unlocked yes)
			(layer "F.SilkS")
			(effects
				(font
					(size 1.905 1.4224)
					(thickness 0.1524)
				)
				(justify left)
			)
		)
		(fp_text user "-"
			(at 2.286 0.22225 180)
			(unlocked yes)
			(layer "F.SilkS")
			(effects
				(font
					(size 1.905 1.4224)
					(thickness 0.1524)
				)
				(justify left)
			)
		)
		(fp_text user "+"
			(at -0.808228 0.239014 180)
			(unlocked yes)
			(layer "F.Fab")
			(effects
				(font
					(size 1.905 1.4224)
					(thickness 0.1524)
				)
				(justify left)
			)
		)
		(fp_text user "-"
			(at 2.48539 0.239014 180)
			(unlocked yes)
			(layer "F.Fab")
			(effects
				(font
					(size 1.905 1.4224)
					(thickness 0.1524)
				)
				(justify left)
			)
		)
		(pad "A" smd rect
			(at -0.424942 0)
			(size 0.5588 0.6096)
			(layers "F.Cu" "F.Mask" "F.Paste")
			(net "GND")
		)
		(pad "C" smd rect
			(at 0.424942 0 180)
			(size 0.5588 0.6096)
			(layers "F.Cu" "F.Mask" "F.Paste")
			(net "FAN_0_TACH_OL_D")
		)
	)
	(footprint ""
		(layer "F.Cu")
		(at 37.846 -133.858 180)
		(property "Reference" "R5600"
			(at 0 0 180)
			(layer "F.SilkS")
			(hide yes)
			(effects
				(font
					(size 1.27 1.27)
				)
			)
		)
		(property "Value" ""
			(at 0 0 180)
			(layer "F.Fab")
			(effects
				(font
					(size 1.27 1.27)
				)
			)
		)
		(duplicate_pad_numbers_are_jumpers no)
		(fp_line
			(start 0.7874 0.4064)
			(end -0.7874 0.4064)
			(stroke
				(width 0.1524)
				(type default)
			)
			(layer "F.SilkS")
		)
		(fp_line
			(start 0.7874 -0.4064)
			(end 0.7874 0.4064)
			(stroke
				(width 0.1524)
				(type default)
			)
			(layer "F.SilkS")
		)
		(fp_line
			(start -0.7874 0.4064)
			(end -0.7874 -0.4064)
			(stroke
				(width 0.1524)
				(type default)
			)
			(layer "F.SilkS")
		)
		(fp_line
			(start -0.7874 -0.4064)
			(end 0.7874 -0.4064)
			(stroke
				(width 0.1524)
				(type default)
			)
			(layer "F.SilkS")
		)
		(fp_line
			(start 0.67945 0.3048)
			(end 0.120396 0.3048)
			(stroke
				(width 0.1)
				(type default)
			)
			(layer "F.Fab")
		)
		(fp_line
			(start 0.67945 -0.3048)
			(end 0.67945 0.3048)
			(stroke
				(width 0.1)
				(type default)
			)
			(layer "F.Fab")
		)
		(fp_line
			(start 0.12065 -0.2794)
			(end 0.12065 -0.3048)
			(stroke
				(width 0.1)
				(type default)
			)
			(layer "F.Fab")
		)
		(fp_line
			(start 0.12065 -0.3048)
			(end 0.67945 -0.3048)
			(stroke
				(width 0.1)
				(type default)
			)
			(layer "F.Fab")
		)
		(fp_line
			(start 0.120396 0.3048)
			(end 0.120396 0.2794)
			(stroke
				(width 0.1)
				(type default)
			)
			(layer "F.Fab")
		)
		(fp_line
			(start 0.120396 0.2794)
			(end -0.12065 0.2794)
			(stroke
				(width 0.1)
				(type default)
			)
			(layer "F.Fab")
		)
		(fp_line
			(start -0.12065 0.3048)
			(end -0.67945 0.3048)
			(stroke
				(width 0.1)
				(type default)
			)
			(layer "F.Fab")
		)
		(fp_line
			(start -0.12065 0.2794)
			(end -0.12065 0.3048)
			(stroke
				(width 0.1)
				(type default)
			)
			(layer "F.Fab")
		)
		(fp_line
			(start -0.12065 -0.2794)
			(end 0.12065 -0.2794)
			(stroke
				(width 0.1)
				(type default)
			)
			(layer "F.Fab")
		)
		(fp_line
			(start -0.12065 -0.305054)
			(end -0.12065 -0.2794)
			(stroke
				(width 0.1)
				(type default)
			)
			(layer "F.Fab")
		)
		(fp_line
			(start -0.67945 0.3048)
			(end -0.67945 -0.305054)
			(stroke
				(width 0.1)
				(type default)
			)
			(layer "F.Fab")
		)
		(fp_line
			(start -0.67945 -0.305054)
			(end -0.12065 -0.305054)
			(stroke
				(width 0.1)
				(type default)
			)
			(layer "F.Fab")
		)
		(pad "1" smd rect
			(at -0.40005 0)
			(size 0.4572 0.508)
			(layers "F.Cu" "F.Mask" "F.Paste")
			(net "FAN_0_TACH_OL")
		)
		(pad "2" smd rect
			(at 0.40005 0)
			(size 0.4572 0.508)
			(layers "F.Cu" "F.Mask" "F.Paste")
			(net "FAN_0_TACH_OL_R1")
		)
	)
	(footprint ""
		(layer "F.Cu")
		(at 14.07795 -122.047 180)
		(property "Reference" "R5585"
			(at 0 0 180)
			(layer "F.SilkS")
			(hide yes)
			(effects
				(font
					(size 1.27 1.27)
				)
			)
		)
		(property "Value" ""
			(at 0 0 180)
			(layer "F.Fab")
			(effects
				(font
					(size 1.27 1.27)
				)
			)
		)
		(duplicate_pad_numbers_are_jumpers no)
		(fp_line
			(start 0.7874 0.4064)
			(end -0.7874 0.4064)
			(stroke
				(width 0.1524)
				(type default)
			)
			(layer "F.SilkS")
		)
		(fp_line
			(start 0.7874 -0.4064)
			(end 0.7874 0.4064)
			(stroke
				(width 0.1524)
				(type default)
			)
			(layer "F.SilkS")
		)
		(fp_line
			(start -0.7874 0.4064)
			(end -0.7874 -0.4064)
			(stroke
				(width 0.1524)
				(type default)
			)
			(layer "F.SilkS")
		)
		(fp_line
			(start -0.7874 -0.4064)
			(end 0.7874 -0.4064)
			(stroke
				(width 0.1524)
				(type default)
			)
			(layer "F.SilkS")
		)
		(fp_line
			(start 0.67945 0.3048)
			(end 0.120396 0.3048)
			(stroke
				(width 0.1)
				(type default)
			)
			(layer "F.Fab")
		)
		(fp_line
			(start 0.67945 -0.3048)
			(end 0.67945 0.3048)
			(stroke
				(width 0.1)
				(type default)
			)
			(layer "F.Fab")
		)
		(fp_line
			(start 0.12065 -0.2794)
			(end 0.12065 -0.3048)
			(stroke
				(width 0.1)
				(type default)
			)
			(layer "F.Fab")
		)
		(fp_line
			(start 0.12065 -0.3048)
			(end 0.67945 -0.3048)
			(stroke
				(width 0.1)
				(type default)
			)
			(layer "F.Fab")
		)
		(fp_line
			(start 0.120396 0.3048)
			(end 0.120396 0.2794)
			(stroke
				(width 0.1)
				(type default)
			)
			(layer "F.Fab")
		)
		(fp_line
			(start 0.120396 0.2794)
			(end -0.12065 0.2794)
			(stroke
				(width 0.1)
				(type default)
			)
			(layer "F.Fab")
		)
		(fp_line
			(start -0.12065 0.3048)
			(end -0.67945 0.3048)
			(stroke
				(width 0.1)
				(type default)
			)
			(layer "F.Fab")
		)
		(fp_line
			(start -0.12065 0.2794)
			(end -0.12065 0.3048)
			(stroke
				(width 0.1)
				(type default)
			)
			(layer "F.Fab")
		)
		(fp_line
			(start -0.12065 -0.2794)
			(end 0.12065 -0.2794)
			(stroke
				(width 0.1)
				(type default)
			)
			(layer "F.Fab")
		)
		(fp_line
			(start -0.12065 -0.305054)
			(end -0.12065 -0.2794)
			(stroke
				(width 0.1)
				(type default)
			)
			(layer "F.Fab")
		)
		(fp_line
			(start -0.67945 0.3048)
			(end -0.67945 -0.305054)
			(stroke
				(width 0.1)
				(type default)
			)
			(layer "F.Fab")
		)
		(fp_line
			(start -0.67945 -0.305054)
			(end -0.12065 -0.305054)
			(stroke
				(width 0.1)
				(type default)
			)
			(layer "F.Fab")
		)
		(pad "1" smd rect
			(at -0.40005 0)
			(size 0.4572 0.508)
			(layers "F.Cu" "F.Mask" "F.Paste")
			(net "FAN_4_PWM")
		)
		(pad "2" smd rect
			(at 0.40005 0)
			(size 0.4572 0.508)
			(layers "F.Cu" "F.Mask" "F.Paste")
			(net "FAN_4_PWM_R2")
		)
	)
	(footprint ""
		(layer "F.Cu")
		(at 31.623 -141.351 -90)
		(property "Reference" "R5280"
			(at 0 0 270)
			(layer "F.SilkS")
			(hide yes)
			(effects
				(font
					(size 1.27 1.27)
				)
			)
		)
		(property "Value" ""
			(at 0 0 270)
			(layer "F.Fab")
			(effects
				(font
					(size 1.27 1.27)
				)
			)
		)
		(duplicate_pad_numbers_are_jumpers no)
		(fp_line
			(start -0.7874 0.4064)
			(end -0.7874 -0.4064)
			(stroke
				(width 0.1524)
				(type default)
			)
			(layer "F.SilkS")
		)
		(fp_line
			(start 0.7874 0.4064)
			(end -0.7874 0.4064)
			(stroke
				(width 0.1524)
				(type default)
			)
			(layer "F.SilkS")
		)
		(fp_line
			(start -0.7874 -0.4064)
			(end 0.7874 -0.4064)
			(stroke
				(width 0.1524)
				(type default)
			)
			(layer "F.SilkS")
		)
		(fp_line
			(start 0.7874 -0.4064)
			(end 0.7874 0.4064)
			(stroke
				(width 0.1524)
				(type default)
			)
			(layer "F.SilkS")
		)
		(fp_line
			(start -0.67945 0.3048)
			(end -0.67945 -0.305054)
			(stroke
				(width 0.1)
				(type default)
			)
			(layer "F.Fab")
		)
		(fp_line
			(start -0.12065 0.3048)
			(end -0.67945 0.3048)
			(stroke
				(width 0.1)
				(type default)
			)
			(layer "F.Fab")
		)
		(fp_line
			(start 0.120396 0.3048)
			(end 0.120396 0.2794)
			(stroke
				(width 0.1)
				(type default)
			)
			(layer "F.Fab")
		)
		(fp_line
			(start 0.67945 0.3048)
			(end 0.120396 0.3048)
			(stroke
				(width 0.1)
				(type default)
			)
			(layer "F.Fab")
		)
		(fp_line
			(start -0.12065 0.2794)
			(end -0.12065 0.3048)
			(stroke
				(width 0.1)
				(type default)
			)
			(layer "F.Fab")
		)
		(fp_line
			(start 0.120396 0.2794)
			(end -0.12065 0.2794)
			(stroke
				(width 0.1)
				(type default)
			)
			(layer "F.Fab")
		)
		(fp_line
			(start -0.12065 -0.2794)
			(end 0.12065 -0.2794)
			(stroke
				(width 0.1)
				(type default)
			)
			(layer "F.Fab")
		)
		(fp_line
			(start 0.12065 -0.2794)
			(end 0.12065 -0.3048)
			(stroke
				(width 0.1)
				(type default)
			)
			(layer "F.Fab")
		)
		(fp_line
			(start 0.12065 -0.3048)
			(end 0.67945 -0.3048)
			(stroke
				(width 0.1)
				(type default)
			)
			(layer "F.Fab")
		)
		(fp_line
			(start 0.67945 -0.3048)
			(end 0.67945 0.3048)
			(stroke
				(width 0.1)
				(type default)
			)
			(layer "F.Fab")
		)
		(fp_line
			(start -0.67945 -0.305054)
			(end -0.12065 -0.305054)
			(stroke
				(width 0.1)
				(type default)
			)
			(layer "F.Fab")
		)
		(fp_line
			(start -0.12065 -0.305054)
			(end -0.12065 -0.2794)
			(stroke
				(width 0.1)
				(type default)
			)
			(layer "F.Fab")
		)
		(pad "1" smd circle
			(at -0.40005 0 270)
			(size 0 0)
			(layers "F.Cu" "F.Mask" "F.Paste")
			(net "SMB_FAN2_R_SCL")
		)
		(pad "2" smd circle
			(at 0.40005 0 270)
			(size 0 0)
			(layers "F.Cu" "F.Mask" "F.Paste")
			(net "P3V3_AUX")
		)
	)
	(footprint ""
		(layer "F.Cu")
		(at 18.679922 -286.6771 180)
		(property "Reference" "D261"
			(at 1.407922 -1.58877 0)
			(unlocked yes)
			(layer "F.SilkS")
			(effects
				(font
					(size 0.7874 0.5842)
					(thickness 0.1524)
				)
				(justify left)
			)
		)
		(property "Value" ""
			(at 0 0 180)
			(layer "F.Fab")
			(effects
				(font
					(size 1.27 1.27)
				)
			)
		)
		(duplicate_pad_numbers_are_jumpers no)
		(fp_line
			(start 0.94488 0.450088)
			(end 0.94488 -0.450088)
			(stroke
				(width 0.1524)
				(type default)
			)
			(layer "F.SilkS")
		)
		(fp_line
			(start 0.94488 -0.450088)
			(end -0.854964 -0.450088)
			(stroke
				(width 0.1524)
				(type default)
			)
			(layer "F.SilkS")
		)
		(fp_line
			(start 0.870458 -0.2794)
			(end 0.845058 0.4064)
			(stroke
				(width 0.1524)
				(type default)
			)
			(layer "F.SilkS")
		)
		(fp_line
			(start 0.845058 0.4064)
			(end 0.845058 -0.381)
			(stroke
				(width 0.1524)
				(type default)
			)
			(layer "F.SilkS")
		)
		(fp_line
			(start -0.854964 0.450088)
			(end 0.925068 0.450088)
			(stroke
				(width 0.1524)
				(type default)
			)
			(layer "F.SilkS")
		)
		(fp_line
			(start -0.854964 -0.450088)
			(end -0.854964 0.450088)
			(stroke
				(width 0.1524)
				(type default)
			)
			(layer "F.SilkS")
		)
		(fp_line
			(start 0.54991 0.350012)
			(end 0.54991 -0.350012)
			(stroke
				(width 0.1)
				(type default)
			)
			(layer "F.Fab")
		)
		(fp_line
			(start 0.54991 -0.350012)
			(end -0.54991 -0.350012)
			(stroke
				(width 0.1)
				(type default)
			)
			(layer "F.Fab")
		)
		(fp_line
			(start -0.54991 0.350012)
			(end 0.54991 0.350012)
			(stroke
				(width 0.1)
				(type default)
			)
			(layer "F.Fab")
		)
		(fp_line
			(start -0.54991 -0.350012)
			(end -0.54991 0.350012)
			(stroke
				(width 0.1)
				(type default)
			)
			(layer "F.Fab")
		)
		(fp_text user "-"
			(at 1.915922 -0.57785 0)
			(unlocked yes)
			(layer "F.SilkS")
			(effects
				(font
					(size 1.905 1.4224)
					(thickness 0.1524)
				)
				(justify left)
			)
		)
		(fp_text user "+"
			(at -1.132078 0.18415 0)
			(unlocked yes)
			(layer "F.SilkS")
			(effects
				(font
					(size 1.905 1.4224)
					(thickness 0.1524)
				)
				(justify left)
			)
		)
		(fp_text user "-"
			(at 2.48539 0.239014 0)
			(unlocked yes)
			(layer "F.Fab")
			(effects
				(font
					(size 1.905 1.4224)
					(thickness 0.1524)
				)
				(justify left)
			)
		)
		(fp_text user "+"
			(at -0.808228 0.239014 0)
			(unlocked yes)
			(layer "F.Fab")
			(effects
				(font
					(size 1.905 1.4224)
					(thickness 0.1524)
				)
				(justify left)
			)
		)
		(pad "A" smd rect
			(at -0.424942 0 180)
			(size 0.5588 0.6096)
			(layers "F.Cu" "F.Mask" "F.Paste")
			(net "GND")
		)
		(pad "C" smd rect
			(at 0.424942 0)
			(size 0.5588 0.6096)
			(layers "F.Cu" "F.Mask" "F.Paste")
			(net "FAN_7_PWM_OL_R")
		)
	)
	(footprint ""
		(layer "F.Cu")
		(at 31.623 -121.92 90)
		(property "Reference" "R4782"
			(at 0 0 90)
			(layer "F.SilkS")
			(hide yes)
			(effects
				(font
					(size 1.27 1.27)
				)
			)
		)
		(property "Value" ""
			(at 0 0 90)
			(layer "F.Fab")
			(effects
				(font
					(size 1.27 1.27)
				)
			)
		)
		(duplicate_pad_numbers_are_jumpers no)
		(fp_line
			(start 0.7874 -0.4064)
			(end 0.7874 0.4064)
			(stroke
				(width 0.1524)
				(type default)
			)
			(layer "F.SilkS")
		)
		(fp_line
			(start -0.7874 -0.4064)
			(end 0.7874 -0.4064)
			(stroke
				(width 0.1524)
				(type default)
			)
			(layer "F.SilkS")
		)
		(fp_line
			(start 0.7874 0.4064)
			(end -0.7874 0.4064)
			(stroke
				(width 0.1524)
				(type default)
			)
			(layer "F.SilkS")
		)
		(fp_line
			(start -0.7874 0.4064)
			(end -0.7874 -0.4064)
			(stroke
				(width 0.1524)
				(type default)
			)
			(layer "F.SilkS")
		)
		(fp_line
			(start -0.12065 -0.305054)
			(end -0.12065 -0.2794)
			(stroke
				(width 0.1)
				(type default)
			)
			(layer "F.Fab")
		)
		(fp_line
			(start -0.67945 -0.305054)
			(end -0.12065 -0.305054)
			(stroke
				(width 0.1)
				(type default)
			)
			(layer "F.Fab")
		)
		(fp_line
			(start 0.67945 -0.3048)
			(end 0.67945 0.3048)
			(stroke
				(width 0.1)
				(type default)
			)
			(layer "F.Fab")
		)
		(fp_line
			(start 0.12065 -0.3048)
			(end 0.67945 -0.3048)
			(stroke
				(width 0.1)
				(type default)
			)
			(layer "F.Fab")
		)
		(fp_line
			(start 0.12065 -0.2794)
			(end 0.12065 -0.3048)
			(stroke
				(width 0.1)
				(type default)
			)
			(layer "F.Fab")
		)
		(fp_line
			(start -0.12065 -0.2794)
			(end 0.12065 -0.2794)
			(stroke
				(width 0.1)
				(type default)
			)
			(layer "F.Fab")
		)
		(fp_line
			(start 0.120396 0.2794)
			(end -0.12065 0.2794)
			(stroke
				(width 0.1)
				(type default)
			)
			(layer "F.Fab")
		)
		(fp_line
			(start -0.12065 0.2794)
			(end -0.12065 0.3048)
			(stroke
				(width 0.1)
				(type default)
			)
			(layer "F.Fab")
		)
		(fp_line
			(start 0.67945 0.3048)
			(end 0.120396 0.3048)
			(stroke
				(width 0.1)
				(type default)
			)
			(layer "F.Fab")
		)
		(fp_line
			(start 0.120396 0.3048)
			(end 0.120396 0.2794)
			(stroke
				(width 0.1)
				(type default)
			)
			(layer "F.Fab")
		)
		(fp_line
			(start -0.12065 0.3048)
			(end -0.67945 0.3048)
			(stroke
				(width 0.1)
				(type default)
			)
			(layer "F.Fab")
		)
		(fp_line
			(start -0.67945 0.3048)
			(end -0.67945 -0.305054)
			(stroke
				(width 0.1)
				(type default)
			)
			(layer "F.Fab")
		)
		(pad "1" smd circle
			(at -0.40005 0 90)
			(size 0 0)
			(layers "F.Cu" "F.Mask" "F.Paste")
			(net "GND")
		)
		(pad "2" smd circle
			(at 0.40005 0 90)
			(size 0 0)
			(layers "F.Cu" "F.Mask" "F.Paste")
			(net "MAX31790_U317_ADD1")
		)
	)
	(footprint ""
		(layer "F.Cu")
		(at 36.322 -208.308956)
		(property "Reference" "D272"
			(at 2.794 -0.706374 0)
			(unlocked yes)
			(layer "F.SilkS")
			(effects
				(font
					(size 0.7874 0.5842)
					(thickness 0.1524)
				)
				(justify left)
			)
		)
		(property "Value" ""
			(at 0 0 0)
			(layer "F.Fab")
			(effects
				(font
					(size 1.27 1.27)
				)
			)
		)
		(duplicate_pad_numbers_are_jumpers no)
		(fp_line
			(start -0.854964 -0.450088)
			(end -0.854964 0.450088)
			(stroke
				(width 0.1524)
				(type default)
			)
			(layer "F.SilkS")
		)
		(fp_line
			(start -0.854964 0.450088)
			(end 0.925068 0.450088)
			(stroke
				(width 0.1524)
				(type default)
			)
			(layer "F.SilkS")
		)
		(fp_line
			(start 0.845058 0.4064)
			(end 0.845058 -0.381)
			(stroke
				(width 0.1524)
				(type default)
			)
			(layer "F.SilkS")
		)
		(fp_line
			(start 0.870458 -0.2794)
			(end 0.845058 0.4064)
			(stroke
				(width 0.1524)
				(type default)
			)
			(layer "F.SilkS")
		)
		(fp_line
			(start 0.94488 -0.450088)
			(end -0.854964 -0.450088)
			(stroke
				(width 0.1524)
				(type default)
			)
			(layer "F.SilkS")
		)
		(fp_line
			(start 0.94488 0.450088)
			(end 0.94488 -0.450088)
			(stroke
				(width 0.1524)
				(type default)
			)
			(layer "F.SilkS")
		)
		(fp_line
			(start -0.54991 -0.350012)
			(end -0.54991 0.350012)
			(stroke
				(width 0.1)
				(type default)
			)
			(layer "F.Fab")
		)
		(fp_line
			(start -0.54991 0.350012)
			(end 0.54991 0.350012)
			(stroke
				(width 0.1)
				(type default)
			)
			(layer "F.Fab")
		)
		(fp_line
			(start 0.54991 -0.350012)
			(end -0.54991 -0.350012)
			(stroke
				(width 0.1)
				(type default)
			)
			(layer "F.Fab")
		)
		(fp_line
			(start 0.54991 0.350012)
			(end 0.54991 -0.350012)
			(stroke
				(width 0.1)
				(type default)
			)
			(layer "F.Fab")
		)
		(fp_text user "+"
			(at -0.681228 0.239014 180)
			(unlocked yes)
			(layer "F.SilkS")
			(effects
				(font
					(size 1.905 1.4224)
					(thickness 0.1524)
				)
				(justify left)
			)
		)
		(fp_text user "-"
			(at 2.159 0.251206 180)
			(unlocked yes)
			(layer "F.SilkS")
			(effects
				(font
					(size 1.905 1.4224)
					(thickness 0.1524)
				)
				(justify left)
			)
		)
		(fp_text user "+"
			(at -0.808228 0.239014 180)
			(unlocked yes)
			(layer "F.Fab")
			(effects
				(font
					(size 1.905 1.4224)
					(thickness 0.1524)
				)
				(justify left)
			)
		)
		(fp_text user "-"
			(at 2.48539 0.239014 180)
			(unlocked yes)
			(layer "F.Fab")
			(effects
				(font
					(size 1.905 1.4224)
					(thickness 0.1524)
				)
				(justify left)
			)
		)
		(pad "A" smd rect
			(at -0.424942 0)
			(size 0.5588 0.6096)
			(layers "F.Cu" "F.Mask" "F.Paste")
			(net "GND")
		)
		(pad "C" smd rect
			(at 0.424942 0 180)
			(size 0.5588 0.6096)
			(layers "F.Cu" "F.Mask" "F.Paste")
			(net "FAN_1_TACH_IL_D")
		)
	)
	(footprint ""
		(layer "F.Cu")
		(at 30.734 -162.941 90)
		(property "Reference" "R5271"
			(at 0 0 90)
			(layer "F.SilkS")
			(hide yes)
			(effects
				(font
					(size 1.27 1.27)
				)
			)
		)
		(property "Value" ""
			(at 0 0 90)
			(layer "F.Fab")
			(effects
				(font
					(size 1.27 1.27)
				)
			)
		)
		(duplicate_pad_numbers_are_jumpers no)
		(fp_line
			(start 0.7874 -0.4064)
			(end 0.7874 0.4064)
			(stroke
				(width 0.1524)
				(type default)
			)
			(layer "F.SilkS")
		)
		(fp_line
			(start -0.7874 -0.4064)
			(end 0.7874 -0.4064)
			(stroke
				(width 0.1524)
				(type default)
			)
			(layer "F.SilkS")
		)
		(fp_line
			(start 0.7874 0.4064)
			(end -0.7874 0.4064)
			(stroke
				(width 0.1524)
				(type default)
			)
			(layer "F.SilkS")
		)
		(fp_line
			(start -0.7874 0.4064)
			(end -0.7874 -0.4064)
			(stroke
				(width 0.1524)
				(type default)
			)
			(layer "F.SilkS")
		)
		(fp_line
			(start -0.12065 -0.305054)
			(end -0.12065 -0.2794)
			(stroke
				(width 0.1)
				(type default)
			)
			(layer "F.Fab")
		)
		(fp_line
			(start -0.67945 -0.305054)
			(end -0.12065 -0.305054)
			(stroke
				(width 0.1)
				(type default)
			)
			(layer "F.Fab")
		)
		(fp_line
			(start 0.67945 -0.3048)
			(end 0.67945 0.3048)
			(stroke
				(width 0.1)
				(type default)
			)
			(layer "F.Fab")
		)
		(fp_line
			(start 0.12065 -0.3048)
			(end 0.67945 -0.3048)
			(stroke
				(width 0.1)
				(type default)
			)
			(layer "F.Fab")
		)
		(fp_line
			(start 0.12065 -0.2794)
			(end 0.12065 -0.3048)
			(stroke
				(width 0.1)
				(type default)
			)
			(layer "F.Fab")
		)
		(fp_line
			(start -0.12065 -0.2794)
			(end 0.12065 -0.2794)
			(stroke
				(width 0.1)
				(type default)
			)
			(layer "F.Fab")
		)
		(fp_line
			(start 0.120396 0.2794)
			(end -0.12065 0.2794)
			(stroke
				(width 0.1)
				(type default)
			)
			(layer "F.Fab")
		)
		(fp_line
			(start -0.12065 0.2794)
			(end -0.12065 0.3048)
			(stroke
				(width 0.1)
				(type default)
			)
			(layer "F.Fab")
		)
		(fp_line
			(start 0.67945 0.3048)
			(end 0.120396 0.3048)
			(stroke
				(width 0.1)
				(type default)
			)
			(layer "F.Fab")
		)
		(fp_line
			(start 0.120396 0.3048)
			(end 0.120396 0.2794)
			(stroke
				(width 0.1)
				(type default)
			)
			(layer "F.Fab")
		)
		(fp_line
			(start -0.12065 0.3048)
			(end -0.67945 0.3048)
			(stroke
				(width 0.1)
				(type default)
			)
			(layer "F.Fab")
		)
		(fp_line
			(start -0.67945 0.3048)
			(end -0.67945 -0.305054)
			(stroke
				(width 0.1)
				(type default)
			)
			(layer "F.Fab")
		)
		(pad "1" smd circle
			(at -0.40005 0 90)
			(size 0 0)
			(layers "F.Cu" "F.Mask" "F.Paste")
			(net "SMB_FAN5_R_SDA")
		)
		(pad "2" smd circle
			(at 0.40005 0 90)
			(size 0 0)
			(layers "F.Cu" "F.Mask" "F.Paste")
			(net "P3V3_AUX")
		)
	)
	(footprint ""
		(layer "F.Cu")
		(at 37.338 -105.086912)
		(property "Reference" "D276"
			(at 1.32334 -0.098298 0)
			(unlocked yes)
			(layer "F.SilkS")
			(effects
				(font
					(size 0.7874 0.5842)
					(thickness 0.1524)
				)
				(justify left)
			)
		)
		(property "Value" ""
			(at 0 0 0)
			(layer "F.Fab")
			(effects
				(font
					(size 1.27 1.27)
				)
			)
		)
		(duplicate_pad_numbers_are_jumpers no)
		(fp_line
			(start -0.854964 -0.450088)
			(end -0.854964 0.450088)
			(stroke
				(width 0.1524)
				(type default)
			)
			(layer "F.SilkS")
		)
		(fp_line
			(start -0.854964 0.450088)
			(end 0.925068 0.450088)
			(stroke
				(width 0.1524)
				(type default)
			)
			(layer "F.SilkS")
		)
		(fp_line
			(start 0.845058 0.4064)
			(end 0.845058 -0.381)
			(stroke
				(width 0.1524)
				(type default)
			)
			(layer "F.SilkS")
		)
		(fp_line
			(start 0.870458 -0.2794)
			(end 0.845058 0.4064)
			(stroke
				(width 0.1524)
				(type default)
			)
			(layer "F.SilkS")
		)
		(fp_line
			(start 0.94488 -0.450088)
			(end -0.854964 -0.450088)
			(stroke
				(width 0.1524)
				(type default)
			)
			(layer "F.SilkS")
		)
		(fp_line
			(start 0.94488 0.450088)
			(end 0.94488 -0.450088)
			(stroke
				(width 0.1524)
				(type default)
			)
			(layer "F.SilkS")
		)
		(fp_line
			(start -0.54991 -0.350012)
			(end -0.54991 0.350012)
			(stroke
				(width 0.1)
				(type default)
			)
			(layer "F.Fab")
		)
		(fp_line
			(start -0.54991 0.350012)
			(end 0.54991 0.350012)
			(stroke
				(width 0.1)
				(type default)
			)
			(layer "F.Fab")
		)
		(fp_line
			(start 0.54991 -0.350012)
			(end -0.54991 -0.350012)
			(stroke
				(width 0.1)
				(type default)
			)
			(layer "F.Fab")
		)
		(fp_line
			(start 0.54991 0.350012)
			(end 0.54991 -0.350012)
			(stroke
				(width 0.1)
				(type default)
			)
			(layer "F.Fab")
		)
		(fp_text user "+"
			(at -0.381 -0.408178 180)
			(unlocked yes)
			(layer "F.SilkS")
			(effects
				(font
					(size 1.905 1.4224)
					(thickness 0.1524)
				)
				(justify left)
			)
		)
		(fp_text user "-"
			(at 1.27 -0.608838 180)
			(unlocked yes)
			(layer "F.SilkS")
			(effects
				(font
					(size 1.905 1.4224)
					(thickness 0.1524)
				)
				(justify left)
			)
		)
		(fp_text user "+"
			(at -0.808228 0.239014 180)
			(unlocked yes)
			(layer "F.Fab")
			(effects
				(font
					(size 1.905 1.4224)
					(thickness 0.1524)
				)
				(justify left)
			)
		)
		(fp_text user "-"
			(at 2.48539 0.239014 180)
			(unlocked yes)
			(layer "F.Fab")
			(effects
				(font
					(size 1.905 1.4224)
					(thickness 0.1524)
				)
				(justify left)
			)
		)
		(pad "A" smd rect
			(at -0.424942 0)
			(size 0.5588 0.6096)
			(layers "F.Cu" "F.Mask" "F.Paste")
			(net "GND")
		)
		(pad "C" smd rect
			(at 0.424942 0 180)
			(size 0.5588 0.6096)
			(layers "F.Cu" "F.Mask" "F.Paste")
			(net "FAN_2_OK_R_LED_N")
		)
	)
	(footprint ""
		(layer "F.Cu")
		(at 11.557 -73.914 90)
		(property "Reference" "PR57"
			(at 0 0 90)
			(layer "F.SilkS")
			(hide yes)
			(effects
				(font
					(size 1.27 1.27)
				)
			)
		)
		(property "Value" ""
			(at 0 0 90)
			(layer "F.Fab")
			(effects
				(font
					(size 1.27 1.27)
				)
			)
		)
		(duplicate_pad_numbers_are_jumpers no)
		(fp_line
			(start 0.7874 -0.4064)
			(end 0.7874 0.4064)
			(stroke
				(width 0.1524)
				(type default)
			)
			(layer "F.SilkS")
		)
		(fp_line
			(start -0.7874 -0.4064)
			(end 0.7874 -0.4064)
			(stroke
				(width 0.1524)
				(type default)
			)
			(layer "F.SilkS")
		)
		(fp_line
			(start 0.7874 0.4064)
			(end -0.7874 0.4064)
			(stroke
				(width 0.1524)
				(type default)
			)
			(layer "F.SilkS")
		)
		(fp_line
			(start -0.7874 0.4064)
			(end -0.7874 -0.4064)
			(stroke
				(width 0.1524)
				(type default)
			)
			(layer "F.SilkS")
		)
		(fp_line
			(start -0.12065 -0.305054)
			(end -0.12065 -0.2794)
			(stroke
				(width 0.1)
				(type default)
			)
			(layer "F.Fab")
		)
		(fp_line
			(start -0.67945 -0.305054)
			(end -0.12065 -0.305054)
			(stroke
				(width 0.1)
				(type default)
			)
			(layer "F.Fab")
		)
		(fp_line
			(start 0.67945 -0.3048)
			(end 0.67945 0.3048)
			(stroke
				(width 0.1)
				(type default)
			)
			(layer "F.Fab")
		)
		(fp_line
			(start 0.12065 -0.3048)
			(end 0.67945 -0.3048)
			(stroke
				(width 0.1)
				(type default)
			)
			(layer "F.Fab")
		)
		(fp_line
			(start 0.12065 -0.2794)
			(end 0.12065 -0.3048)
			(stroke
				(width 0.1)
				(type default)
			)
			(layer "F.Fab")
		)
		(fp_line
			(start -0.12065 -0.2794)
			(end 0.12065 -0.2794)
			(stroke
				(width 0.1)
				(type default)
			)
			(layer "F.Fab")
		)
		(fp_line
			(start 0.120396 0.2794)
			(end -0.12065 0.2794)
			(stroke
				(width 0.1)
				(type default)
			)
			(layer "F.Fab")
		)
		(fp_line
			(start -0.12065 0.2794)
			(end -0.12065 0.3048)
			(stroke
				(width 0.1)
				(type default)
			)
			(layer "F.Fab")
		)
		(fp_line
			(start 0.67945 0.3048)
			(end 0.120396 0.3048)
			(stroke
				(width 0.1)
				(type default)
			)
			(layer "F.Fab")
		)
		(fp_line
			(start 0.120396 0.3048)
			(end 0.120396 0.2794)
			(stroke
				(width 0.1)
				(type default)
			)
			(layer "F.Fab")
		)
		(fp_line
			(start -0.12065 0.3048)
			(end -0.67945 0.3048)
			(stroke
				(width 0.1)
				(type default)
			)
			(layer "F.Fab")
		)
		(fp_line
			(start -0.67945 0.3048)
			(end -0.67945 -0.305054)
			(stroke
				(width 0.1)
				(type default)
			)
			(layer "F.Fab")
		)
		(pad "1" smd circle
			(at -0.40005 0 90)
			(size 0 0)
			(layers "F.Cu" "F.Mask" "F.Paste")
			(net "FAN_5_P3V_R")
		)
		(pad "2" smd circle
			(at 0.40005 0 90)
			(size 0 0)
			(layers "F.Cu" "F.Mask" "F.Paste")
			(net "FAN_5_MODE")
		)
	)
	(footprint ""
		(layer "F.Cu")
		(at 38.227 -185.166 180)
		(property "Reference" "C188"
			(at 0 0 180)
			(layer "F.SilkS")
			(hide yes)
			(effects
				(font
					(size 1.27 1.27)
				)
			)
		)
		(property "Value" ""
			(at 0 0 180)
			(layer "F.Fab")
			(effects
				(font
					(size 1.27 1.27)
				)
			)
		)
		(duplicate_pad_numbers_are_jumpers no)
		(fp_line
			(start 0.7874 0.4064)
			(end -0.7874 0.4064)
			(stroke
				(width 0.1524)
				(type default)
			)
			(layer "F.SilkS")
		)
		(fp_line
			(start 0.7874 -0.4064)
			(end 0.7874 0.4064)
			(stroke
				(width 0.1524)
				(type default)
			)
			(layer "F.SilkS")
		)
		(fp_line
			(start -0.7874 0.4064)
			(end -0.7874 -0.4064)
			(stroke
				(width 0.1524)
				(type default)
			)
			(layer "F.SilkS")
		)
		(fp_line
			(start -0.7874 -0.4064)
			(end 0.7874 -0.4064)
			(stroke
				(width 0.1524)
				(type default)
			)
			(layer "F.SilkS")
		)
		(fp_line
			(start 0.67945 0.3048)
			(end 0.120396 0.3048)
			(stroke
				(width 0.1)
				(type default)
			)
			(layer "F.Fab")
		)
		(fp_line
			(start 0.67945 -0.3048)
			(end 0.67945 0.3048)
			(stroke
				(width 0.1)
				(type default)
			)
			(layer "F.Fab")
		)
		(fp_line
			(start 0.12065 -0.2794)
			(end 0.12065 -0.3048)
			(stroke
				(width 0.1)
				(type default)
			)
			(layer "F.Fab")
		)
		(fp_line
			(start 0.12065 -0.3048)
			(end 0.67945 -0.3048)
			(stroke
				(width 0.1)
				(type default)
			)
			(layer "F.Fab")
		)
		(fp_line
			(start 0.120396 0.3048)
			(end 0.120396 0.2794)
			(stroke
				(width 0.1)
				(type default)
			)
			(layer "F.Fab")
		)
		(fp_line
			(start 0.120396 0.2794)
			(end -0.12065 0.2794)
			(stroke
				(width 0.1)
				(type default)
			)
			(layer "F.Fab")
		)
		(fp_line
			(start -0.12065 0.3048)
			(end -0.67945 0.3048)
			(stroke
				(width 0.1)
				(type default)
			)
			(layer "F.Fab")
		)
		(fp_line
			(start -0.12065 0.2794)
			(end -0.12065 0.3048)
			(stroke
				(width 0.1)
				(type default)
			)
			(layer "F.Fab")
		)
		(fp_line
			(start -0.12065 -0.2794)
			(end 0.12065 -0.2794)
			(stroke
				(width 0.1)
				(type default)
			)
			(layer "F.Fab")
		)
		(fp_line
			(start -0.12065 -0.305054)
			(end -0.12065 -0.2794)
			(stroke
				(width 0.1)
				(type default)
			)
			(layer "F.Fab")
		)
		(fp_line
			(start -0.67945 0.3048)
			(end -0.67945 -0.305054)
			(stroke
				(width 0.1)
				(type default)
			)
			(layer "F.Fab")
		)
		(fp_line
			(start -0.67945 -0.305054)
			(end -0.12065 -0.305054)
			(stroke
				(width 0.1)
				(type default)
			)
			(layer "F.Fab")
		)
		(pad "1" smd circle
			(at -0.40005 0 180)
			(size 0 0)
			(layers "F.Cu" "F.Mask" "F.Paste")
			(net "P3V3_AUX")
		)
		(pad "2" smd circle
			(at 0.40005 0 180)
			(size 0 0)
			(layers "F.Cu" "F.Mask" "F.Paste")
			(net "GND")
		)
	)
	(footprint ""
		(layer "F.Cu")
		(at 25.527 -135.001)
		(property "Reference" "R5682"
			(at 0 0 0)
			(layer "F.SilkS")
			(hide yes)
			(effects
				(font
					(size 1.27 1.27)
				)
			)
		)
		(property "Value" ""
			(at 0 0 0)
			(layer "F.Fab")
			(effects
				(font
					(size 1.27 1.27)
				)
			)
		)
		(duplicate_pad_numbers_are_jumpers no)
		(fp_line
			(start -0.7874 -0.4064)
			(end 0.7874 -0.4064)
			(stroke
				(width 0.1524)
				(type default)
			)
			(layer "F.SilkS")
		)
		(fp_line
			(start -0.7874 0.4064)
			(end -0.7874 -0.4064)
			(stroke
				(width 0.1524)
				(type default)
			)
			(layer "F.SilkS")
		)
		(fp_line
			(start 0.7874 -0.4064)
			(end 0.7874 0.4064)
			(stroke
				(width 0.1524)
				(type default)
			)
			(layer "F.SilkS")
		)
		(fp_line
			(start 0.7874 0.4064)
			(end -0.7874 0.4064)
			(stroke
				(width 0.1524)
				(type default)
			)
			(layer "F.SilkS")
		)
		(fp_line
			(start -0.67945 -0.305054)
			(end -0.12065 -0.305054)
			(stroke
				(width 0.1)
				(type default)
			)
			(layer "F.Fab")
		)
		(fp_line
			(start -0.67945 0.3048)
			(end -0.67945 -0.305054)
			(stroke
				(width 0.1)
				(type default)
			)
			(layer "F.Fab")
		)
		(fp_line
			(start -0.12065 -0.305054)
			(end -0.12065 -0.2794)
			(stroke
				(width 0.1)
				(type default)
			)
			(layer "F.Fab")
		)
		(fp_line
			(start -0.12065 -0.2794)
			(end 0.12065 -0.2794)
			(stroke
				(width 0.1)
				(type default)
			)
			(layer "F.Fab")
		)
		(fp_line
			(start -0.12065 0.2794)
			(end -0.12065 0.3048)
			(stroke
				(width 0.1)
				(type default)
			)
			(layer "F.Fab")
		)
		(fp_line
			(start -0.12065 0.3048)
			(end -0.67945 0.3048)
			(stroke
				(width 0.1)
				(type default)
			)
			(layer "F.Fab")
		)
		(fp_line
			(start 0.120396 0.2794)
			(end -0.12065 0.2794)
			(stroke
				(width 0.1)
				(type default)
			)
			(layer "F.Fab")
		)
		(fp_line
			(start 0.120396 0.3048)
			(end 0.120396 0.2794)
			(stroke
				(width 0.1)
				(type default)
			)
			(layer "F.Fab")
		)
		(fp_line
			(start 0.12065 -0.3048)
			(end 0.67945 -0.3048)
			(stroke
				(width 0.1)
				(type default)
			)
			(layer "F.Fab")
		)
		(fp_line
			(start 0.12065 -0.2794)
			(end 0.12065 -0.3048)
			(stroke
				(width 0.1)
				(type default)
			)
			(layer "F.Fab")
		)
		(fp_line
			(start 0.67945 -0.3048)
			(end 0.67945 0.3048)
			(stroke
				(width 0.1)
				(type default)
			)
			(layer "F.Fab")
		)
		(fp_line
			(start 0.67945 0.3048)
			(end 0.120396 0.3048)
			(stroke
				(width 0.1)
				(type default)
			)
			(layer "F.Fab")
		)
		(pad "1" smd circle
			(at -0.40005 0)
			(size 0 0)
			(layers "F.Cu" "F.Mask" "F.Paste")
			(net "P3V3_AUX")
		)
		(pad "2" smd circle
			(at 0.40005 0)
			(size 0 0)
			(layers "F.Cu" "F.Mask" "F.Paste")
			(net "U330_FAN FAIL_N")
		)
	)
	(footprint ""
		(layer "F.Cu")
		(at 22.225 -123.317 90)
		(property "Reference" "C1938"
			(at 0 0 90)
			(layer "F.SilkS")
			(hide yes)
			(effects
				(font
					(size 1.27 1.27)
				)
			)
		)
		(property "Value" ""
			(at 0 0 90)
			(layer "F.Fab")
			(effects
				(font
					(size 1.27 1.27)
				)
			)
		)
		(duplicate_pad_numbers_are_jumpers no)
		(fp_line
			(start 0.7874 -0.4064)
			(end 0.7874 0.4064)
			(stroke
				(width 0.1524)
				(type default)
			)
			(layer "F.SilkS")
		)
		(fp_line
			(start -0.7874 -0.4064)
			(end 0.7874 -0.4064)
			(stroke
				(width 0.1524)
				(type default)
			)
			(layer "F.SilkS")
		)
		(fp_line
			(start 0.7874 0.4064)
			(end -0.7874 0.4064)
			(stroke
				(width 0.1524)
				(type default)
			)
			(layer "F.SilkS")
		)
		(fp_line
			(start -0.7874 0.4064)
			(end -0.7874 -0.4064)
			(stroke
				(width 0.1524)
				(type default)
			)
			(layer "F.SilkS")
		)
		(fp_line
			(start -0.12065 -0.305054)
			(end -0.12065 -0.2794)
			(stroke
				(width 0.1)
				(type default)
			)
			(layer "F.Fab")
		)
		(fp_line
			(start -0.67945 -0.305054)
			(end -0.12065 -0.305054)
			(stroke
				(width 0.1)
				(type default)
			)
			(layer "F.Fab")
		)
		(fp_line
			(start 0.67945 -0.3048)
			(end 0.67945 0.3048)
			(stroke
				(width 0.1)
				(type default)
			)
			(layer "F.Fab")
		)
		(fp_line
			(start 0.12065 -0.3048)
			(end 0.67945 -0.3048)
			(stroke
				(width 0.1)
				(type default)
			)
			(layer "F.Fab")
		)
		(fp_line
			(start 0.12065 -0.2794)
			(end 0.12065 -0.3048)
			(stroke
				(width 0.1)
				(type default)
			)
			(layer "F.Fab")
		)
		(fp_line
			(start -0.12065 -0.2794)
			(end 0.12065 -0.2794)
			(stroke
				(width 0.1)
				(type default)
			)
			(layer "F.Fab")
		)
		(fp_line
			(start 0.120396 0.2794)
			(end -0.12065 0.2794)
			(stroke
				(width 0.1)
				(type default)
			)
			(layer "F.Fab")
		)
		(fp_line
			(start -0.12065 0.2794)
			(end -0.12065 0.3048)
			(stroke
				(width 0.1)
				(type default)
			)
			(layer "F.Fab")
		)
		(fp_line
			(start 0.67945 0.3048)
			(end 0.120396 0.3048)
			(stroke
				(width 0.1)
				(type default)
			)
			(layer "F.Fab")
		)
		(fp_line
			(start 0.120396 0.3048)
			(end 0.120396 0.2794)
			(stroke
				(width 0.1)
				(type default)
			)
			(layer "F.Fab")
		)
		(fp_line
			(start -0.12065 0.3048)
			(end -0.67945 0.3048)
			(stroke
				(width 0.1)
				(type default)
			)
			(layer "F.Fab")
		)
		(fp_line
			(start -0.67945 0.3048)
			(end -0.67945 -0.305054)
			(stroke
				(width 0.1)
				(type default)
			)
			(layer "F.Fab")
		)
		(pad "1" smd circle
			(at -0.40005 0 90)
			(size 0 0)
			(layers "F.Cu" "F.Mask" "F.Paste")
			(net "GND")
		)
		(pad "2" smd circle
			(at 0.40005 0 90)
			(size 0 0)
			(layers "F.Cu" "F.Mask" "F.Paste")
			(net "P3V3_AUX")
		)
	)
	(footprint ""
		(layer "F.Cu")
		(at 32.004 -108.966)
		(property "Reference" "R5530"
			(at 0 0 0)
			(layer "F.SilkS")
			(hide yes)
			(effects
				(font
					(size 1.27 1.27)
				)
			)
		)
		(property "Value" ""
			(at 0 0 0)
			(layer "F.Fab")
			(effects
				(font
					(size 1.27 1.27)
				)
			)
		)
		(duplicate_pad_numbers_are_jumpers no)
		(fp_line
			(start -0.7874 -0.4064)
			(end 0.7874 -0.4064)
			(stroke
				(width 0.1524)
				(type default)
			)
			(layer "F.SilkS")
		)
		(fp_line
			(start -0.7874 0.4064)
			(end -0.7874 -0.4064)
			(stroke
				(width 0.1524)
				(type default)
			)
			(layer "F.SilkS")
		)
		(fp_line
			(start 0.7874 -0.4064)
			(end 0.7874 0.4064)
			(stroke
				(width 0.1524)
				(type default)
			)
			(layer "F.SilkS")
		)
		(fp_line
			(start 0.7874 0.4064)
			(end -0.7874 0.4064)
			(stroke
				(width 0.1524)
				(type default)
			)
			(layer "F.SilkS")
		)
		(fp_line
			(start -0.67945 -0.305054)
			(end -0.12065 -0.305054)
			(stroke
				(width 0.1)
				(type default)
			)
			(layer "F.Fab")
		)
		(fp_line
			(start -0.67945 0.3048)
			(end -0.67945 -0.305054)
			(stroke
				(width 0.1)
				(type default)
			)
			(layer "F.Fab")
		)
		(fp_line
			(start -0.12065 -0.305054)
			(end -0.12065 -0.2794)
			(stroke
				(width 0.1)
				(type default)
			)
			(layer "F.Fab")
		)
		(fp_line
			(start -0.12065 -0.2794)
			(end 0.12065 -0.2794)
			(stroke
				(width 0.1)
				(type default)
			)
			(layer "F.Fab")
		)
		(fp_line
			(start -0.12065 0.2794)
			(end -0.12065 0.3048)
			(stroke
				(width 0.1)
				(type default)
			)
			(layer "F.Fab")
		)
		(fp_line
			(start -0.12065 0.3048)
			(end -0.67945 0.3048)
			(stroke
				(width 0.1)
				(type default)
			)
			(layer "F.Fab")
		)
		(fp_line
			(start 0.120396 0.2794)
			(end -0.12065 0.2794)
			(stroke
				(width 0.1)
				(type default)
			)
			(layer "F.Fab")
		)
		(fp_line
			(start 0.120396 0.3048)
			(end 0.120396 0.2794)
			(stroke
				(width 0.1)
				(type default)
			)
			(layer "F.Fab")
		)
		(fp_line
			(start 0.12065 -0.3048)
			(end 0.67945 -0.3048)
			(stroke
				(width 0.1)
				(type default)
			)
			(layer "F.Fab")
		)
		(fp_line
			(start 0.12065 -0.2794)
			(end 0.12065 -0.3048)
			(stroke
				(width 0.1)
				(type default)
			)
			(layer "F.Fab")
		)
		(fp_line
			(start 0.67945 -0.3048)
			(end 0.67945 0.3048)
			(stroke
				(width 0.1)
				(type default)
			)
			(layer "F.Fab")
		)
		(fp_line
			(start 0.67945 0.3048)
			(end 0.120396 0.3048)
			(stroke
				(width 0.1)
				(type default)
			)
			(layer "F.Fab")
		)
		(pad "1" smd rect
			(at -0.40005 0 180)
			(size 0.4572 0.508)
			(layers "F.Cu" "F.Mask" "F.Paste")
			(net "P12V_LED_FAN2")
		)
		(pad "2" smd rect
			(at 0.40005 0 180)
			(size 0.4572 0.508)
			(layers "F.Cu" "F.Mask" "F.Paste")
			(net "FAN_2_FAIL_LED_R_N")
		)
	)
	(footprint ""
		(layer "F.Cu")
		(at 15.377922 -117.825012 180)
		(property "Reference" "D136"
			(at 5.471922 2.036318 0)
			(unlocked yes)
			(layer "F.SilkS")
			(effects
				(font
					(size 0.7874 0.5842)
					(thickness 0.1524)
				)
				(justify left)
			)
		)
		(property "Value" ""
			(at 0 0 180)
			(layer "F.Fab")
			(effects
				(font
					(size 1.27 1.27)
				)
			)
		)
		(duplicate_pad_numbers_are_jumpers no)
		(fp_line
			(start 2.032 0.7112)
			(end -1.651 0.7112)
			(stroke
				(width 0.1524)
				(type default)
			)
			(layer "F.SilkS")
		)
		(fp_line
			(start 2.032 -0.7112)
			(end 2.032 0.7112)
			(stroke
				(width 0.1524)
				(type default)
			)
			(layer "F.SilkS")
		)
		(fp_line
			(start 1.905 -0.6858)
			(end 1.905 0.6858)
			(stroke
				(width 0.1524)
				(type default)
			)
			(layer "F.SilkS")
		)
		(fp_line
			(start 1.778 0.6858)
			(end 1.778 -0.6858)
			(stroke
				(width 0.1524)
				(type default)
			)
			(layer "F.SilkS")
		)
		(fp_line
			(start 1.651 -0.6858)
			(end 1.651 0.6858)
			(stroke
				(width 0.1524)
				(type default)
			)
			(layer "F.SilkS")
		)
		(fp_line
			(start 0.299974 -0.500126)
			(end 0.299974 0.500126)
			(stroke
				(width 0.1524)
				(type default)
			)
			(layer "F.SilkS")
		)
		(fp_line
			(start 0.199898 0)
			(end -0.299974 -0.500126)
			(stroke
				(width 0.1524)
				(type default)
			)
			(layer "F.SilkS")
		)
		(fp_line
			(start -0.299974 0.500126)
			(end 0.199898 0)
			(stroke
				(width 0.1524)
				(type default)
			)
			(layer "F.SilkS")
		)
		(fp_line
			(start -0.299974 -0.500126)
			(end -0.299974 0.500126)
			(stroke
				(width 0.1524)
				(type default)
			)
			(layer "F.SilkS")
		)
		(fp_line
			(start -1.651 0.7112)
			(end -1.651 -0.7112)
			(stroke
				(width 0.1524)
				(type default)
			)
			(layer "F.SilkS")
		)
		(fp_line
			(start -1.651 -0.7112)
			(end 2.032 -0.7112)
			(stroke
				(width 0.1524)
				(type default)
			)
			(layer "F.SilkS")
		)
		(fp_line
			(start 1.35001 0.175006)
			(end 0.899922 0.175006)
			(stroke
				(width 0.1)
				(type default)
			)
			(layer "F.Fab")
		)
		(fp_line
			(start 1.35001 -0.225044)
			(end 1.35001 0.175006)
			(stroke
				(width 0.1)
				(type default)
			)
			(layer "F.Fab")
		)
		(fp_line
			(start 0.899922 0.700024)
			(end -0.899922 0.700024)
			(stroke
				(width 0.1)
				(type default)
			)
			(layer "F.Fab")
		)
		(fp_line
			(start 0.899922 0.175006)
			(end 0.899922 0.700024)
			(stroke
				(width 0.1)
				(type default)
			)
			(layer "F.Fab")
		)
		(fp_line
			(start 0.899922 -0.225044)
			(end 1.35001 -0.225044)
			(stroke
				(width 0.1)
				(type default)
			)
			(layer "F.Fab")
		)
		(fp_line
			(start 0.899922 -0.700024)
			(end 0.899922 -0.225044)
			(stroke
				(width 0.1)
				(type default)
			)
			(layer "F.Fab")
		)
		(fp_line
			(start 0.299974 -0.500126)
			(end 0.299974 0.500126)
			(stroke
				(width 0.1)
				(type default)
			)
			(layer "F.Fab")
		)
		(fp_line
			(start 0.199898 0)
			(end -0.299974 -0.500126)
			(stroke
				(width 0.1)
				(type default)
			)
			(layer "F.Fab")
		)
		(fp_line
			(start -0.299974 0.500126)
			(end 0.199898 0)
			(stroke
				(width 0.1)
				(type default)
			)
			(layer "F.Fab")
		)
		(fp_line
			(start -0.299974 -0.500126)
			(end -0.299974 0.500126)
			(stroke
				(width 0.1)
				(type default)
			)
			(layer "F.Fab")
		)
		(fp_line
			(start -0.899922 0.700024)
			(end -0.899922 0.175006)
			(stroke
				(width 0.1)
				(type default)
			)
			(layer "F.Fab")
		)
		(fp_line
			(start -0.899922 0.175006)
			(end -1.35001 0.175006)
			(stroke
				(width 0.1)
				(type default)
			)
			(layer "F.Fab")
		)
		(fp_line
			(start -0.899922 -0.225044)
			(end -0.899922 -0.700024)
			(stroke
				(width 0.1)
				(type default)
			)
			(layer "F.Fab")
		)
		(fp_line
			(start -0.899922 -0.700024)
			(end 0.899922 -0.700024)
			(stroke
				(width 0.1)
				(type default)
			)
			(layer "F.Fab")
		)
		(fp_line
			(start -1.35001 0.175006)
			(end -1.35001 -0.225044)
			(stroke
				(width 0.1)
				(type default)
			)
			(layer "F.Fab")
		)
		(fp_line
			(start -1.35001 -0.225044)
			(end -0.899922 -0.225044)
			(stroke
				(width 0.1)
				(type default)
			)
			(layer "F.Fab")
		)
		(fp_text user "-"
			(at 1.026922 0.824738 180)
			(unlocked yes)
			(layer "F.SilkS")
			(effects
				(font
					(size 1.905 1.4224)
					(thickness 0.1524)
				)
				(justify left)
			)
		)
		(fp_text user "+"
			(at -2.148078 1.205738 180)
			(unlocked yes)
			(layer "F.SilkS")
			(effects
				(font
					(size 1.905 1.4224)
					(thickness 0.1524)
				)
				(justify left)
			)
		)
		(fp_text user "-"
			(at 1.8288 -0.24765 180)
			(unlocked yes)
			(layer "F.Fab")
			(effects
				(font
					(size 1.905 1.4224)
					(thickness 0.1524)
				)
				(justify left)
			)
		)
		(fp_text user "+"
			(at -2.794 -0.19685 180)
			(unlocked yes)
			(layer "F.Fab")
			(effects
				(font
					(size 1.905 1.4224)
					(thickness 0.1524)
				)
				(justify left)
			)
		)
		(pad "1" smd rect
			(at -1.0922 0)
			(size 0.8128 0.8636)
			(layers "F.Cu" "F.Mask" "F.Paste")
			(net "FAN_5_TACH_OL_R")
		)
		(pad "2" smd rect
			(at 1.0922 0 180)
			(size 0.8128 0.8636)
			(layers "F.Cu" "F.Mask" "F.Paste")
			(net "FAN_5_TACH_OL_D")
		)
	)
	(footprint ""
		(layer "F.Cu")
		(at 17.272 -160.02 -90)
		(property "Reference" "R5462"
			(at 0 0 270)
			(layer "F.SilkS")
			(hide yes)
			(effects
				(font
					(size 1.27 1.27)
				)
			)
		)
		(property "Value" ""
			(at 0 0 270)
			(layer "F.Fab")
			(effects
				(font
					(size 1.27 1.27)
				)
			)
		)
		(duplicate_pad_numbers_are_jumpers no)
		(fp_line
			(start -0.7874 0.4064)
			(end -0.7874 -0.4064)
			(stroke
				(width 0.1524)
				(type default)
			)
			(layer "F.SilkS")
		)
		(fp_line
			(start 0.7874 0.4064)
			(end -0.7874 0.4064)
			(stroke
				(width 0.1524)
				(type default)
			)
			(layer "F.SilkS")
		)
		(fp_line
			(start -0.7874 -0.4064)
			(end 0.7874 -0.4064)
			(stroke
				(width 0.1524)
				(type default)
			)
			(layer "F.SilkS")
		)
		(fp_line
			(start 0.7874 -0.4064)
			(end 0.7874 0.4064)
			(stroke
				(width 0.1524)
				(type default)
			)
			(layer "F.SilkS")
		)
		(fp_line
			(start -0.67945 0.3048)
			(end -0.67945 -0.305054)
			(stroke
				(width 0.1)
				(type default)
			)
			(layer "F.Fab")
		)
		(fp_line
			(start -0.12065 0.3048)
			(end -0.67945 0.3048)
			(stroke
				(width 0.1)
				(type default)
			)
			(layer "F.Fab")
		)
		(fp_line
			(start 0.120396 0.3048)
			(end 0.120396 0.2794)
			(stroke
				(width 0.1)
				(type default)
			)
			(layer "F.Fab")
		)
		(fp_line
			(start 0.67945 0.3048)
			(end 0.120396 0.3048)
			(stroke
				(width 0.1)
				(type default)
			)
			(layer "F.Fab")
		)
		(fp_line
			(start -0.12065 0.2794)
			(end -0.12065 0.3048)
			(stroke
				(width 0.1)
				(type default)
			)
			(layer "F.Fab")
		)
		(fp_line
			(start 0.120396 0.2794)
			(end -0.12065 0.2794)
			(stroke
				(width 0.1)
				(type default)
			)
			(layer "F.Fab")
		)
		(fp_line
			(start -0.12065 -0.2794)
			(end 0.12065 -0.2794)
			(stroke
				(width 0.1)
				(type default)
			)
			(layer "F.Fab")
		)
		(fp_line
			(start 0.12065 -0.2794)
			(end 0.12065 -0.3048)
			(stroke
				(width 0.1)
				(type default)
			)
			(layer "F.Fab")
		)
		(fp_line
			(start 0.12065 -0.3048)
			(end 0.67945 -0.3048)
			(stroke
				(width 0.1)
				(type default)
			)
			(layer "F.Fab")
		)
		(fp_line
			(start 0.67945 -0.3048)
			(end 0.67945 0.3048)
			(stroke
				(width 0.1)
				(type default)
			)
			(layer "F.Fab")
		)
		(fp_line
			(start -0.67945 -0.305054)
			(end -0.12065 -0.305054)
			(stroke
				(width 0.1)
				(type default)
			)
			(layer "F.Fab")
		)
		(fp_line
			(start -0.12065 -0.305054)
			(end -0.12065 -0.2794)
			(stroke
				(width 0.1)
				(type default)
			)
			(layer "F.Fab")
		)
		(pad "1" smd circle
			(at -0.40005 0 270)
			(size 0 0)
			(layers "F.Cu" "F.Mask" "F.Paste")
			(net "SMB_PDBV_FAN_SDA")
		)
		(pad "2" smd circle
			(at 0.40005 0 270)
			(size 0 0)
			(layers "F.Cu" "F.Mask" "F.Paste")
			(net "SMB_PDBV_FAN_R_U321_SDA")
		)
	)
	(footprint ""
		(layer "F.Cu")
		(at 33.147 -211.963)
		(property "Reference" "D273"
			(at -1.27 -1.595374 0)
			(unlocked yes)
			(layer "F.SilkS")
			(effects
				(font
					(size 0.7874 0.5842)
					(thickness 0.1524)
				)
				(justify left)
			)
		)
		(property "Value" ""
			(at 0 0 0)
			(layer "F.Fab")
			(effects
				(font
					(size 1.27 1.27)
				)
			)
		)
		(duplicate_pad_numbers_are_jumpers no)
		(fp_line
			(start -0.854964 -0.450088)
			(end -0.854964 0.450088)
			(stroke
				(width 0.1524)
				(type default)
			)
			(layer "F.SilkS")
		)
		(fp_line
			(start -0.854964 0.450088)
			(end 0.925068 0.450088)
			(stroke
				(width 0.1524)
				(type default)
			)
			(layer "F.SilkS")
		)
		(fp_line
			(start 0.845058 0.4064)
			(end 0.845058 -0.381)
			(stroke
				(width 0.1524)
				(type default)
			)
			(layer "F.SilkS")
		)
		(fp_line
			(start 0.870458 -0.2794)
			(end 0.845058 0.4064)
			(stroke
				(width 0.1524)
				(type default)
			)
			(layer "F.SilkS")
		)
		(fp_line
			(start 0.94488 -0.450088)
			(end -0.854964 -0.450088)
			(stroke
				(width 0.1524)
				(type default)
			)
			(layer "F.SilkS")
		)
		(fp_line
			(start 0.94488 0.450088)
			(end 0.94488 -0.450088)
			(stroke
				(width 0.1524)
				(type default)
			)
			(layer "F.SilkS")
		)
		(fp_line
			(start -0.54991 -0.350012)
			(end -0.54991 0.350012)
			(stroke
				(width 0.1)
				(type default)
			)
			(layer "F.Fab")
		)
		(fp_line
			(start -0.54991 0.350012)
			(end 0.54991 0.350012)
			(stroke
				(width 0.1)
				(type default)
			)
			(layer "F.Fab")
		)
		(fp_line
			(start 0.54991 -0.350012)
			(end -0.54991 -0.350012)
			(stroke
				(width 0.1)
				(type default)
			)
			(layer "F.Fab")
		)
		(fp_line
			(start 0.54991 0.350012)
			(end 0.54991 -0.350012)
			(stroke
				(width 0.1)
				(type default)
			)
			(layer "F.Fab")
		)
		(fp_text user "+"
			(at -0.635 0.251206 180)
			(unlocked yes)
			(layer "F.SilkS")
			(effects
				(font
					(size 1.905 1.4224)
					(thickness 0.1524)
				)
				(justify left)
			)
		)
		(fp_text user "-"
			(at 1.27 -0.637794 180)
			(unlocked yes)
			(layer "F.SilkS")
			(effects
				(font
					(size 1.905 1.4224)
					(thickness 0.1524)
				)
				(justify left)
			)
		)
		(fp_text user "+"
			(at -0.808228 0.239014 180)
			(unlocked yes)
			(layer "F.Fab")
			(effects
				(font
					(size 1.905 1.4224)
					(thickness 0.1524)
				)
				(justify left)
			)
		)
		(fp_text user "-"
			(at 2.48539 0.239014 180)
			(unlocked yes)
			(layer "F.Fab")
			(effects
				(font
					(size 1.905 1.4224)
					(thickness 0.1524)
				)
				(justify left)
			)
		)
		(pad "A" smd rect
			(at -0.424942 0)
			(size 0.5588 0.6096)
			(layers "F.Cu" "F.Mask" "F.Paste")
			(net "GND")
		)
		(pad "C" smd rect
			(at 0.424942 0 180)
			(size 0.5588 0.6096)
			(layers "F.Cu" "F.Mask" "F.Paste")
			(net "FAN_1_PWM_OL_R")
		)
	)
	(footprint ""
		(layer "F.Cu")
		(at 37.338 -300.609)
		(property "Reference" "D266"
			(at 1.651 -0.73533 0)
			(unlocked yes)
			(layer "F.SilkS")
			(effects
				(font
					(size 0.7874 0.5842)
					(thickness 0.1524)
				)
				(justify left)
			)
		)
		(property "Value" ""
			(at 0 0 0)
			(layer "F.Fab")
			(effects
				(font
					(size 1.27 1.27)
				)
			)
		)
		(duplicate_pad_numbers_are_jumpers no)
		(fp_line
			(start -0.854964 -0.450088)
			(end -0.854964 0.450088)
			(stroke
				(width 0.1524)
				(type default)
			)
			(layer "F.SilkS")
		)
		(fp_line
			(start -0.854964 0.450088)
			(end 0.925068 0.450088)
			(stroke
				(width 0.1524)
				(type default)
			)
			(layer "F.SilkS")
		)
		(fp_line
			(start 0.845058 0.4064)
			(end 0.845058 -0.381)
			(stroke
				(width 0.1524)
				(type default)
			)
			(layer "F.SilkS")
		)
		(fp_line
			(start 0.870458 -0.2794)
			(end 0.845058 0.4064)
			(stroke
				(width 0.1524)
				(type default)
			)
			(layer "F.SilkS")
		)
		(fp_line
			(start 0.94488 -0.450088)
			(end -0.854964 -0.450088)
			(stroke
				(width 0.1524)
				(type default)
			)
			(layer "F.SilkS")
		)
		(fp_line
			(start 0.94488 0.450088)
			(end 0.94488 -0.450088)
			(stroke
				(width 0.1524)
				(type default)
			)
			(layer "F.SilkS")
		)
		(fp_line
			(start -0.54991 -0.350012)
			(end -0.54991 0.350012)
			(stroke
				(width 0.1)
				(type default)
			)
			(layer "F.Fab")
		)
		(fp_line
			(start -0.54991 0.350012)
			(end 0.54991 0.350012)
			(stroke
				(width 0.1)
				(type default)
			)
			(layer "F.Fab")
		)
		(fp_line
			(start 0.54991 -0.350012)
			(end -0.54991 -0.350012)
			(stroke
				(width 0.1)
				(type default)
			)
			(layer "F.Fab")
		)
		(fp_line
			(start 0.54991 0.350012)
			(end 0.54991 -0.350012)
			(stroke
				(width 0.1)
				(type default)
			)
			(layer "F.Fab")
		)
		(fp_text user "+"
			(at -0.381 0.88265 180)
			(unlocked yes)
			(layer "F.SilkS")
			(effects
				(font
					(size 1.905 1.4224)
					(thickness 0.1524)
				)
				(justify left)
			)
		)
		(fp_text user "-"
			(at 2.159 0.22225 180)
			(unlocked yes)
			(layer "F.SilkS")
			(effects
				(font
					(size 1.905 1.4224)
					(thickness 0.1524)
				)
				(justify left)
			)
		)
		(fp_text user "+"
			(at -0.808228 0.239014 180)
			(unlocked yes)
			(layer "F.Fab")
			(effects
				(font
					(size 1.905 1.4224)
					(thickness 0.1524)
				)
				(justify left)
			)
		)
		(fp_text user "-"
			(at 2.48539 0.239014 180)
			(unlocked yes)
			(layer "F.Fab")
			(effects
				(font
					(size 1.905 1.4224)
					(thickness 0.1524)
				)
				(justify left)
			)
		)
		(pad "A" smd rect
			(at -0.424942 0)
			(size 0.5588 0.6096)
			(layers "F.Cu" "F.Mask" "F.Paste")
			(net "GND")
		)
		(pad "C" smd rect
			(at 0.424942 0 180)
			(size 0.5588 0.6096)
			(layers "F.Cu" "F.Mask" "F.Paste")
			(net "FAN_0_TACH_IL_D")
		)
	)
	(footprint ""
		(layer "F.Cu")
		(at 14.351 -292.608 180)
		(property "Reference" "R5243"
			(at 0 0 180)
			(layer "F.SilkS")
			(hide yes)
			(effects
				(font
					(size 1.27 1.27)
				)
			)
		)
		(property "Value" ""
			(at 0 0 180)
			(layer "F.Fab")
			(effects
				(font
					(size 1.27 1.27)
				)
			)
		)
		(duplicate_pad_numbers_are_jumpers no)
		(fp_line
			(start 0.7874 0.4064)
			(end -0.7874 0.4064)
			(stroke
				(width 0.1524)
				(type default)
			)
			(layer "F.SilkS")
		)
		(fp_line
			(start 0.7874 -0.4064)
			(end 0.7874 0.4064)
			(stroke
				(width 0.1524)
				(type default)
			)
			(layer "F.SilkS")
		)
		(fp_line
			(start -0.7874 0.4064)
			(end -0.7874 -0.4064)
			(stroke
				(width 0.1524)
				(type default)
			)
			(layer "F.SilkS")
		)
		(fp_line
			(start -0.7874 -0.4064)
			(end 0.7874 -0.4064)
			(stroke
				(width 0.1524)
				(type default)
			)
			(layer "F.SilkS")
		)
		(fp_line
			(start 0.67945 0.3048)
			(end 0.120396 0.3048)
			(stroke
				(width 0.1)
				(type default)
			)
			(layer "F.Fab")
		)
		(fp_line
			(start 0.67945 -0.3048)
			(end 0.67945 0.3048)
			(stroke
				(width 0.1)
				(type default)
			)
			(layer "F.Fab")
		)
		(fp_line
			(start 0.12065 -0.2794)
			(end 0.12065 -0.3048)
			(stroke
				(width 0.1)
				(type default)
			)
			(layer "F.Fab")
		)
		(fp_line
			(start 0.12065 -0.3048)
			(end 0.67945 -0.3048)
			(stroke
				(width 0.1)
				(type default)
			)
			(layer "F.Fab")
		)
		(fp_line
			(start 0.120396 0.3048)
			(end 0.120396 0.2794)
			(stroke
				(width 0.1)
				(type default)
			)
			(layer "F.Fab")
		)
		(fp_line
			(start 0.120396 0.2794)
			(end -0.12065 0.2794)
			(stroke
				(width 0.1)
				(type default)
			)
			(layer "F.Fab")
		)
		(fp_line
			(start -0.12065 0.3048)
			(end -0.67945 0.3048)
			(stroke
				(width 0.1)
				(type default)
			)
			(layer "F.Fab")
		)
		(fp_line
			(start -0.12065 0.2794)
			(end -0.12065 0.3048)
			(stroke
				(width 0.1)
				(type default)
			)
			(layer "F.Fab")
		)
		(fp_line
			(start -0.12065 -0.2794)
			(end 0.12065 -0.2794)
			(stroke
				(width 0.1)
				(type default)
			)
			(layer "F.Fab")
		)
		(fp_line
			(start -0.12065 -0.305054)
			(end -0.12065 -0.2794)
			(stroke
				(width 0.1)
				(type default)
			)
			(layer "F.Fab")
		)
		(fp_line
			(start -0.67945 0.3048)
			(end -0.67945 -0.305054)
			(stroke
				(width 0.1)
				(type default)
			)
			(layer "F.Fab")
		)
		(fp_line
			(start -0.67945 -0.305054)
			(end -0.12065 -0.305054)
			(stroke
				(width 0.1)
				(type default)
			)
			(layer "F.Fab")
		)
		(pad "1" smd circle
			(at -0.40005 0 180)
			(size 0 0)
			(layers "F.Cu" "F.Mask" "F.Paste")
			(net "SMB_FAN7_SCL")
		)
		(pad "2" smd circle
			(at 0.40005 0 180)
			(size 0 0)
			(layers "F.Cu" "F.Mask" "F.Paste")
			(net "SMB_FAN7_SCL_R")
		)
	)
	(footprint ""
		(layer "F.Cu")
		(at 37.338 -26.248868)
		(property "Reference" "R5242"
			(at 0 0 0)
			(layer "F.SilkS")
			(hide yes)
			(effects
				(font
					(size 1.27 1.27)
				)
			)
		)
		(property "Value" ""
			(at 0 0 0)
			(layer "F.Fab")
			(effects
				(font
					(size 1.27 1.27)
				)
			)
		)
		(duplicate_pad_numbers_are_jumpers no)
		(fp_line
			(start -0.7874 -0.4064)
			(end 0.7874 -0.4064)
			(stroke
				(width 0.1524)
				(type default)
			)
			(layer "F.SilkS")
		)
		(fp_line
			(start -0.7874 0.4064)
			(end -0.7874 -0.4064)
			(stroke
				(width 0.1524)
				(type default)
			)
			(layer "F.SilkS")
		)
		(fp_line
			(start 0.7874 -0.4064)
			(end 0.7874 0.4064)
			(stroke
				(width 0.1524)
				(type default)
			)
			(layer "F.SilkS")
		)
		(fp_line
			(start 0.7874 0.4064)
			(end -0.7874 0.4064)
			(stroke
				(width 0.1524)
				(type default)
			)
			(layer "F.SilkS")
		)
		(fp_line
			(start -0.67945 -0.305054)
			(end -0.12065 -0.305054)
			(stroke
				(width 0.1)
				(type default)
			)
			(layer "F.Fab")
		)
		(fp_line
			(start -0.67945 0.3048)
			(end -0.67945 -0.305054)
			(stroke
				(width 0.1)
				(type default)
			)
			(layer "F.Fab")
		)
		(fp_line
			(start -0.12065 -0.305054)
			(end -0.12065 -0.2794)
			(stroke
				(width 0.1)
				(type default)
			)
			(layer "F.Fab")
		)
		(fp_line
			(start -0.12065 -0.2794)
			(end 0.12065 -0.2794)
			(stroke
				(width 0.1)
				(type default)
			)
			(layer "F.Fab")
		)
		(fp_line
			(start -0.12065 0.2794)
			(end -0.12065 0.3048)
			(stroke
				(width 0.1)
				(type default)
			)
			(layer "F.Fab")
		)
		(fp_line
			(start -0.12065 0.3048)
			(end -0.67945 0.3048)
			(stroke
				(width 0.1)
				(type default)
			)
			(layer "F.Fab")
		)
		(fp_line
			(start 0.120396 0.2794)
			(end -0.12065 0.2794)
			(stroke
				(width 0.1)
				(type default)
			)
			(layer "F.Fab")
		)
		(fp_line
			(start 0.120396 0.3048)
			(end 0.120396 0.2794)
			(stroke
				(width 0.1)
				(type default)
			)
			(layer "F.Fab")
		)
		(fp_line
			(start 0.12065 -0.3048)
			(end 0.67945 -0.3048)
			(stroke
				(width 0.1)
				(type default)
			)
			(layer "F.Fab")
		)
		(fp_line
			(start 0.12065 -0.2794)
			(end 0.12065 -0.3048)
			(stroke
				(width 0.1)
				(type default)
			)
			(layer "F.Fab")
		)
		(fp_line
			(start 0.67945 -0.3048)
			(end 0.67945 0.3048)
			(stroke
				(width 0.1)
				(type default)
			)
			(layer "F.Fab")
		)
		(fp_line
			(start 0.67945 0.3048)
			(end 0.120396 0.3048)
			(stroke
				(width 0.1)
				(type default)
			)
			(layer "F.Fab")
		)
		(pad "1" smd circle
			(at -0.40005 0)
			(size 0 0)
			(layers "F.Cu" "F.Mask" "F.Paste")
			(net "SMB_FAN3_SCL")
		)
		(pad "2" smd circle
			(at 0.40005 0)
			(size 0 0)
			(layers "F.Cu" "F.Mask" "F.Paste")
			(net "SMB_FAN3_SCL_R")
		)
	)
	(footprint ""
		(layer "F.Cu")
		(at 26.035 -13.8938 -90)
		(property "Reference" "R4969"
			(at 0 0 270)
			(layer "F.SilkS")
			(hide yes)
			(effects
				(font
					(size 1.27 1.27)
				)
			)
		)
		(property "Value" ""
			(at 0 0 270)
			(layer "F.Fab")
			(effects
				(font
					(size 1.27 1.27)
				)
			)
		)
		(duplicate_pad_numbers_are_jumpers no)
		(fp_line
			(start -0.7874 0.4064)
			(end -0.7874 -0.4064)
			(stroke
				(width 0.1524)
				(type default)
			)
			(layer "F.SilkS")
		)
		(fp_line
			(start 0.7874 0.4064)
			(end -0.7874 0.4064)
			(stroke
				(width 0.1524)
				(type default)
			)
			(layer "F.SilkS")
		)
		(fp_line
			(start -0.7874 -0.4064)
			(end 0.7874 -0.4064)
			(stroke
				(width 0.1524)
				(type default)
			)
			(layer "F.SilkS")
		)
		(fp_line
			(start 0.7874 -0.4064)
			(end 0.7874 0.4064)
			(stroke
				(width 0.1524)
				(type default)
			)
			(layer "F.SilkS")
		)
		(fp_line
			(start -0.67945 0.3048)
			(end -0.67945 -0.305054)
			(stroke
				(width 0.1)
				(type default)
			)
			(layer "F.Fab")
		)
		(fp_line
			(start -0.12065 0.3048)
			(end -0.67945 0.3048)
			(stroke
				(width 0.1)
				(type default)
			)
			(layer "F.Fab")
		)
		(fp_line
			(start 0.120396 0.3048)
			(end 0.120396 0.2794)
			(stroke
				(width 0.1)
				(type default)
			)
			(layer "F.Fab")
		)
		(fp_line
			(start 0.67945 0.3048)
			(end 0.120396 0.3048)
			(stroke
				(width 0.1)
				(type default)
			)
			(layer "F.Fab")
		)
		(fp_line
			(start -0.12065 0.2794)
			(end -0.12065 0.3048)
			(stroke
				(width 0.1)
				(type default)
			)
			(layer "F.Fab")
		)
		(fp_line
			(start 0.120396 0.2794)
			(end -0.12065 0.2794)
			(stroke
				(width 0.1)
				(type default)
			)
			(layer "F.Fab")
		)
		(fp_line
			(start -0.12065 -0.2794)
			(end 0.12065 -0.2794)
			(stroke
				(width 0.1)
				(type default)
			)
			(layer "F.Fab")
		)
		(fp_line
			(start 0.12065 -0.2794)
			(end 0.12065 -0.3048)
			(stroke
				(width 0.1)
				(type default)
			)
			(layer "F.Fab")
		)
		(fp_line
			(start 0.12065 -0.3048)
			(end 0.67945 -0.3048)
			(stroke
				(width 0.1)
				(type default)
			)
			(layer "F.Fab")
		)
		(fp_line
			(start 0.67945 -0.3048)
			(end 0.67945 0.3048)
			(stroke
				(width 0.1)
				(type default)
			)
			(layer "F.Fab")
		)
		(fp_line
			(start -0.67945 -0.305054)
			(end -0.12065 -0.305054)
			(stroke
				(width 0.1)
				(type default)
			)
			(layer "F.Fab")
		)
		(fp_line
			(start -0.12065 -0.305054)
			(end -0.12065 -0.2794)
			(stroke
				(width 0.1)
				(type default)
			)
			(layer "F.Fab")
		)
		(pad "1" smd circle
			(at -0.40005 0 270)
			(size 0 0)
			(layers "F.Cu" "F.Mask" "F.Paste")
			(net "SMB_PDBV_FAN_SDA")
		)
		(pad "2" smd circle
			(at 0.40005 0 270)
			(size 0 0)
			(layers "F.Cu" "F.Mask" "F.Paste")
			(net "SMB_PDBV_FAN_R_SDA")
		)
	)
	(footprint ""
		(layer "F.Cu")
		(at 48.26 -135.128 180)
		(property "Reference" "R5557"
			(at 0 0 180)
			(layer "F.SilkS")
			(hide yes)
			(effects
				(font
					(size 1.27 1.27)
				)
			)
		)
		(property "Value" ""
			(at 0 0 180)
			(layer "F.Fab")
			(effects
				(font
					(size 1.27 1.27)
				)
			)
		)
		(duplicate_pad_numbers_are_jumpers no)
		(fp_line
			(start 0.7874 0.4064)
			(end -0.7874 0.4064)
			(stroke
				(width 0.1524)
				(type default)
			)
			(layer "F.SilkS")
		)
		(fp_line
			(start 0.7874 -0.4064)
			(end 0.7874 0.4064)
			(stroke
				(width 0.1524)
				(type default)
			)
			(layer "F.SilkS")
		)
		(fp_line
			(start -0.7874 0.4064)
			(end -0.7874 -0.4064)
			(stroke
				(width 0.1524)
				(type default)
			)
			(layer "F.SilkS")
		)
		(fp_line
			(start -0.7874 -0.4064)
			(end 0.7874 -0.4064)
			(stroke
				(width 0.1524)
				(type default)
			)
			(layer "F.SilkS")
		)
		(fp_line
			(start 0.67945 0.3048)
			(end 0.120396 0.3048)
			(stroke
				(width 0.1)
				(type default)
			)
			(layer "F.Fab")
		)
		(fp_line
			(start 0.67945 -0.3048)
			(end 0.67945 0.3048)
			(stroke
				(width 0.1)
				(type default)
			)
			(layer "F.Fab")
		)
		(fp_line
			(start 0.12065 -0.2794)
			(end 0.12065 -0.3048)
			(stroke
				(width 0.1)
				(type default)
			)
			(layer "F.Fab")
		)
		(fp_line
			(start 0.12065 -0.3048)
			(end 0.67945 -0.3048)
			(stroke
				(width 0.1)
				(type default)
			)
			(layer "F.Fab")
		)
		(fp_line
			(start 0.120396 0.3048)
			(end 0.120396 0.2794)
			(stroke
				(width 0.1)
				(type default)
			)
			(layer "F.Fab")
		)
		(fp_line
			(start 0.120396 0.2794)
			(end -0.12065 0.2794)
			(stroke
				(width 0.1)
				(type default)
			)
			(layer "F.Fab")
		)
		(fp_line
			(start -0.12065 0.3048)
			(end -0.67945 0.3048)
			(stroke
				(width 0.1)
				(type default)
			)
			(layer "F.Fab")
		)
		(fp_line
			(start -0.12065 0.2794)
			(end -0.12065 0.3048)
			(stroke
				(width 0.1)
				(type default)
			)
			(layer "F.Fab")
		)
		(fp_line
			(start -0.12065 -0.2794)
			(end 0.12065 -0.2794)
			(stroke
				(width 0.1)
				(type default)
			)
			(layer "F.Fab")
		)
		(fp_line
			(start -0.12065 -0.305054)
			(end -0.12065 -0.2794)
			(stroke
				(width 0.1)
				(type default)
			)
			(layer "F.Fab")
		)
		(fp_line
			(start -0.67945 0.3048)
			(end -0.67945 -0.305054)
			(stroke
				(width 0.1)
				(type default)
			)
			(layer "F.Fab")
		)
		(fp_line
			(start -0.67945 -0.305054)
			(end -0.12065 -0.305054)
			(stroke
				(width 0.1)
				(type default)
			)
			(layer "F.Fab")
		)
		(pad "1" smd circle
			(at -0.40005 0 180)
			(size 0 0)
			(layers "F.Cu" "F.Mask" "F.Paste")
			(net "SMB_PDBV_FAN_SDA")
		)
		(pad "2" smd circle
			(at 0.40005 0 180)
			(size 0 0)
			(layers "F.Cu" "F.Mask" "F.Paste")
			(net "SMB_PDBV_FAN_R_U403_SDA")
		)
	)
	(footprint ""
		(layer "F.Cu")
		(at 13.335 -170.815 180)
		(property "Reference" "R5504"
			(at 0 0 180)
			(layer "F.SilkS")
			(hide yes)
			(effects
				(font
					(size 1.27 1.27)
				)
			)
		)
		(property "Value" ""
			(at 0 0 180)
			(layer "F.Fab")
			(effects
				(font
					(size 1.27 1.27)
				)
			)
		)
		(duplicate_pad_numbers_are_jumpers no)
		(fp_line
			(start 0.7874 0.4064)
			(end -0.7874 0.4064)
			(stroke
				(width 0.1524)
				(type default)
			)
			(layer "F.SilkS")
		)
		(fp_line
			(start 0.7874 -0.4064)
			(end 0.7874 0.4064)
			(stroke
				(width 0.1524)
				(type default)
			)
			(layer "F.SilkS")
		)
		(fp_line
			(start -0.7874 0.4064)
			(end -0.7874 -0.4064)
			(stroke
				(width 0.1524)
				(type default)
			)
			(layer "F.SilkS")
		)
		(fp_line
			(start -0.7874 -0.4064)
			(end 0.7874 -0.4064)
			(stroke
				(width 0.1524)
				(type default)
			)
			(layer "F.SilkS")
		)
		(fp_line
			(start 0.67945 0.3048)
			(end 0.120396 0.3048)
			(stroke
				(width 0.1)
				(type default)
			)
			(layer "F.Fab")
		)
		(fp_line
			(start 0.67945 -0.3048)
			(end 0.67945 0.3048)
			(stroke
				(width 0.1)
				(type default)
			)
			(layer "F.Fab")
		)
		(fp_line
			(start 0.12065 -0.2794)
			(end 0.12065 -0.3048)
			(stroke
				(width 0.1)
				(type default)
			)
			(layer "F.Fab")
		)
		(fp_line
			(start 0.12065 -0.3048)
			(end 0.67945 -0.3048)
			(stroke
				(width 0.1)
				(type default)
			)
			(layer "F.Fab")
		)
		(fp_line
			(start 0.120396 0.3048)
			(end 0.120396 0.2794)
			(stroke
				(width 0.1)
				(type default)
			)
			(layer "F.Fab")
		)
		(fp_line
			(start 0.120396 0.2794)
			(end -0.12065 0.2794)
			(stroke
				(width 0.1)
				(type default)
			)
			(layer "F.Fab")
		)
		(fp_line
			(start -0.12065 0.3048)
			(end -0.67945 0.3048)
			(stroke
				(width 0.1)
				(type default)
			)
			(layer "F.Fab")
		)
		(fp_line
			(start -0.12065 0.2794)
			(end -0.12065 0.3048)
			(stroke
				(width 0.1)
				(type default)
			)
			(layer "F.Fab")
		)
		(fp_line
			(start -0.12065 -0.2794)
			(end 0.12065 -0.2794)
			(stroke
				(width 0.1)
				(type default)
			)
			(layer "F.Fab")
		)
		(fp_line
			(start -0.12065 -0.305054)
			(end -0.12065 -0.2794)
			(stroke
				(width 0.1)
				(type default)
			)
			(layer "F.Fab")
		)
		(fp_line
			(start -0.67945 0.3048)
			(end -0.67945 -0.305054)
			(stroke
				(width 0.1)
				(type default)
			)
			(layer "F.Fab")
		)
		(fp_line
			(start -0.67945 -0.305054)
			(end -0.12065 -0.305054)
			(stroke
				(width 0.1)
				(type default)
			)
			(layer "F.Fab")
		)
		(pad "1" smd circle
			(at -0.40005 0 180)
			(size 0 0)
			(layers "F.Cu" "F.Mask" "F.Paste")
			(net "P3V3_AUX")
		)
		(pad "2" smd circle
			(at 0.40005 0 180)
			(size 0 0)
			(layers "F.Cu" "F.Mask" "F.Paste")
			(net "FAN_5_PRESENT_N")
		)
	)
	(footprint ""
		(layer "F.Cu")
		(at 16.891 -108.458 180)
		(property "Reference" "R5538"
			(at 0 0 180)
			(layer "F.SilkS")
			(hide yes)
			(effects
				(font
					(size 1.27 1.27)
				)
			)
		)
		(property "Value" ""
			(at 0 0 180)
			(layer "F.Fab")
			(effects
				(font
					(size 1.27 1.27)
				)
			)
		)
		(duplicate_pad_numbers_are_jumpers no)
		(fp_line
			(start 0.7874 0.4064)
			(end -0.7874 0.4064)
			(stroke
				(width 0.1524)
				(type default)
			)
			(layer "F.SilkS")
		)
		(fp_line
			(start 0.7874 -0.4064)
			(end 0.7874 0.4064)
			(stroke
				(width 0.1524)
				(type default)
			)
			(layer "F.SilkS")
		)
		(fp_line
			(start -0.7874 0.4064)
			(end -0.7874 -0.4064)
			(stroke
				(width 0.1524)
				(type default)
			)
			(layer "F.SilkS")
		)
		(fp_line
			(start -0.7874 -0.4064)
			(end 0.7874 -0.4064)
			(stroke
				(width 0.1524)
				(type default)
			)
			(layer "F.SilkS")
		)
		(fp_line
			(start 0.67945 0.3048)
			(end 0.120396 0.3048)
			(stroke
				(width 0.1)
				(type default)
			)
			(layer "F.Fab")
		)
		(fp_line
			(start 0.67945 -0.3048)
			(end 0.67945 0.3048)
			(stroke
				(width 0.1)
				(type default)
			)
			(layer "F.Fab")
		)
		(fp_line
			(start 0.12065 -0.2794)
			(end 0.12065 -0.3048)
			(stroke
				(width 0.1)
				(type default)
			)
			(layer "F.Fab")
		)
		(fp_line
			(start 0.12065 -0.3048)
			(end 0.67945 -0.3048)
			(stroke
				(width 0.1)
				(type default)
			)
			(layer "F.Fab")
		)
		(fp_line
			(start 0.120396 0.3048)
			(end 0.120396 0.2794)
			(stroke
				(width 0.1)
				(type default)
			)
			(layer "F.Fab")
		)
		(fp_line
			(start 0.120396 0.2794)
			(end -0.12065 0.2794)
			(stroke
				(width 0.1)
				(type default)
			)
			(layer "F.Fab")
		)
		(fp_line
			(start -0.12065 0.3048)
			(end -0.67945 0.3048)
			(stroke
				(width 0.1)
				(type default)
			)
			(layer "F.Fab")
		)
		(fp_line
			(start -0.12065 0.2794)
			(end -0.12065 0.3048)
			(stroke
				(width 0.1)
				(type default)
			)
			(layer "F.Fab")
		)
		(fp_line
			(start -0.12065 -0.2794)
			(end 0.12065 -0.2794)
			(stroke
				(width 0.1)
				(type default)
			)
			(layer "F.Fab")
		)
		(fp_line
			(start -0.12065 -0.305054)
			(end -0.12065 -0.2794)
			(stroke
				(width 0.1)
				(type default)
			)
			(layer "F.Fab")
		)
		(fp_line
			(start -0.67945 0.3048)
			(end -0.67945 -0.305054)
			(stroke
				(width 0.1)
				(type default)
			)
			(layer "F.Fab")
		)
		(fp_line
			(start -0.67945 -0.305054)
			(end -0.12065 -0.305054)
			(stroke
				(width 0.1)
				(type default)
			)
			(layer "F.Fab")
		)
		(pad "1" smd rect
			(at -0.40005 0)
			(size 0.4572 0.508)
			(layers "F.Cu" "F.Mask" "F.Paste")
			(net "P12V_LED_FAN5")
		)
		(pad "2" smd rect
			(at 0.40005 0)
			(size 0.4572 0.508)
			(layers "F.Cu" "F.Mask" "F.Paste")
			(net "FAN_5_FAIL_LED_R_N")
		)
	)
	(footprint ""
		(layer "F.Cu")
		(at 36.703 -22.098 -90)
		(property "Reference" "R5408"
			(at 0 0 270)
			(layer "F.SilkS")
			(hide yes)
			(effects
				(font
					(size 1.27 1.27)
				)
			)
		)
		(property "Value" ""
			(at 0 0 270)
			(layer "F.Fab")
			(effects
				(font
					(size 1.27 1.27)
				)
			)
		)
		(duplicate_pad_numbers_are_jumpers no)
		(fp_line
			(start -0.7874 0.4064)
			(end -0.7874 -0.4064)
			(stroke
				(width 0.1524)
				(type default)
			)
			(layer "F.SilkS")
		)
		(fp_line
			(start 0.7874 0.4064)
			(end -0.7874 0.4064)
			(stroke
				(width 0.1524)
				(type default)
			)
			(layer "F.SilkS")
		)
		(fp_line
			(start -0.7874 -0.4064)
			(end 0.7874 -0.4064)
			(stroke
				(width 0.1524)
				(type default)
			)
			(layer "F.SilkS")
		)
		(fp_line
			(start 0.7874 -0.4064)
			(end 0.7874 0.4064)
			(stroke
				(width 0.1524)
				(type default)
			)
			(layer "F.SilkS")
		)
		(fp_line
			(start -0.67945 0.3048)
			(end -0.67945 -0.305054)
			(stroke
				(width 0.1)
				(type default)
			)
			(layer "F.Fab")
		)
		(fp_line
			(start -0.12065 0.3048)
			(end -0.67945 0.3048)
			(stroke
				(width 0.1)
				(type default)
			)
			(layer "F.Fab")
		)
		(fp_line
			(start 0.120396 0.3048)
			(end 0.120396 0.2794)
			(stroke
				(width 0.1)
				(type default)
			)
			(layer "F.Fab")
		)
		(fp_line
			(start 0.67945 0.3048)
			(end 0.120396 0.3048)
			(stroke
				(width 0.1)
				(type default)
			)
			(layer "F.Fab")
		)
		(fp_line
			(start -0.12065 0.2794)
			(end -0.12065 0.3048)
			(stroke
				(width 0.1)
				(type default)
			)
			(layer "F.Fab")
		)
		(fp_line
			(start 0.120396 0.2794)
			(end -0.12065 0.2794)
			(stroke
				(width 0.1)
				(type default)
			)
			(layer "F.Fab")
		)
		(fp_line
			(start -0.12065 -0.2794)
			(end 0.12065 -0.2794)
			(stroke
				(width 0.1)
				(type default)
			)
			(layer "F.Fab")
		)
		(fp_line
			(start 0.12065 -0.2794)
			(end 0.12065 -0.3048)
			(stroke
				(width 0.1)
				(type default)
			)
			(layer "F.Fab")
		)
		(fp_line
			(start 0.12065 -0.3048)
			(end 0.67945 -0.3048)
			(stroke
				(width 0.1)
				(type default)
			)
			(layer "F.Fab")
		)
		(fp_line
			(start 0.67945 -0.3048)
			(end 0.67945 0.3048)
			(stroke
				(width 0.1)
				(type default)
			)
			(layer "F.Fab")
		)
		(fp_line
			(start -0.67945 -0.305054)
			(end -0.12065 -0.305054)
			(stroke
				(width 0.1)
				(type default)
			)
			(layer "F.Fab")
		)
		(fp_line
			(start -0.12065 -0.305054)
			(end -0.12065 -0.2794)
			(stroke
				(width 0.1)
				(type default)
			)
			(layer "F.Fab")
		)
		(pad "1" smd rect
			(at -0.40005 0 90)
			(size 0.4572 0.508)
			(layers "F.Cu" "F.Mask" "F.Paste")
			(net "FAN_3_FAIL_LED_R_N")
		)
		(pad "2" smd rect
			(at 0.40005 0 90)
			(size 0.4572 0.508)
			(layers "F.Cu" "F.Mask" "F.Paste")
			(net "FAN_3_FAIL_R_LED_N")
		)
	)
	(footprint ""
		(layer "F.Cu")
		(at 6.477 -166.116)
		(property "Reference" "R101"
			(at 0 0 0)
			(layer "F.SilkS")
			(hide yes)
			(effects
				(font
					(size 1.27 1.27)
				)
			)
		)
		(property "Value" ""
			(at 0 0 0)
			(layer "F.Fab")
			(effects
				(font
					(size 1.27 1.27)
				)
			)
		)
		(duplicate_pad_numbers_are_jumpers no)
		(fp_line
			(start -0.7874 -0.4064)
			(end 0.7874 -0.4064)
			(stroke
				(width 0.1524)
				(type default)
			)
			(layer "F.SilkS")
		)
		(fp_line
			(start -0.7874 0.4064)
			(end -0.7874 -0.4064)
			(stroke
				(width 0.1524)
				(type default)
			)
			(layer "F.SilkS")
		)
		(fp_line
			(start 0.7874 -0.4064)
			(end 0.7874 0.4064)
			(stroke
				(width 0.1524)
				(type default)
			)
			(layer "F.SilkS")
		)
		(fp_line
			(start 0.7874 0.4064)
			(end -0.7874 0.4064)
			(stroke
				(width 0.1524)
				(type default)
			)
			(layer "F.SilkS")
		)
		(fp_line
			(start -0.67945 -0.305054)
			(end -0.12065 -0.305054)
			(stroke
				(width 0.1)
				(type default)
			)
			(layer "F.Fab")
		)
		(fp_line
			(start -0.67945 0.3048)
			(end -0.67945 -0.305054)
			(stroke
				(width 0.1)
				(type default)
			)
			(layer "F.Fab")
		)
		(fp_line
			(start -0.12065 -0.305054)
			(end -0.12065 -0.2794)
			(stroke
				(width 0.1)
				(type default)
			)
			(layer "F.Fab")
		)
		(fp_line
			(start -0.12065 -0.2794)
			(end 0.12065 -0.2794)
			(stroke
				(width 0.1)
				(type default)
			)
			(layer "F.Fab")
		)
		(fp_line
			(start -0.12065 0.2794)
			(end -0.12065 0.3048)
			(stroke
				(width 0.1)
				(type default)
			)
			(layer "F.Fab")
		)
		(fp_line
			(start -0.12065 0.3048)
			(end -0.67945 0.3048)
			(stroke
				(width 0.1)
				(type default)
			)
			(layer "F.Fab")
		)
		(fp_line
			(start 0.120396 0.2794)
			(end -0.12065 0.2794)
			(stroke
				(width 0.1)
				(type default)
			)
			(layer "F.Fab")
		)
		(fp_line
			(start 0.120396 0.3048)
			(end 0.120396 0.2794)
			(stroke
				(width 0.1)
				(type default)
			)
			(layer "F.Fab")
		)
		(fp_line
			(start 0.12065 -0.3048)
			(end 0.67945 -0.3048)
			(stroke
				(width 0.1)
				(type default)
			)
			(layer "F.Fab")
		)
		(fp_line
			(start 0.12065 -0.2794)
			(end 0.12065 -0.3048)
			(stroke
				(width 0.1)
				(type default)
			)
			(layer "F.Fab")
		)
		(fp_line
			(start 0.67945 -0.3048)
			(end 0.67945 0.3048)
			(stroke
				(width 0.1)
				(type default)
			)
			(layer "F.Fab")
		)
		(fp_line
			(start 0.67945 0.3048)
			(end 0.120396 0.3048)
			(stroke
				(width 0.1)
				(type default)
			)
			(layer "F.Fab")
		)
		(pad "1" smd circle
			(at -0.40005 0)
			(size 0 0)
			(layers "F.Cu" "F.Mask" "F.Paste")
			(net "P3V3_AUX")
		)
		(pad "2" smd circle
			(at 0.40005 0)
			(size 0 0)
			(layers "F.Cu" "F.Mask" "F.Paste")
			(net "FAN_2_PRSNT_BUF_R_N")
		)
	)
	(footprint ""
		(layer "F.Cu")
		(at 15.621 -172.466)
		(property "Reference" "C1946"
			(at 0 0 0)
			(layer "F.SilkS")
			(hide yes)
			(effects
				(font
					(size 1.27 1.27)
				)
			)
		)
		(property "Value" ""
			(at 0 0 0)
			(layer "F.Fab")
			(effects
				(font
					(size 1.27 1.27)
				)
			)
		)
		(duplicate_pad_numbers_are_jumpers no)
		(fp_line
			(start -0.7874 -0.4064)
			(end 0.7874 -0.4064)
			(stroke
				(width 0.1524)
				(type default)
			)
			(layer "F.SilkS")
		)
		(fp_line
			(start -0.7874 0.4064)
			(end -0.7874 -0.4064)
			(stroke
				(width 0.1524)
				(type default)
			)
			(layer "F.SilkS")
		)
		(fp_line
			(start 0.7874 -0.4064)
			(end 0.7874 0.4064)
			(stroke
				(width 0.1524)
				(type default)
			)
			(layer "F.SilkS")
		)
		(fp_line
			(start 0.7874 0.4064)
			(end -0.7874 0.4064)
			(stroke
				(width 0.1524)
				(type default)
			)
			(layer "F.SilkS")
		)
		(fp_line
			(start -0.67945 -0.305054)
			(end -0.12065 -0.305054)
			(stroke
				(width 0.1)
				(type default)
			)
			(layer "F.Fab")
		)
		(fp_line
			(start -0.67945 0.3048)
			(end -0.67945 -0.305054)
			(stroke
				(width 0.1)
				(type default)
			)
			(layer "F.Fab")
		)
		(fp_line
			(start -0.12065 -0.305054)
			(end -0.12065 -0.2794)
			(stroke
				(width 0.1)
				(type default)
			)
			(layer "F.Fab")
		)
		(fp_line
			(start -0.12065 -0.2794)
			(end 0.12065 -0.2794)
			(stroke
				(width 0.1)
				(type default)
			)
			(layer "F.Fab")
		)
		(fp_line
			(start -0.12065 0.2794)
			(end -0.12065 0.3048)
			(stroke
				(width 0.1)
				(type default)
			)
			(layer "F.Fab")
		)
		(fp_line
			(start -0.12065 0.3048)
			(end -0.67945 0.3048)
			(stroke
				(width 0.1)
				(type default)
			)
			(layer "F.Fab")
		)
		(fp_line
			(start 0.120396 0.2794)
			(end -0.12065 0.2794)
			(stroke
				(width 0.1)
				(type default)
			)
			(layer "F.Fab")
		)
		(fp_line
			(start 0.120396 0.3048)
			(end 0.120396 0.2794)
			(stroke
				(width 0.1)
				(type default)
			)
			(layer "F.Fab")
		)
		(fp_line
			(start 0.12065 -0.3048)
			(end 0.67945 -0.3048)
			(stroke
				(width 0.1)
				(type default)
			)
			(layer "F.Fab")
		)
		(fp_line
			(start 0.12065 -0.2794)
			(end 0.12065 -0.3048)
			(stroke
				(width 0.1)
				(type default)
			)
			(layer "F.Fab")
		)
		(fp_line
			(start 0.67945 -0.3048)
			(end 0.67945 0.3048)
			(stroke
				(width 0.1)
				(type default)
			)
			(layer "F.Fab")
		)
		(fp_line
			(start 0.67945 0.3048)
			(end 0.120396 0.3048)
			(stroke
				(width 0.1)
				(type default)
			)
			(layer "F.Fab")
		)
		(pad "1" smd circle
			(at -0.40005 0)
			(size 0 0)
			(layers "F.Cu" "F.Mask" "F.Paste")
			(net "FAN_6_PRESENT_N")
		)
		(pad "2" smd circle
			(at 0.40005 0)
			(size 0 0)
			(layers "F.Cu" "F.Mask" "F.Paste")
			(net "GND")
		)
	)
	(footprint ""
		(layer "F.Cu")
		(at 14.351 -109.023912)
		(property "Reference" "R5205"
			(at 0 0 0)
			(layer "F.SilkS")
			(hide yes)
			(effects
				(font
					(size 1.27 1.27)
				)
			)
		)
		(property "Value" ""
			(at 0 0 0)
			(layer "F.Fab")
			(effects
				(font
					(size 1.27 1.27)
				)
			)
		)
		(duplicate_pad_numbers_are_jumpers no)
		(fp_line
			(start -0.7874 -0.4064)
			(end 0.7874 -0.4064)
			(stroke
				(width 0.1524)
				(type default)
			)
			(layer "F.SilkS")
		)
		(fp_line
			(start -0.7874 0.4064)
			(end -0.7874 -0.4064)
			(stroke
				(width 0.1524)
				(type default)
			)
			(layer "F.SilkS")
		)
		(fp_line
			(start 0.7874 -0.4064)
			(end 0.7874 0.4064)
			(stroke
				(width 0.1524)
				(type default)
			)
			(layer "F.SilkS")
		)
		(fp_line
			(start 0.7874 0.4064)
			(end -0.7874 0.4064)
			(stroke
				(width 0.1524)
				(type default)
			)
			(layer "F.SilkS")
		)
		(fp_line
			(start -0.67945 -0.305054)
			(end -0.12065 -0.305054)
			(stroke
				(width 0.1)
				(type default)
			)
			(layer "F.Fab")
		)
		(fp_line
			(start -0.67945 0.3048)
			(end -0.67945 -0.305054)
			(stroke
				(width 0.1)
				(type default)
			)
			(layer "F.Fab")
		)
		(fp_line
			(start -0.12065 -0.305054)
			(end -0.12065 -0.2794)
			(stroke
				(width 0.1)
				(type default)
			)
			(layer "F.Fab")
		)
		(fp_line
			(start -0.12065 -0.2794)
			(end 0.12065 -0.2794)
			(stroke
				(width 0.1)
				(type default)
			)
			(layer "F.Fab")
		)
		(fp_line
			(start -0.12065 0.2794)
			(end -0.12065 0.3048)
			(stroke
				(width 0.1)
				(type default)
			)
			(layer "F.Fab")
		)
		(fp_line
			(start -0.12065 0.3048)
			(end -0.67945 0.3048)
			(stroke
				(width 0.1)
				(type default)
			)
			(layer "F.Fab")
		)
		(fp_line
			(start 0.120396 0.2794)
			(end -0.12065 0.2794)
			(stroke
				(width 0.1)
				(type default)
			)
			(layer "F.Fab")
		)
		(fp_line
			(start 0.120396 0.3048)
			(end 0.120396 0.2794)
			(stroke
				(width 0.1)
				(type default)
			)
			(layer "F.Fab")
		)
		(fp_line
			(start 0.12065 -0.3048)
			(end 0.67945 -0.3048)
			(stroke
				(width 0.1)
				(type default)
			)
			(layer "F.Fab")
		)
		(fp_line
			(start 0.12065 -0.2794)
			(end 0.12065 -0.3048)
			(stroke
				(width 0.1)
				(type default)
			)
			(layer "F.Fab")
		)
		(fp_line
			(start 0.67945 -0.3048)
			(end 0.67945 0.3048)
			(stroke
				(width 0.1)
				(type default)
			)
			(layer "F.Fab")
		)
		(fp_line
			(start 0.67945 0.3048)
			(end 0.120396 0.3048)
			(stroke
				(width 0.1)
				(type default)
			)
			(layer "F.Fab")
		)
		(pad "1" smd circle
			(at -0.40005 0)
			(size 0 0)
			(layers "F.Cu" "F.Mask" "F.Paste")
			(net "SMB_FAN5_SDA_R")
		)
		(pad "2" smd circle
			(at 0.40005 0)
			(size 0 0)
			(layers "F.Cu" "F.Mask" "F.Paste")
			(net "SMB_FAN5_SDA")
		)
	)
	(footprint ""
		(layer "F.Cu")
		(at 25.273 -197.104)
		(property "Reference" "U327"
			(at -1.397 1.93167 0)
			(unlocked yes)
			(layer "F.SilkS")
			(effects
				(font
					(size 0.7874 0.5842)
					(thickness 0.1524)
				)
				(justify left)
			)
		)
		(property "Value" ""
			(at 0 0 0)
			(layer "F.Fab")
			(effects
				(font
					(size 1.27 1.27)
				)
			)
		)
		(duplicate_pad_numbers_are_jumpers no)
		(fp_line
			(start -1.538478 -1.150874)
			(end -1.538478 1.150874)
			(stroke
				(width 0.1524)
				(type default)
			)
			(layer "F.SilkS")
		)
		(fp_line
			(start -1.538478 1.150874)
			(end 1.538478 1.150874)
			(stroke
				(width 0.1524)
				(type default)
			)
			(layer "F.SilkS")
		)
		(fp_line
			(start 1.538478 -1.150874)
			(end -1.538478 -1.150874)
			(stroke
				(width 0.1524)
				(type default)
			)
			(layer "F.SilkS")
		)
		(fp_line
			(start 1.538478 1.150874)
			(end 1.538478 -1.150874)
			(stroke
				(width 0.1524)
				(type default)
			)
			(layer "F.SilkS")
		)
		(fp_line
			(start -0.674878 -1.100074)
			(end -0.674878 1.100074)
			(stroke
				(width 0.1)
				(type default)
			)
			(layer "F.Fab")
		)
		(fp_line
			(start -0.674878 1.100074)
			(end 0.674878 1.100074)
			(stroke
				(width 0.1)
				(type default)
			)
			(layer "F.Fab")
		)
		(fp_line
			(start 0.674878 -1.100074)
			(end -0.674878 -1.100074)
			(stroke
				(width 0.1)
				(type default)
			)
			(layer "F.Fab")
		)
		(fp_line
			(start 0.674878 1.100074)
			(end 0.674878 -1.100074)
			(stroke
				(width 0.1)
				(type default)
			)
			(layer "F.Fab")
		)
		(pad "1" smd rect
			(at -0.94996 -0.649986 90)
			(size 0.7112 0.9144)
			(layers "F.Cu" "F.Mask" "F.Paste")
			(net "FAN_6_PWM_IL")
		)
		(pad "2" smd rect
			(at -0.94996 0.649986 90)
			(size 0.7112 0.9144)
			(layers "F.Cu" "F.Mask" "F.Paste")
			(net "FAN_6_PWM_OL")
		)
		(pad "3" smd rect
			(at 0.94996 0 90)
			(size 0.7112 0.9144)
			(layers "F.Cu" "F.Mask" "F.Paste")
			(net "FAN_6_PWM_BUF")
		)
	)
	(footprint ""
		(layer "F.Cu")
		(at 16.520922 -199.076056)
		(property "Reference" "C2045"
			(at 0 0 0)
			(layer "F.SilkS")
			(hide yes)
			(effects
				(font
					(size 1.27 1.27)
				)
			)
		)
		(property "Value" ""
			(at 0 0 0)
			(layer "F.Fab")
			(effects
				(font
					(size 1.27 1.27)
				)
			)
		)
		(duplicate_pad_numbers_are_jumpers no)
		(fp_line
			(start -0.7874 -0.4064)
			(end 0.7874 -0.4064)
			(stroke
				(width 0.1524)
				(type default)
			)
			(layer "F.SilkS")
		)
		(fp_line
			(start -0.7874 0.4064)
			(end -0.7874 -0.4064)
			(stroke
				(width 0.1524)
				(type default)
			)
			(layer "F.SilkS")
		)
		(fp_line
			(start 0.7874 -0.4064)
			(end 0.7874 0.4064)
			(stroke
				(width 0.1524)
				(type default)
			)
			(layer "F.SilkS")
		)
		(fp_line
			(start 0.7874 0.4064)
			(end -0.7874 0.4064)
			(stroke
				(width 0.1524)
				(type default)
			)
			(layer "F.SilkS")
		)
		(fp_line
			(start -0.67945 -0.305054)
			(end -0.12065 -0.305054)
			(stroke
				(width 0.1)
				(type default)
			)
			(layer "F.Fab")
		)
		(fp_line
			(start -0.67945 0.3048)
			(end -0.67945 -0.305054)
			(stroke
				(width 0.1)
				(type default)
			)
			(layer "F.Fab")
		)
		(fp_line
			(start -0.12065 -0.305054)
			(end -0.12065 -0.2794)
			(stroke
				(width 0.1)
				(type default)
			)
			(layer "F.Fab")
		)
		(fp_line
			(start -0.12065 -0.2794)
			(end 0.12065 -0.2794)
			(stroke
				(width 0.1)
				(type default)
			)
			(layer "F.Fab")
		)
		(fp_line
			(start -0.12065 0.2794)
			(end -0.12065 0.3048)
			(stroke
				(width 0.1)
				(type default)
			)
			(layer "F.Fab")
		)
		(fp_line
			(start -0.12065 0.3048)
			(end -0.67945 0.3048)
			(stroke
				(width 0.1)
				(type default)
			)
			(layer "F.Fab")
		)
		(fp_line
			(start 0.120396 0.2794)
			(end -0.12065 0.2794)
			(stroke
				(width 0.1)
				(type default)
			)
			(layer "F.Fab")
		)
		(fp_line
			(start 0.120396 0.3048)
			(end 0.120396 0.2794)
			(stroke
				(width 0.1)
				(type default)
			)
			(layer "F.Fab")
		)
		(fp_line
			(start 0.12065 -0.3048)
			(end 0.67945 -0.3048)
			(stroke
				(width 0.1)
				(type default)
			)
			(layer "F.Fab")
		)
		(fp_line
			(start 0.12065 -0.2794)
			(end 0.12065 -0.3048)
			(stroke
				(width 0.1)
				(type default)
			)
			(layer "F.Fab")
		)
		(fp_line
			(start 0.67945 -0.3048)
			(end 0.67945 0.3048)
			(stroke
				(width 0.1)
				(type default)
			)
			(layer "F.Fab")
		)
		(fp_line
			(start 0.67945 0.3048)
			(end 0.120396 0.3048)
			(stroke
				(width 0.1)
				(type default)
			)
			(layer "F.Fab")
		)
		(pad "1" smd circle
			(at -0.40005 0)
			(size 0 0)
			(layers "F.Cu" "F.Mask" "F.Paste")
			(net "FAN_6_PWM_IL_R")
		)
		(pad "2" smd circle
			(at 0.40005 0)
			(size 0 0)
			(layers "F.Cu" "F.Mask" "F.Paste")
			(net "GND")
		)
	)
	(footprint ""
		(layer "F.Cu")
		(at 33.528 -176.403)
		(property "Reference" "R5102"
			(at 0 0 0)
			(layer "F.SilkS")
			(hide yes)
			(effects
				(font
					(size 1.27 1.27)
				)
			)
		)
		(property "Value" ""
			(at 0 0 0)
			(layer "F.Fab")
			(effects
				(font
					(size 1.27 1.27)
				)
			)
		)
		(duplicate_pad_numbers_are_jumpers no)
		(fp_line
			(start -0.7874 -0.4064)
			(end 0.7874 -0.4064)
			(stroke
				(width 0.1524)
				(type default)
			)
			(layer "F.SilkS")
		)
		(fp_line
			(start -0.7874 0.4064)
			(end -0.7874 -0.4064)
			(stroke
				(width 0.1524)
				(type default)
			)
			(layer "F.SilkS")
		)
		(fp_line
			(start 0.7874 -0.4064)
			(end 0.7874 0.4064)
			(stroke
				(width 0.1524)
				(type default)
			)
			(layer "F.SilkS")
		)
		(fp_line
			(start 0.7874 0.4064)
			(end -0.7874 0.4064)
			(stroke
				(width 0.1524)
				(type default)
			)
			(layer "F.SilkS")
		)
		(fp_line
			(start -0.67945 -0.305054)
			(end -0.12065 -0.305054)
			(stroke
				(width 0.1)
				(type default)
			)
			(layer "F.Fab")
		)
		(fp_line
			(start -0.67945 0.3048)
			(end -0.67945 -0.305054)
			(stroke
				(width 0.1)
				(type default)
			)
			(layer "F.Fab")
		)
		(fp_line
			(start -0.12065 -0.305054)
			(end -0.12065 -0.2794)
			(stroke
				(width 0.1)
				(type default)
			)
			(layer "F.Fab")
		)
		(fp_line
			(start -0.12065 -0.2794)
			(end 0.12065 -0.2794)
			(stroke
				(width 0.1)
				(type default)
			)
			(layer "F.Fab")
		)
		(fp_line
			(start -0.12065 0.2794)
			(end -0.12065 0.3048)
			(stroke
				(width 0.1)
				(type default)
			)
			(layer "F.Fab")
		)
		(fp_line
			(start -0.12065 0.3048)
			(end -0.67945 0.3048)
			(stroke
				(width 0.1)
				(type default)
			)
			(layer "F.Fab")
		)
		(fp_line
			(start 0.120396 0.2794)
			(end -0.12065 0.2794)
			(stroke
				(width 0.1)
				(type default)
			)
			(layer "F.Fab")
		)
		(fp_line
			(start 0.120396 0.3048)
			(end 0.120396 0.2794)
			(stroke
				(width 0.1)
				(type default)
			)
			(layer "F.Fab")
		)
		(fp_line
			(start 0.12065 -0.3048)
			(end 0.67945 -0.3048)
			(stroke
				(width 0.1)
				(type default)
			)
			(layer "F.Fab")
		)
		(fp_line
			(start 0.12065 -0.2794)
			(end 0.12065 -0.3048)
			(stroke
				(width 0.1)
				(type default)
			)
			(layer "F.Fab")
		)
		(fp_line
			(start 0.67945 -0.3048)
			(end 0.67945 0.3048)
			(stroke
				(width 0.1)
				(type default)
			)
			(layer "F.Fab")
		)
		(fp_line
			(start 0.67945 0.3048)
			(end 0.120396 0.3048)
			(stroke
				(width 0.1)
				(type default)
			)
			(layer "F.Fab")
		)
		(pad "1" smd circle
			(at -0.40005 0)
			(size 0 0)
			(layers "F.Cu" "F.Mask" "F.Paste")
			(net "FAN_4_OK_LED")
		)
		(pad "2" smd circle
			(at 0.40005 0)
			(size 0 0)
			(layers "F.Cu" "F.Mask" "F.Paste")
			(net "FAN_4_OK_R_LED")
		)
	)
	(footprint ""
		(layer "F.Cu")
		(at 17.272 -298.704 180)
		(property "Reference" "U366"
			(at -0.508 -1.80467 0)
			(unlocked yes)
			(layer "F.SilkS")
			(effects
				(font
					(size 0.7874 0.5842)
					(thickness 0.1524)
				)
				(justify left)
			)
		)
		(property "Value" ""
			(at 0 0 180)
			(layer "F.Fab")
			(effects
				(font
					(size 1.27 1.27)
				)
			)
		)
		(duplicate_pad_numbers_are_jumpers no)
		(fp_line
			(start 1.335278 1.100074)
			(end 1.335278 -1.100074)
			(stroke
				(width 0.1524)
				(type default)
			)
			(layer "F.SilkS")
		)
		(fp_line
			(start 1.335278 -1.100074)
			(end -1.335278 -1.100074)
			(stroke
				(width 0.1524)
				(type default)
			)
			(layer "F.SilkS")
		)
		(fp_line
			(start -1.335278 1.100074)
			(end 1.335278 1.100074)
			(stroke
				(width 0.1524)
				(type default)
			)
			(layer "F.SilkS")
		)
		(fp_line
			(start -1.335278 -1.100074)
			(end -1.335278 1.100074)
			(stroke
				(width 0.1524)
				(type default)
			)
			(layer "F.SilkS")
		)
		(fp_line
			(start 0.674878 1.100074)
			(end 0.674878 -1.100074)
			(stroke
				(width 0.1)
				(type default)
			)
			(layer "F.Fab")
		)
		(fp_line
			(start 0.674878 -1.100074)
			(end -0.674878 -1.100074)
			(stroke
				(width 0.1)
				(type default)
			)
			(layer "F.Fab")
		)
		(fp_line
			(start -0.674878 1.100074)
			(end 0.674878 1.100074)
			(stroke
				(width 0.1)
				(type default)
			)
			(layer "F.Fab")
		)
		(fp_line
			(start -0.674878 -1.100074)
			(end -0.674878 1.100074)
			(stroke
				(width 0.1)
				(type default)
			)
			(layer "F.Fab")
		)
		(pad "D" smd rect
			(at 0.8001 0 90)
			(size 0.6096 0.8128)
			(layers "F.Cu" "F.Mask" "F.Paste")
			(net "FAN_7_OK_LED_R_N")
		)
		(pad "G" smd rect
			(at -0.8001 -0.649986 90)
			(size 0.6096 0.8128)
			(layers "F.Cu" "F.Mask" "F.Paste")
			(net "FAN_7_OK_R_LED")
		)
		(pad "S" smd rect
			(at -0.8001 0.649986 90)
			(size 0.6096 0.8128)
			(layers "F.Cu" "F.Mask" "F.Paste")
			(net "GND")
		)
	)
	(footprint ""
		(layer "F.Cu")
		(at 32.258 -198.755 90)
		(property "Reference" "R5391"
			(at 0 0 90)
			(layer "F.SilkS")
			(hide yes)
			(effects
				(font
					(size 1.27 1.27)
				)
			)
		)
		(property "Value" ""
			(at 0 0 90)
			(layer "F.Fab")
			(effects
				(font
					(size 1.27 1.27)
				)
			)
		)
		(duplicate_pad_numbers_are_jumpers no)
		(fp_line
			(start 0.7874 -0.4064)
			(end 0.7874 0.4064)
			(stroke
				(width 0.1524)
				(type default)
			)
			(layer "F.SilkS")
		)
		(fp_line
			(start -0.7874 -0.4064)
			(end 0.7874 -0.4064)
			(stroke
				(width 0.1524)
				(type default)
			)
			(layer "F.SilkS")
		)
		(fp_line
			(start 0.7874 0.4064)
			(end -0.7874 0.4064)
			(stroke
				(width 0.1524)
				(type default)
			)
			(layer "F.SilkS")
		)
		(fp_line
			(start -0.7874 0.4064)
			(end -0.7874 -0.4064)
			(stroke
				(width 0.1524)
				(type default)
			)
			(layer "F.SilkS")
		)
		(fp_line
			(start -0.12065 -0.305054)
			(end -0.12065 -0.2794)
			(stroke
				(width 0.1)
				(type default)
			)
			(layer "F.Fab")
		)
		(fp_line
			(start -0.67945 -0.305054)
			(end -0.12065 -0.305054)
			(stroke
				(width 0.1)
				(type default)
			)
			(layer "F.Fab")
		)
		(fp_line
			(start 0.67945 -0.3048)
			(end 0.67945 0.3048)
			(stroke
				(width 0.1)
				(type default)
			)
			(layer "F.Fab")
		)
		(fp_line
			(start 0.12065 -0.3048)
			(end 0.67945 -0.3048)
			(stroke
				(width 0.1)
				(type default)
			)
			(layer "F.Fab")
		)
		(fp_line
			(start 0.12065 -0.2794)
			(end 0.12065 -0.3048)
			(stroke
				(width 0.1)
				(type default)
			)
			(layer "F.Fab")
		)
		(fp_line
			(start -0.12065 -0.2794)
			(end 0.12065 -0.2794)
			(stroke
				(width 0.1)
				(type default)
			)
			(layer "F.Fab")
		)
		(fp_line
			(start 0.120396 0.2794)
			(end -0.12065 0.2794)
			(stroke
				(width 0.1)
				(type default)
			)
			(layer "F.Fab")
		)
		(fp_line
			(start -0.12065 0.2794)
			(end -0.12065 0.3048)
			(stroke
				(width 0.1)
				(type default)
			)
			(layer "F.Fab")
		)
		(fp_line
			(start 0.67945 0.3048)
			(end 0.120396 0.3048)
			(stroke
				(width 0.1)
				(type default)
			)
			(layer "F.Fab")
		)
		(fp_line
			(start 0.120396 0.3048)
			(end 0.120396 0.2794)
			(stroke
				(width 0.1)
				(type default)
			)
			(layer "F.Fab")
		)
		(fp_line
			(start -0.12065 0.3048)
			(end -0.67945 0.3048)
			(stroke
				(width 0.1)
				(type default)
			)
			(layer "F.Fab")
		)
		(fp_line
			(start -0.67945 0.3048)
			(end -0.67945 -0.305054)
			(stroke
				(width 0.1)
				(type default)
			)
			(layer "F.Fab")
		)
		(pad "1" smd circle
			(at -0.40005 0 90)
			(size 0 0)
			(layers "F.Cu" "F.Mask" "F.Paste")
			(net "P3V3_AUX")
		)
		(pad "2" smd circle
			(at 0.40005 0 90)
			(size 0 0)
			(layers "F.Cu" "F.Mask" "F.Paste")
			(net "FAN_1_OK_R_LED")
		)
	)
	(footprint ""
		(layer "F.Cu")
		(at 37.084 -249.047)
		(property "Reference" "PR31"
			(at 0 0 0)
			(layer "F.SilkS")
			(hide yes)
			(effects
				(font
					(size 1.27 1.27)
				)
			)
		)
		(property "Value" ""
			(at 0 0 0)
			(layer "F.Fab")
			(effects
				(font
					(size 1.27 1.27)
				)
			)
		)
		(duplicate_pad_numbers_are_jumpers no)
		(fp_line
			(start -0.7874 -0.4064)
			(end 0.7874 -0.4064)
			(stroke
				(width 0.1524)
				(type default)
			)
			(layer "F.SilkS")
		)
		(fp_line
			(start -0.7874 0.4064)
			(end -0.7874 -0.4064)
			(stroke
				(width 0.1524)
				(type default)
			)
			(layer "F.SilkS")
		)
		(fp_line
			(start 0.7874 -0.4064)
			(end 0.7874 0.4064)
			(stroke
				(width 0.1524)
				(type default)
			)
			(layer "F.SilkS")
		)
		(fp_line
			(start 0.7874 0.4064)
			(end -0.7874 0.4064)
			(stroke
				(width 0.1524)
				(type default)
			)
			(layer "F.SilkS")
		)
		(fp_line
			(start -0.67945 -0.305054)
			(end -0.12065 -0.305054)
			(stroke
				(width 0.1)
				(type default)
			)
			(layer "F.Fab")
		)
		(fp_line
			(start -0.67945 0.3048)
			(end -0.67945 -0.305054)
			(stroke
				(width 0.1)
				(type default)
			)
			(layer "F.Fab")
		)
		(fp_line
			(start -0.12065 -0.305054)
			(end -0.12065 -0.2794)
			(stroke
				(width 0.1)
				(type default)
			)
			(layer "F.Fab")
		)
		(fp_line
			(start -0.12065 -0.2794)
			(end 0.12065 -0.2794)
			(stroke
				(width 0.1)
				(type default)
			)
			(layer "F.Fab")
		)
		(fp_line
			(start -0.12065 0.2794)
			(end -0.12065 0.3048)
			(stroke
				(width 0.1)
				(type default)
			)
			(layer "F.Fab")
		)
		(fp_line
			(start -0.12065 0.3048)
			(end -0.67945 0.3048)
			(stroke
				(width 0.1)
				(type default)
			)
			(layer "F.Fab")
		)
		(fp_line
			(start 0.120396 0.2794)
			(end -0.12065 0.2794)
			(stroke
				(width 0.1)
				(type default)
			)
			(layer "F.Fab")
		)
		(fp_line
			(start 0.120396 0.3048)
			(end 0.120396 0.2794)
			(stroke
				(width 0.1)
				(type default)
			)
			(layer "F.Fab")
		)
		(fp_line
			(start 0.12065 -0.3048)
			(end 0.67945 -0.3048)
			(stroke
				(width 0.1)
				(type default)
			)
			(layer "F.Fab")
		)
		(fp_line
			(start 0.12065 -0.2794)
			(end 0.12065 -0.3048)
			(stroke
				(width 0.1)
				(type default)
			)
			(layer "F.Fab")
		)
		(fp_line
			(start 0.67945 -0.3048)
			(end 0.67945 0.3048)
			(stroke
				(width 0.1)
				(type default)
			)
			(layer "F.Fab")
		)
		(fp_line
			(start 0.67945 0.3048)
			(end 0.120396 0.3048)
			(stroke
				(width 0.1)
				(type default)
			)
			(layer "F.Fab")
		)
		(pad "1" smd circle
			(at -0.40005 0)
			(size 0 0)
			(layers "F.Cu" "F.Mask" "F.Paste")
			(net "FAN_1_MODE")
		)
		(pad "2" smd circle
			(at 0.40005 0)
			(size 0 0)
			(layers "F.Cu" "F.Mask" "F.Paste")
			(net "GND")
		)
	)
	(footprint ""
		(layer "F.Cu")
		(at 29.464 -133.477 -90)
		(property "Reference" "C1932"
			(at 0 0 270)
			(layer "F.SilkS")
			(hide yes)
			(effects
				(font
					(size 1.27 1.27)
				)
			)
		)
		(property "Value" ""
			(at 0 0 270)
			(layer "F.Fab")
			(effects
				(font
					(size 1.27 1.27)
				)
			)
		)
		(duplicate_pad_numbers_are_jumpers no)
		(fp_line
			(start -0.7874 0.4064)
			(end -0.7874 -0.4064)
			(stroke
				(width 0.1524)
				(type default)
			)
			(layer "F.SilkS")
		)
		(fp_line
			(start 0.7874 0.4064)
			(end -0.7874 0.4064)
			(stroke
				(width 0.1524)
				(type default)
			)
			(layer "F.SilkS")
		)
		(fp_line
			(start -0.7874 -0.4064)
			(end 0.7874 -0.4064)
			(stroke
				(width 0.1524)
				(type default)
			)
			(layer "F.SilkS")
		)
		(fp_line
			(start 0.7874 -0.4064)
			(end 0.7874 0.4064)
			(stroke
				(width 0.1524)
				(type default)
			)
			(layer "F.SilkS")
		)
		(fp_line
			(start -0.67945 0.3048)
			(end -0.67945 -0.305054)
			(stroke
				(width 0.1)
				(type default)
			)
			(layer "F.Fab")
		)
		(fp_line
			(start -0.12065 0.3048)
			(end -0.67945 0.3048)
			(stroke
				(width 0.1)
				(type default)
			)
			(layer "F.Fab")
		)
		(fp_line
			(start 0.120396 0.3048)
			(end 0.120396 0.2794)
			(stroke
				(width 0.1)
				(type default)
			)
			(layer "F.Fab")
		)
		(fp_line
			(start 0.67945 0.3048)
			(end 0.120396 0.3048)
			(stroke
				(width 0.1)
				(type default)
			)
			(layer "F.Fab")
		)
		(fp_line
			(start -0.12065 0.2794)
			(end -0.12065 0.3048)
			(stroke
				(width 0.1)
				(type default)
			)
			(layer "F.Fab")
		)
		(fp_line
			(start 0.120396 0.2794)
			(end -0.12065 0.2794)
			(stroke
				(width 0.1)
				(type default)
			)
			(layer "F.Fab")
		)
		(fp_line
			(start -0.12065 -0.2794)
			(end 0.12065 -0.2794)
			(stroke
				(width 0.1)
				(type default)
			)
			(layer "F.Fab")
		)
		(fp_line
			(start 0.12065 -0.2794)
			(end 0.12065 -0.3048)
			(stroke
				(width 0.1)
				(type default)
			)
			(layer "F.Fab")
		)
		(fp_line
			(start 0.12065 -0.3048)
			(end 0.67945 -0.3048)
			(stroke
				(width 0.1)
				(type default)
			)
			(layer "F.Fab")
		)
		(fp_line
			(start 0.67945 -0.3048)
			(end 0.67945 0.3048)
			(stroke
				(width 0.1)
				(type default)
			)
			(layer "F.Fab")
		)
		(fp_line
			(start -0.67945 -0.305054)
			(end -0.12065 -0.305054)
			(stroke
				(width 0.1)
				(type default)
			)
			(layer "F.Fab")
		)
		(fp_line
			(start -0.12065 -0.305054)
			(end -0.12065 -0.2794)
			(stroke
				(width 0.1)
				(type default)
			)
			(layer "F.Fab")
		)
		(pad "1" smd circle
			(at -0.40005 0 270)
			(size 0 0)
			(layers "F.Cu" "F.Mask" "F.Paste")
			(net "GND")
		)
		(pad "2" smd circle
			(at 0.40005 0 270)
			(size 0 0)
			(layers "F.Cu" "F.Mask" "F.Paste")
			(net "P3V3_AUX")
		)
	)
	(footprint ""
		(layer "F.Cu")
		(at 15.377922 -196.155056 180)
		(property "Reference" "D138"
			(at 5.344922 -0.982726 0)
			(unlocked yes)
			(layer "F.SilkS")
			(effects
				(font
					(size 0.7874 0.5842)
					(thickness 0.1524)
				)
				(justify left)
			)
		)
		(property "Value" ""
			(at 0 0 180)
			(layer "F.Fab")
			(effects
				(font
					(size 1.27 1.27)
				)
			)
		)
		(duplicate_pad_numbers_are_jumpers no)
		(fp_line
			(start 2.032 0.7112)
			(end -1.651 0.7112)
			(stroke
				(width 0.1524)
				(type default)
			)
			(layer "F.SilkS")
		)
		(fp_line
			(start 2.032 -0.7112)
			(end 2.032 0.7112)
			(stroke
				(width 0.1524)
				(type default)
			)
			(layer "F.SilkS")
		)
		(fp_line
			(start 1.905 -0.6858)
			(end 1.905 0.6858)
			(stroke
				(width 0.1524)
				(type default)
			)
			(layer "F.SilkS")
		)
		(fp_line
			(start 1.778 0.6858)
			(end 1.778 -0.6858)
			(stroke
				(width 0.1524)
				(type default)
			)
			(layer "F.SilkS")
		)
		(fp_line
			(start 1.651 -0.6858)
			(end 1.651 0.6858)
			(stroke
				(width 0.1524)
				(type default)
			)
			(layer "F.SilkS")
		)
		(fp_line
			(start 0.299974 -0.500126)
			(end 0.299974 0.500126)
			(stroke
				(width 0.1524)
				(type default)
			)
			(layer "F.SilkS")
		)
		(fp_line
			(start 0.199898 0)
			(end -0.299974 -0.500126)
			(stroke
				(width 0.1524)
				(type default)
			)
			(layer "F.SilkS")
		)
		(fp_line
			(start -0.299974 0.500126)
			(end 0.199898 0)
			(stroke
				(width 0.1524)
				(type default)
			)
			(layer "F.SilkS")
		)
		(fp_line
			(start -0.299974 -0.500126)
			(end -0.299974 0.500126)
			(stroke
				(width 0.1524)
				(type default)
			)
			(layer "F.SilkS")
		)
		(fp_line
			(start -1.651 0.7112)
			(end -1.651 -0.7112)
			(stroke
				(width 0.1524)
				(type default)
			)
			(layer "F.SilkS")
		)
		(fp_line
			(start -1.651 -0.7112)
			(end 2.032 -0.7112)
			(stroke
				(width 0.1524)
				(type default)
			)
			(layer "F.SilkS")
		)
		(fp_line
			(start 1.35001 0.175006)
			(end 0.899922 0.175006)
			(stroke
				(width 0.1)
				(type default)
			)
			(layer "F.Fab")
		)
		(fp_line
			(start 1.35001 -0.225044)
			(end 1.35001 0.175006)
			(stroke
				(width 0.1)
				(type default)
			)
			(layer "F.Fab")
		)
		(fp_line
			(start 0.899922 0.700024)
			(end -0.899922 0.700024)
			(stroke
				(width 0.1)
				(type default)
			)
			(layer "F.Fab")
		)
		(fp_line
			(start 0.899922 0.175006)
			(end 0.899922 0.700024)
			(stroke
				(width 0.1)
				(type default)
			)
			(layer "F.Fab")
		)
		(fp_line
			(start 0.899922 -0.225044)
			(end 1.35001 -0.225044)
			(stroke
				(width 0.1)
				(type default)
			)
			(layer "F.Fab")
		)
		(fp_line
			(start 0.899922 -0.700024)
			(end 0.899922 -0.225044)
			(stroke
				(width 0.1)
				(type default)
			)
			(layer "F.Fab")
		)
		(fp_line
			(start 0.299974 -0.500126)
			(end 0.299974 0.500126)
			(stroke
				(width 0.1)
				(type default)
			)
			(layer "F.Fab")
		)
		(fp_line
			(start 0.199898 0)
			(end -0.299974 -0.500126)
			(stroke
				(width 0.1)
				(type default)
			)
			(layer "F.Fab")
		)
		(fp_line
			(start -0.299974 0.500126)
			(end 0.199898 0)
			(stroke
				(width 0.1)
				(type default)
			)
			(layer "F.Fab")
		)
		(fp_line
			(start -0.299974 -0.500126)
			(end -0.299974 0.500126)
			(stroke
				(width 0.1)
				(type default)
			)
			(layer "F.Fab")
		)
		(fp_line
			(start -0.899922 0.700024)
			(end -0.899922 0.175006)
			(stroke
				(width 0.1)
				(type default)
			)
			(layer "F.Fab")
		)
		(fp_line
			(start -0.899922 0.175006)
			(end -1.35001 0.175006)
			(stroke
				(width 0.1)
				(type default)
			)
			(layer "F.Fab")
		)
		(fp_line
			(start -0.899922 -0.225044)
			(end -0.899922 -0.700024)
			(stroke
				(width 0.1)
				(type default)
			)
			(layer "F.Fab")
		)
		(fp_line
			(start -0.899922 -0.700024)
			(end 0.899922 -0.700024)
			(stroke
				(width 0.1)
				(type default)
			)
			(layer "F.Fab")
		)
		(fp_line
			(start -1.35001 0.175006)
			(end -1.35001 -0.225044)
			(stroke
				(width 0.1)
				(type default)
			)
			(layer "F.Fab")
		)
		(fp_line
			(start -1.35001 -0.225044)
			(end -0.899922 -0.225044)
			(stroke
				(width 0.1)
				(type default)
			)
			(layer "F.Fab")
		)
		(fp_text user "-"
			(at 0.518922 -1.305306 180)
			(unlocked yes)
			(layer "F.SilkS")
			(effects
				(font
					(size 1.905 1.4224)
					(thickness 0.1524)
				)
				(justify left)
			)
		)
		(fp_text user "+"
			(at -2.656078 -1.178306 180)
			(unlocked yes)
			(layer "F.SilkS")
			(effects
				(font
					(size 1.905 1.4224)
					(thickness 0.1524)
				)
				(justify left)
			)
		)
		(fp_text user "-"
			(at 1.8288 -0.24765 180)
			(unlocked yes)
			(layer "F.Fab")
			(effects
				(font
					(size 1.905 1.4224)
					(thickness 0.1524)
				)
				(justify left)
			)
		)
		(fp_text user "+"
			(at -2.794 -0.19685 180)
			(unlocked yes)
			(layer "F.Fab")
			(effects
				(font
					(size 1.905 1.4224)
					(thickness 0.1524)
				)
				(justify left)
			)
		)
		(pad "1" smd rect
			(at -1.0922 0)
			(size 0.8128 0.8636)
			(layers "F.Cu" "F.Mask" "F.Paste")
			(net "FAN_6_TACH_IL_R")
		)
		(pad "2" smd rect
			(at 1.0922 0 180)
			(size 0.8128 0.8636)
			(layers "F.Cu" "F.Mask" "F.Paste")
			(net "FAN_6_TACH_IL_D")
		)
	)
	(footprint ""
		(layer "F.Cu")
		(at 43.561 -176.911)
		(property "Reference" "R5101"
			(at 0 0 0)
			(layer "F.SilkS")
			(hide yes)
			(effects
				(font
					(size 1.27 1.27)
				)
			)
		)
		(property "Value" ""
			(at 0 0 0)
			(layer "F.Fab")
			(effects
				(font
					(size 1.27 1.27)
				)
			)
		)
		(duplicate_pad_numbers_are_jumpers no)
		(fp_line
			(start -0.7874 -0.4064)
			(end 0.7874 -0.4064)
			(stroke
				(width 0.1524)
				(type default)
			)
			(layer "F.SilkS")
		)
		(fp_line
			(start -0.7874 0.4064)
			(end -0.7874 -0.4064)
			(stroke
				(width 0.1524)
				(type default)
			)
			(layer "F.SilkS")
		)
		(fp_line
			(start 0.7874 -0.4064)
			(end 0.7874 0.4064)
			(stroke
				(width 0.1524)
				(type default)
			)
			(layer "F.SilkS")
		)
		(fp_line
			(start 0.7874 0.4064)
			(end -0.7874 0.4064)
			(stroke
				(width 0.1524)
				(type default)
			)
			(layer "F.SilkS")
		)
		(fp_line
			(start -0.67945 -0.305054)
			(end -0.12065 -0.305054)
			(stroke
				(width 0.1)
				(type default)
			)
			(layer "F.Fab")
		)
		(fp_line
			(start -0.67945 0.3048)
			(end -0.67945 -0.305054)
			(stroke
				(width 0.1)
				(type default)
			)
			(layer "F.Fab")
		)
		(fp_line
			(start -0.12065 -0.305054)
			(end -0.12065 -0.2794)
			(stroke
				(width 0.1)
				(type default)
			)
			(layer "F.Fab")
		)
		(fp_line
			(start -0.12065 -0.2794)
			(end 0.12065 -0.2794)
			(stroke
				(width 0.1)
				(type default)
			)
			(layer "F.Fab")
		)
		(fp_line
			(start -0.12065 0.2794)
			(end -0.12065 0.3048)
			(stroke
				(width 0.1)
				(type default)
			)
			(layer "F.Fab")
		)
		(fp_line
			(start -0.12065 0.3048)
			(end -0.67945 0.3048)
			(stroke
				(width 0.1)
				(type default)
			)
			(layer "F.Fab")
		)
		(fp_line
			(start 0.120396 0.2794)
			(end -0.12065 0.2794)
			(stroke
				(width 0.1)
				(type default)
			)
			(layer "F.Fab")
		)
		(fp_line
			(start 0.120396 0.3048)
			(end 0.120396 0.2794)
			(stroke
				(width 0.1)
				(type default)
			)
			(layer "F.Fab")
		)
		(fp_line
			(start 0.12065 -0.3048)
			(end 0.67945 -0.3048)
			(stroke
				(width 0.1)
				(type default)
			)
			(layer "F.Fab")
		)
		(fp_line
			(start 0.12065 -0.2794)
			(end 0.12065 -0.3048)
			(stroke
				(width 0.1)
				(type default)
			)
			(layer "F.Fab")
		)
		(fp_line
			(start 0.67945 -0.3048)
			(end 0.67945 0.3048)
			(stroke
				(width 0.1)
				(type default)
			)
			(layer "F.Fab")
		)
		(fp_line
			(start 0.67945 0.3048)
			(end 0.120396 0.3048)
			(stroke
				(width 0.1)
				(type default)
			)
			(layer "F.Fab")
		)
		(pad "1" smd circle
			(at -0.40005 0)
			(size 0 0)
			(layers "F.Cu" "F.Mask" "F.Paste")
			(net "FAN_3_FAIL_LED")
		)
		(pad "2" smd circle
			(at 0.40005 0)
			(size 0 0)
			(layers "F.Cu" "F.Mask" "F.Paste")
			(net "FAN_3_FAIL_R_LED")
		)
	)
	(footprint ""
		(layer "F.Cu")
		(at 25.527 -133.858)
		(property "Reference" "R5680"
			(at 0 0 0)
			(layer "F.SilkS")
			(hide yes)
			(effects
				(font
					(size 1.27 1.27)
				)
			)
		)
		(property "Value" ""
			(at 0 0 0)
			(layer "F.Fab")
			(effects
				(font
					(size 1.27 1.27)
				)
			)
		)
		(duplicate_pad_numbers_are_jumpers no)
		(fp_line
			(start -0.7874 -0.4064)
			(end 0.7874 -0.4064)
			(stroke
				(width 0.1524)
				(type default)
			)
			(layer "F.SilkS")
		)
		(fp_line
			(start -0.7874 0.4064)
			(end -0.7874 -0.4064)
			(stroke
				(width 0.1524)
				(type default)
			)
			(layer "F.SilkS")
		)
		(fp_line
			(start 0.7874 -0.4064)
			(end 0.7874 0.4064)
			(stroke
				(width 0.1524)
				(type default)
			)
			(layer "F.SilkS")
		)
		(fp_line
			(start 0.7874 0.4064)
			(end -0.7874 0.4064)
			(stroke
				(width 0.1524)
				(type default)
			)
			(layer "F.SilkS")
		)
		(fp_line
			(start -0.67945 -0.305054)
			(end -0.12065 -0.305054)
			(stroke
				(width 0.1)
				(type default)
			)
			(layer "F.Fab")
		)
		(fp_line
			(start -0.67945 0.3048)
			(end -0.67945 -0.305054)
			(stroke
				(width 0.1)
				(type default)
			)
			(layer "F.Fab")
		)
		(fp_line
			(start -0.12065 -0.305054)
			(end -0.12065 -0.2794)
			(stroke
				(width 0.1)
				(type default)
			)
			(layer "F.Fab")
		)
		(fp_line
			(start -0.12065 -0.2794)
			(end 0.12065 -0.2794)
			(stroke
				(width 0.1)
				(type default)
			)
			(layer "F.Fab")
		)
		(fp_line
			(start -0.12065 0.2794)
			(end -0.12065 0.3048)
			(stroke
				(width 0.1)
				(type default)
			)
			(layer "F.Fab")
		)
		(fp_line
			(start -0.12065 0.3048)
			(end -0.67945 0.3048)
			(stroke
				(width 0.1)
				(type default)
			)
			(layer "F.Fab")
		)
		(fp_line
			(start 0.120396 0.2794)
			(end -0.12065 0.2794)
			(stroke
				(width 0.1)
				(type default)
			)
			(layer "F.Fab")
		)
		(fp_line
			(start 0.120396 0.3048)
			(end 0.120396 0.2794)
			(stroke
				(width 0.1)
				(type default)
			)
			(layer "F.Fab")
		)
		(fp_line
			(start 0.12065 -0.3048)
			(end 0.67945 -0.3048)
			(stroke
				(width 0.1)
				(type default)
			)
			(layer "F.Fab")
		)
		(fp_line
			(start 0.12065 -0.2794)
			(end 0.12065 -0.3048)
			(stroke
				(width 0.1)
				(type default)
			)
			(layer "F.Fab")
		)
		(fp_line
			(start 0.67945 -0.3048)
			(end 0.67945 0.3048)
			(stroke
				(width 0.1)
				(type default)
			)
			(layer "F.Fab")
		)
		(fp_line
			(start 0.67945 0.3048)
			(end 0.120396 0.3048)
			(stroke
				(width 0.1)
				(type default)
			)
			(layer "F.Fab")
		)
		(pad "1" smd rect
			(at -0.40005 0 180)
			(size 0.4572 0.508)
			(layers "F.Cu" "F.Mask" "F.Paste")
			(net "U330_FAN FS_N")
		)
		(pad "2" smd rect
			(at 0.40005 0 180)
			(size 0.4572 0.508)
			(layers "F.Cu" "F.Mask" "F.Paste")
			(net "U330_FAN FAIL_N")
		)
	)
	(footprint ""
		(layer "F.Cu")
		(at 17.399 -211.836 180)
		(property "Reference" "R5319"
			(at 0 0 180)
			(layer "F.SilkS")
			(hide yes)
			(effects
				(font
					(size 1.27 1.27)
				)
			)
		)
		(property "Value" ""
			(at 0 0 180)
			(layer "F.Fab")
			(effects
				(font
					(size 1.27 1.27)
				)
			)
		)
		(duplicate_pad_numbers_are_jumpers no)
		(fp_line
			(start 0.7874 0.4064)
			(end -0.7874 0.4064)
			(stroke
				(width 0.1524)
				(type default)
			)
			(layer "F.SilkS")
		)
		(fp_line
			(start 0.7874 -0.4064)
			(end 0.7874 0.4064)
			(stroke
				(width 0.1524)
				(type default)
			)
			(layer "F.SilkS")
		)
		(fp_line
			(start -0.7874 0.4064)
			(end -0.7874 -0.4064)
			(stroke
				(width 0.1524)
				(type default)
			)
			(layer "F.SilkS")
		)
		(fp_line
			(start -0.7874 -0.4064)
			(end 0.7874 -0.4064)
			(stroke
				(width 0.1524)
				(type default)
			)
			(layer "F.SilkS")
		)
		(fp_line
			(start 0.67945 0.3048)
			(end 0.120396 0.3048)
			(stroke
				(width 0.1)
				(type default)
			)
			(layer "F.Fab")
		)
		(fp_line
			(start 0.67945 -0.3048)
			(end 0.67945 0.3048)
			(stroke
				(width 0.1)
				(type default)
			)
			(layer "F.Fab")
		)
		(fp_line
			(start 0.12065 -0.2794)
			(end 0.12065 -0.3048)
			(stroke
				(width 0.1)
				(type default)
			)
			(layer "F.Fab")
		)
		(fp_line
			(start 0.12065 -0.3048)
			(end 0.67945 -0.3048)
			(stroke
				(width 0.1)
				(type default)
			)
			(layer "F.Fab")
		)
		(fp_line
			(start 0.120396 0.3048)
			(end 0.120396 0.2794)
			(stroke
				(width 0.1)
				(type default)
			)
			(layer "F.Fab")
		)
		(fp_line
			(start 0.120396 0.2794)
			(end -0.12065 0.2794)
			(stroke
				(width 0.1)
				(type default)
			)
			(layer "F.Fab")
		)
		(fp_line
			(start -0.12065 0.3048)
			(end -0.67945 0.3048)
			(stroke
				(width 0.1)
				(type default)
			)
			(layer "F.Fab")
		)
		(fp_line
			(start -0.12065 0.2794)
			(end -0.12065 0.3048)
			(stroke
				(width 0.1)
				(type default)
			)
			(layer "F.Fab")
		)
		(fp_line
			(start -0.12065 -0.2794)
			(end 0.12065 -0.2794)
			(stroke
				(width 0.1)
				(type default)
			)
			(layer "F.Fab")
		)
		(fp_line
			(start -0.12065 -0.305054)
			(end -0.12065 -0.2794)
			(stroke
				(width 0.1)
				(type default)
			)
			(layer "F.Fab")
		)
		(fp_line
			(start -0.67945 0.3048)
			(end -0.67945 -0.305054)
			(stroke
				(width 0.1)
				(type default)
			)
			(layer "F.Fab")
		)
		(fp_line
			(start -0.67945 -0.305054)
			(end -0.12065 -0.305054)
			(stroke
				(width 0.1)
				(type default)
			)
			(layer "F.Fab")
		)
		(pad "1" smd rect
			(at -0.40005 0)
			(size 0.4572 0.508)
			(layers "F.Cu" "F.Mask" "F.Paste")
			(net "FAN_6_TACH_OL_R")
		)
		(pad "2" smd rect
			(at 0.40005 0)
			(size 0.4572 0.508)
			(layers "F.Cu" "F.Mask" "F.Paste")
			(net "FAN_6_TACH_OL")
		)
	)
	(footprint ""
		(layer "F.Cu")
		(at 9.906 -166.878 180)
		(property "Reference" "U24"
			(at 2.00533 -1.016 90)
			(unlocked yes)
			(layer "F.SilkS")
			(effects
				(font
					(size 0.7874 0.5842)
					(thickness 0.1524)
				)
				(justify left)
			)
		)
		(property "Value" ""
			(at 0 0 180)
			(layer "F.Fab")
			(effects
				(font
					(size 1.27 1.27)
				)
			)
		)
		(duplicate_pad_numbers_are_jumpers no)
		(fp_line
			(start 1.3462 1.100074)
			(end -1.3462 1.100074)
			(stroke
				(width 0.1524)
				(type default)
			)
			(layer "F.SilkS")
		)
		(fp_line
			(start 1.3462 -1.100074)
			(end 1.3462 1.100074)
			(stroke
				(width 0.1524)
				(type default)
			)
			(layer "F.SilkS")
		)
		(fp_line
			(start 0.670052 -1.100074)
			(end 1.3462 -1.100074)
			(stroke
				(width 0.1524)
				(type default)
			)
			(layer "F.SilkS")
		)
		(fp_line
			(start 0 -0.381)
			(end 0.670052 -1.100074)
			(stroke
				(width 0.1524)
				(type default)
			)
			(layer "F.SilkS")
		)
		(fp_line
			(start -0.670052 -1.100074)
			(end 0 -0.381)
			(stroke
				(width 0.1524)
				(type default)
			)
			(layer "F.SilkS")
		)
		(fp_line
			(start -1.3462 1.100074)
			(end -1.3462 -1.100074)
			(stroke
				(width 0.1524)
				(type default)
			)
			(layer "F.SilkS")
		)
		(fp_line
			(start -1.3462 -1.100074)
			(end -0.670052 -1.100074)
			(stroke
				(width 0.1524)
				(type default)
			)
			(layer "F.SilkS")
		)
		(fp_poly
			(pts
				(xy -1.524 -0.649986) (xy -2.286 -1.030986) (xy -2.286 -0.268986)
			)
			(stroke
				(width 0)
				(type default)
			)
			(fill yes)
			(layer "F.SilkS")
		)
		(fp_line
			(start 1.100074 0.8001)
			(end 0.670052 0.8001)
			(stroke
				(width 0.1)
				(type default)
			)
			(layer "F.Fab")
		)
		(fp_line
			(start 1.100074 -0.8001)
			(end 1.100074 0.8001)
			(stroke
				(width 0.1)
				(type default)
			)
			(layer "F.Fab")
		)
		(fp_line
			(start 0.670052 1.100074)
			(end -0.670052 1.100074)
			(stroke
				(width 0.1)
				(type default)
			)
			(layer "F.Fab")
		)
		(fp_line
			(start 0.670052 0.8001)
			(end 0.670052 1.100074)
			(stroke
				(width 0.1)
				(type default)
			)
			(layer "F.Fab")
		)
		(fp_line
			(start 0.670052 -0.8001)
			(end 1.100074 -0.8001)
			(stroke
				(width 0.1)
				(type default)
			)
			(layer "F.Fab")
		)
		(fp_line
			(start 0.670052 -0.8001)
			(end 0.670052 0.8001)
			(stroke
				(width 0.1)
				(type default)
			)
			(layer "F.Fab")
		)
		(fp_line
			(start 0.670052 -1.100074)
			(end 0.670052 -0.8001)
			(stroke
				(width 0.1)
				(type default)
			)
			(layer "F.Fab")
		)
		(fp_line
			(start -0.670052 1.100074)
			(end -0.670052 0.8001)
			(stroke
				(width 0.1)
				(type default)
			)
			(layer "F.Fab")
		)
		(fp_line
			(start -0.670052 0.8001)
			(end -0.670052 -0.8001)
			(stroke
				(width 0.1)
				(type default)
			)
			(layer "F.Fab")
		)
		(fp_line
			(start -0.670052 0.8001)
			(end -1.100074 0.8001)
			(stroke
				(width 0.1)
				(type default)
			)
			(layer "F.Fab")
		)
		(fp_line
			(start -0.670052 -0.8001)
			(end -0.670052 -1.100074)
			(stroke
				(width 0.1)
				(type default)
			)
			(layer "F.Fab")
		)
		(fp_line
			(start -0.670052 -1.100074)
			(end 0.670052 -1.100074)
			(stroke
				(width 0.1)
				(type default)
			)
			(layer "F.Fab")
		)
		(fp_line
			(start -1.100074 0.8001)
			(end -1.100074 -0.8001)
			(stroke
				(width 0.1)
				(type default)
			)
			(layer "F.Fab")
		)
		(fp_line
			(start -1.100074 -0.8001)
			(end -0.670052 -0.8001)
			(stroke
				(width 0.1)
				(type default)
			)
			(layer "F.Fab")
		)
		(fp_poly
			(pts
				(xy -1.524 -0.649986) (xy -2.286 -1.030986) (xy -2.286 -0.268986)
			)
			(stroke
				(width 0)
				(type default)
			)
			(fill yes)
			(layer "F.Fab")
		)
		(pad "1" smd rect
			(at -0.94996 -0.649986 90)
			(size 0.4064 0.508)
			(layers "F.Cu" "F.Mask" "F.Paste")
			(net "FAN_2_PRESENT_N")
		)
		(pad "2" smd rect
			(at -0.94996 0 90)
			(size 0.4064 0.508)
			(layers "F.Cu" "F.Mask" "F.Paste")
			(net "GND")
		)
		(pad "3" smd rect
			(at -0.94996 0.649986 90)
			(size 0.4064 0.508)
			(layers "F.Cu" "F.Mask" "F.Paste")
			(net "FAN_3_PRESENT_N")
		)
		(pad "4" smd rect
			(at 0.94996 0.649986 90)
			(size 0.4064 0.508)
			(layers "F.Cu" "F.Mask" "F.Paste")
			(net "FAN_3_PRSNT_BUF_R_N")
		)
		(pad "5" smd rect
			(at 0.94996 0 90)
			(size 0.4064 0.508)
			(layers "F.Cu" "F.Mask" "F.Paste")
			(net "P3V3_AUX")
		)
		(pad "6" smd rect
			(at 0.94996 -0.649986 90)
			(size 0.4064 0.508)
			(layers "F.Cu" "F.Mask" "F.Paste")
			(net "FAN_2_PRSNT_BUF_R_N")
		)
	)
	(footprint ""
		(layer "F.Cu")
		(at 28.829 -124.206 -90)
		(property "Reference" "R4939"
			(at 0 0 270)
			(layer "F.SilkS")
			(hide yes)
			(effects
				(font
					(size 1.27 1.27)
				)
			)
		)
		(property "Value" ""
			(at 0 0 270)
			(layer "F.Fab")
			(effects
				(font
					(size 1.27 1.27)
				)
			)
		)
		(duplicate_pad_numbers_are_jumpers no)
		(fp_line
			(start -0.7874 0.4064)
			(end -0.7874 -0.4064)
			(stroke
				(width 0.1524)
				(type default)
			)
			(layer "F.SilkS")
		)
		(fp_line
			(start 0.7874 0.4064)
			(end -0.7874 0.4064)
			(stroke
				(width 0.1524)
				(type default)
			)
			(layer "F.SilkS")
		)
		(fp_line
			(start -0.7874 -0.4064)
			(end 0.7874 -0.4064)
			(stroke
				(width 0.1524)
				(type default)
			)
			(layer "F.SilkS")
		)
		(fp_line
			(start 0.7874 -0.4064)
			(end 0.7874 0.4064)
			(stroke
				(width 0.1524)
				(type default)
			)
			(layer "F.SilkS")
		)
		(fp_line
			(start -0.67945 0.3048)
			(end -0.67945 -0.305054)
			(stroke
				(width 0.1)
				(type default)
			)
			(layer "F.Fab")
		)
		(fp_line
			(start -0.12065 0.3048)
			(end -0.67945 0.3048)
			(stroke
				(width 0.1)
				(type default)
			)
			(layer "F.Fab")
		)
		(fp_line
			(start 0.120396 0.3048)
			(end 0.120396 0.2794)
			(stroke
				(width 0.1)
				(type default)
			)
			(layer "F.Fab")
		)
		(fp_line
			(start 0.67945 0.3048)
			(end 0.120396 0.3048)
			(stroke
				(width 0.1)
				(type default)
			)
			(layer "F.Fab")
		)
		(fp_line
			(start -0.12065 0.2794)
			(end -0.12065 0.3048)
			(stroke
				(width 0.1)
				(type default)
			)
			(layer "F.Fab")
		)
		(fp_line
			(start 0.120396 0.2794)
			(end -0.12065 0.2794)
			(stroke
				(width 0.1)
				(type default)
			)
			(layer "F.Fab")
		)
		(fp_line
			(start -0.12065 -0.2794)
			(end 0.12065 -0.2794)
			(stroke
				(width 0.1)
				(type default)
			)
			(layer "F.Fab")
		)
		(fp_line
			(start 0.12065 -0.2794)
			(end 0.12065 -0.3048)
			(stroke
				(width 0.1)
				(type default)
			)
			(layer "F.Fab")
		)
		(fp_line
			(start 0.12065 -0.3048)
			(end 0.67945 -0.3048)
			(stroke
				(width 0.1)
				(type default)
			)
			(layer "F.Fab")
		)
		(fp_line
			(start 0.67945 -0.3048)
			(end 0.67945 0.3048)
			(stroke
				(width 0.1)
				(type default)
			)
			(layer "F.Fab")
		)
		(fp_line
			(start -0.67945 -0.305054)
			(end -0.12065 -0.305054)
			(stroke
				(width 0.1)
				(type default)
			)
			(layer "F.Fab")
		)
		(fp_line
			(start -0.12065 -0.305054)
			(end -0.12065 -0.2794)
			(stroke
				(width 0.1)
				(type default)
			)
			(layer "F.Fab")
		)
		(pad "1" smd circle
			(at -0.40005 0 270)
			(size 0 0)
			(layers "F.Cu" "F.Mask" "F.Paste")
			(net "MAX31790_U317_FREQ_START")
		)
		(pad "2" smd circle
			(at 0.40005 0 270)
			(size 0 0)
			(layers "F.Cu" "F.Mask" "F.Paste")
			(net "P3V3_AUX")
		)
	)
	(footprint ""
		(layer "F.Cu")
		(at 17.272 -146.05 90)
		(property "Reference" "R5523"
			(at 0 0 90)
			(layer "F.SilkS")
			(hide yes)
			(effects
				(font
					(size 1.27 1.27)
				)
			)
		)
		(property "Value" ""
			(at 0 0 90)
			(layer "F.Fab")
			(effects
				(font
					(size 1.27 1.27)
				)
			)
		)
		(duplicate_pad_numbers_are_jumpers no)
		(fp_line
			(start 0.7874 -0.4064)
			(end 0.7874 0.4064)
			(stroke
				(width 0.1524)
				(type default)
			)
			(layer "F.SilkS")
		)
		(fp_line
			(start -0.7874 -0.4064)
			(end 0.7874 -0.4064)
			(stroke
				(width 0.1524)
				(type default)
			)
			(layer "F.SilkS")
		)
		(fp_line
			(start 0.7874 0.4064)
			(end -0.7874 0.4064)
			(stroke
				(width 0.1524)
				(type default)
			)
			(layer "F.SilkS")
		)
		(fp_line
			(start -0.7874 0.4064)
			(end -0.7874 -0.4064)
			(stroke
				(width 0.1524)
				(type default)
			)
			(layer "F.SilkS")
		)
		(fp_line
			(start -0.12065 -0.305054)
			(end -0.12065 -0.2794)
			(stroke
				(width 0.1)
				(type default)
			)
			(layer "F.Fab")
		)
		(fp_line
			(start -0.67945 -0.305054)
			(end -0.12065 -0.305054)
			(stroke
				(width 0.1)
				(type default)
			)
			(layer "F.Fab")
		)
		(fp_line
			(start 0.67945 -0.3048)
			(end 0.67945 0.3048)
			(stroke
				(width 0.1)
				(type default)
			)
			(layer "F.Fab")
		)
		(fp_line
			(start 0.12065 -0.3048)
			(end 0.67945 -0.3048)
			(stroke
				(width 0.1)
				(type default)
			)
			(layer "F.Fab")
		)
		(fp_line
			(start 0.12065 -0.2794)
			(end 0.12065 -0.3048)
			(stroke
				(width 0.1)
				(type default)
			)
			(layer "F.Fab")
		)
		(fp_line
			(start -0.12065 -0.2794)
			(end 0.12065 -0.2794)
			(stroke
				(width 0.1)
				(type default)
			)
			(layer "F.Fab")
		)
		(fp_line
			(start 0.120396 0.2794)
			(end -0.12065 0.2794)
			(stroke
				(width 0.1)
				(type default)
			)
			(layer "F.Fab")
		)
		(fp_line
			(start -0.12065 0.2794)
			(end -0.12065 0.3048)
			(stroke
				(width 0.1)
				(type default)
			)
			(layer "F.Fab")
		)
		(fp_line
			(start 0.67945 0.3048)
			(end 0.120396 0.3048)
			(stroke
				(width 0.1)
				(type default)
			)
			(layer "F.Fab")
		)
		(fp_line
			(start 0.120396 0.3048)
			(end 0.120396 0.2794)
			(stroke
				(width 0.1)
				(type default)
			)
			(layer "F.Fab")
		)
		(fp_line
			(start -0.12065 0.3048)
			(end -0.67945 0.3048)
			(stroke
				(width 0.1)
				(type default)
			)
			(layer "F.Fab")
		)
		(fp_line
			(start -0.67945 0.3048)
			(end -0.67945 -0.305054)
			(stroke
				(width 0.1)
				(type default)
			)
			(layer "F.Fab")
		)
		(pad "1" smd circle
			(at -0.40005 0 90)
			(size 0 0)
			(layers "F.Cu" "F.Mask" "F.Paste")
			(net "P3V3_AUX")
		)
		(pad "2" smd circle
			(at 0.40005 0 90)
			(size 0 0)
			(layers "F.Cu" "F.Mask" "F.Paste")
			(net "PD_TCA9548_SML1_U321_A0")
		)
	)
	(footprint ""
		(layer "F.Cu")
		(at 35.179 -300.228 90)
		(property "Reference" "C2021"
			(at 0 0 90)
			(layer "F.SilkS")
			(hide yes)
			(effects
				(font
					(size 1.27 1.27)
				)
			)
		)
		(property "Value" ""
			(at 0 0 90)
			(layer "F.Fab")
			(effects
				(font
					(size 1.27 1.27)
				)
			)
		)
		(duplicate_pad_numbers_are_jumpers no)
		(fp_line
			(start 0.7874 -0.4064)
			(end 0.7874 0.4064)
			(stroke
				(width 0.1524)
				(type default)
			)
			(layer "F.SilkS")
		)
		(fp_line
			(start -0.7874 -0.4064)
			(end 0.7874 -0.4064)
			(stroke
				(width 0.1524)
				(type default)
			)
			(layer "F.SilkS")
		)
		(fp_line
			(start 0.7874 0.4064)
			(end -0.7874 0.4064)
			(stroke
				(width 0.1524)
				(type default)
			)
			(layer "F.SilkS")
		)
		(fp_line
			(start -0.7874 0.4064)
			(end -0.7874 -0.4064)
			(stroke
				(width 0.1524)
				(type default)
			)
			(layer "F.SilkS")
		)
		(fp_line
			(start -0.12065 -0.305054)
			(end -0.12065 -0.2794)
			(stroke
				(width 0.1)
				(type default)
			)
			(layer "F.Fab")
		)
		(fp_line
			(start -0.67945 -0.305054)
			(end -0.12065 -0.305054)
			(stroke
				(width 0.1)
				(type default)
			)
			(layer "F.Fab")
		)
		(fp_line
			(start 0.67945 -0.3048)
			(end 0.67945 0.3048)
			(stroke
				(width 0.1)
				(type default)
			)
			(layer "F.Fab")
		)
		(fp_line
			(start 0.12065 -0.3048)
			(end 0.67945 -0.3048)
			(stroke
				(width 0.1)
				(type default)
			)
			(layer "F.Fab")
		)
		(fp_line
			(start 0.12065 -0.2794)
			(end 0.12065 -0.3048)
			(stroke
				(width 0.1)
				(type default)
			)
			(layer "F.Fab")
		)
		(fp_line
			(start -0.12065 -0.2794)
			(end 0.12065 -0.2794)
			(stroke
				(width 0.1)
				(type default)
			)
			(layer "F.Fab")
		)
		(fp_line
			(start 0.120396 0.2794)
			(end -0.12065 0.2794)
			(stroke
				(width 0.1)
				(type default)
			)
			(layer "F.Fab")
		)
		(fp_line
			(start -0.12065 0.2794)
			(end -0.12065 0.3048)
			(stroke
				(width 0.1)
				(type default)
			)
			(layer "F.Fab")
		)
		(fp_line
			(start 0.67945 0.3048)
			(end 0.120396 0.3048)
			(stroke
				(width 0.1)
				(type default)
			)
			(layer "F.Fab")
		)
		(fp_line
			(start 0.120396 0.3048)
			(end 0.120396 0.2794)
			(stroke
				(width 0.1)
				(type default)
			)
			(layer "F.Fab")
		)
		(fp_line
			(start -0.12065 0.3048)
			(end -0.67945 0.3048)
			(stroke
				(width 0.1)
				(type default)
			)
			(layer "F.Fab")
		)
		(fp_line
			(start -0.67945 0.3048)
			(end -0.67945 -0.305054)
			(stroke
				(width 0.1)
				(type default)
			)
			(layer "F.Fab")
		)
		(pad "1" smd circle
			(at -0.40005 0 90)
			(size 0 0)
			(layers "F.Cu" "F.Mask" "F.Paste")
			(net "FAN_0_PWM_IL_R")
		)
		(pad "2" smd circle
			(at 0.40005 0 90)
			(size 0 0)
			(layers "F.Cu" "F.Mask" "F.Paste")
			(net "GND")
		)
	)
	(footprint ""
		(layer "F.Cu")
		(at 42.635932 -256.667)
		(property "Reference" "R5416"
			(at 0 0 0)
			(layer "F.SilkS")
			(hide yes)
			(effects
				(font
					(size 1.27 1.27)
				)
			)
		)
		(property "Value" ""
			(at 0 0 0)
			(layer "F.Fab")
			(effects
				(font
					(size 1.27 1.27)
				)
			)
		)
		(duplicate_pad_numbers_are_jumpers no)
		(fp_line
			(start -0.7874 -0.4064)
			(end 0.7874 -0.4064)
			(stroke
				(width 0.1524)
				(type default)
			)
			(layer "F.SilkS")
		)
		(fp_line
			(start -0.7874 0.4064)
			(end -0.7874 -0.4064)
			(stroke
				(width 0.1524)
				(type default)
			)
			(layer "F.SilkS")
		)
		(fp_line
			(start 0.7874 -0.4064)
			(end 0.7874 0.4064)
			(stroke
				(width 0.1524)
				(type default)
			)
			(layer "F.SilkS")
		)
		(fp_line
			(start 0.7874 0.4064)
			(end -0.7874 0.4064)
			(stroke
				(width 0.1524)
				(type default)
			)
			(layer "F.SilkS")
		)
		(fp_line
			(start -0.67945 -0.305054)
			(end -0.12065 -0.305054)
			(stroke
				(width 0.1)
				(type default)
			)
			(layer "F.Fab")
		)
		(fp_line
			(start -0.67945 0.3048)
			(end -0.67945 -0.305054)
			(stroke
				(width 0.1)
				(type default)
			)
			(layer "F.Fab")
		)
		(fp_line
			(start -0.12065 -0.305054)
			(end -0.12065 -0.2794)
			(stroke
				(width 0.1)
				(type default)
			)
			(layer "F.Fab")
		)
		(fp_line
			(start -0.12065 -0.2794)
			(end 0.12065 -0.2794)
			(stroke
				(width 0.1)
				(type default)
			)
			(layer "F.Fab")
		)
		(fp_line
			(start -0.12065 0.2794)
			(end -0.12065 0.3048)
			(stroke
				(width 0.1)
				(type default)
			)
			(layer "F.Fab")
		)
		(fp_line
			(start -0.12065 0.3048)
			(end -0.67945 0.3048)
			(stroke
				(width 0.1)
				(type default)
			)
			(layer "F.Fab")
		)
		(fp_line
			(start 0.120396 0.2794)
			(end -0.12065 0.2794)
			(stroke
				(width 0.1)
				(type default)
			)
			(layer "F.Fab")
		)
		(fp_line
			(start 0.120396 0.3048)
			(end 0.120396 0.2794)
			(stroke
				(width 0.1)
				(type default)
			)
			(layer "F.Fab")
		)
		(fp_line
			(start 0.12065 -0.3048)
			(end 0.67945 -0.3048)
			(stroke
				(width 0.1)
				(type default)
			)
			(layer "F.Fab")
		)
		(fp_line
			(start 0.12065 -0.2794)
			(end 0.12065 -0.3048)
			(stroke
				(width 0.1)
				(type default)
			)
			(layer "F.Fab")
		)
		(fp_line
			(start 0.67945 -0.3048)
			(end 0.67945 0.3048)
			(stroke
				(width 0.1)
				(type default)
			)
			(layer "F.Fab")
		)
		(fp_line
			(start 0.67945 0.3048)
			(end 0.120396 0.3048)
			(stroke
				(width 0.1)
				(type default)
			)
			(layer "F.Fab")
		)
		(pad "1" smd circle
			(at -0.40005 0)
			(size 0 0)
			(layers "F.Cu" "F.Mask" "F.Paste")
			(net "FAN_0_PRESENT_R")
		)
		(pad "2" smd circle
			(at 0.40005 0)
			(size 0 0)
			(layers "F.Cu" "F.Mask" "F.Paste")
			(net "FAN_0_PRESENT")
		)
	)
	(footprint ""
		(layer "F.Cu")
		(at 17.907 -169.291 180)
		(property "Reference" "R5499"
			(at 0 0 180)
			(layer "F.SilkS")
			(hide yes)
			(effects
				(font
					(size 1.27 1.27)
				)
			)
		)
		(property "Value" ""
			(at 0 0 180)
			(layer "F.Fab")
			(effects
				(font
					(size 1.27 1.27)
				)
			)
		)
		(duplicate_pad_numbers_are_jumpers no)
		(fp_line
			(start 0.7874 0.4064)
			(end -0.7874 0.4064)
			(stroke
				(width 0.1524)
				(type default)
			)
			(layer "F.SilkS")
		)
		(fp_line
			(start 0.7874 -0.4064)
			(end 0.7874 0.4064)
			(stroke
				(width 0.1524)
				(type default)
			)
			(layer "F.SilkS")
		)
		(fp_line
			(start -0.7874 0.4064)
			(end -0.7874 -0.4064)
			(stroke
				(width 0.1524)
				(type default)
			)
			(layer "F.SilkS")
		)
		(fp_line
			(start -0.7874 -0.4064)
			(end 0.7874 -0.4064)
			(stroke
				(width 0.1524)
				(type default)
			)
			(layer "F.SilkS")
		)
		(fp_line
			(start 0.67945 0.3048)
			(end 0.120396 0.3048)
			(stroke
				(width 0.1)
				(type default)
			)
			(layer "F.Fab")
		)
		(fp_line
			(start 0.67945 -0.3048)
			(end 0.67945 0.3048)
			(stroke
				(width 0.1)
				(type default)
			)
			(layer "F.Fab")
		)
		(fp_line
			(start 0.12065 -0.2794)
			(end 0.12065 -0.3048)
			(stroke
				(width 0.1)
				(type default)
			)
			(layer "F.Fab")
		)
		(fp_line
			(start 0.12065 -0.3048)
			(end 0.67945 -0.3048)
			(stroke
				(width 0.1)
				(type default)
			)
			(layer "F.Fab")
		)
		(fp_line
			(start 0.120396 0.3048)
			(end 0.120396 0.2794)
			(stroke
				(width 0.1)
				(type default)
			)
			(layer "F.Fab")
		)
		(fp_line
			(start 0.120396 0.2794)
			(end -0.12065 0.2794)
			(stroke
				(width 0.1)
				(type default)
			)
			(layer "F.Fab")
		)
		(fp_line
			(start -0.12065 0.3048)
			(end -0.67945 0.3048)
			(stroke
				(width 0.1)
				(type default)
			)
			(layer "F.Fab")
		)
		(fp_line
			(start -0.12065 0.2794)
			(end -0.12065 0.3048)
			(stroke
				(width 0.1)
				(type default)
			)
			(layer "F.Fab")
		)
		(fp_line
			(start -0.12065 -0.2794)
			(end 0.12065 -0.2794)
			(stroke
				(width 0.1)
				(type default)
			)
			(layer "F.Fab")
		)
		(fp_line
			(start -0.12065 -0.305054)
			(end -0.12065 -0.2794)
			(stroke
				(width 0.1)
				(type default)
			)
			(layer "F.Fab")
		)
		(fp_line
			(start -0.67945 0.3048)
			(end -0.67945 -0.305054)
			(stroke
				(width 0.1)
				(type default)
			)
			(layer "F.Fab")
		)
		(fp_line
			(start -0.67945 -0.305054)
			(end -0.12065 -0.305054)
			(stroke
				(width 0.1)
				(type default)
			)
			(layer "F.Fab")
		)
		(pad "1" smd circle
			(at -0.40005 0 180)
			(size 0 0)
			(layers "F.Cu" "F.Mask" "F.Paste")
			(net "FAN_4_PRESENT_R_N")
		)
		(pad "2" smd circle
			(at 0.40005 0 180)
			(size 0 0)
			(layers "F.Cu" "F.Mask" "F.Paste")
			(net "FAN_4_PRESENT_N")
		)
	)
	(footprint ""
		(layer "F.Cu")
		(at 19.558 -207.01 -90)
		(property "Reference" "R5371"
			(at 0 0 270)
			(layer "F.SilkS")
			(hide yes)
			(effects
				(font
					(size 1.27 1.27)
				)
			)
		)
		(property "Value" ""
			(at 0 0 270)
			(layer "F.Fab")
			(effects
				(font
					(size 1.27 1.27)
				)
			)
		)
		(duplicate_pad_numbers_are_jumpers no)
		(fp_line
			(start -0.7874 0.4064)
			(end -0.7874 -0.4064)
			(stroke
				(width 0.1524)
				(type default)
			)
			(layer "F.SilkS")
		)
		(fp_line
			(start 0.7874 0.4064)
			(end -0.7874 0.4064)
			(stroke
				(width 0.1524)
				(type default)
			)
			(layer "F.SilkS")
		)
		(fp_line
			(start -0.7874 -0.4064)
			(end 0.7874 -0.4064)
			(stroke
				(width 0.1524)
				(type default)
			)
			(layer "F.SilkS")
		)
		(fp_line
			(start 0.7874 -0.4064)
			(end 0.7874 0.4064)
			(stroke
				(width 0.1524)
				(type default)
			)
			(layer "F.SilkS")
		)
		(fp_line
			(start -0.67945 0.3048)
			(end -0.67945 -0.305054)
			(stroke
				(width 0.1)
				(type default)
			)
			(layer "F.Fab")
		)
		(fp_line
			(start -0.12065 0.3048)
			(end -0.67945 0.3048)
			(stroke
				(width 0.1)
				(type default)
			)
			(layer "F.Fab")
		)
		(fp_line
			(start 0.120396 0.3048)
			(end 0.120396 0.2794)
			(stroke
				(width 0.1)
				(type default)
			)
			(layer "F.Fab")
		)
		(fp_line
			(start 0.67945 0.3048)
			(end 0.120396 0.3048)
			(stroke
				(width 0.1)
				(type default)
			)
			(layer "F.Fab")
		)
		(fp_line
			(start -0.12065 0.2794)
			(end -0.12065 0.3048)
			(stroke
				(width 0.1)
				(type default)
			)
			(layer "F.Fab")
		)
		(fp_line
			(start 0.120396 0.2794)
			(end -0.12065 0.2794)
			(stroke
				(width 0.1)
				(type default)
			)
			(layer "F.Fab")
		)
		(fp_line
			(start -0.12065 -0.2794)
			(end 0.12065 -0.2794)
			(stroke
				(width 0.1)
				(type default)
			)
			(layer "F.Fab")
		)
		(fp_line
			(start 0.12065 -0.2794)
			(end 0.12065 -0.3048)
			(stroke
				(width 0.1)
				(type default)
			)
			(layer "F.Fab")
		)
		(fp_line
			(start 0.12065 -0.3048)
			(end 0.67945 -0.3048)
			(stroke
				(width 0.1)
				(type default)
			)
			(layer "F.Fab")
		)
		(fp_line
			(start 0.67945 -0.3048)
			(end 0.67945 0.3048)
			(stroke
				(width 0.1)
				(type default)
			)
			(layer "F.Fab")
		)
		(fp_line
			(start -0.67945 -0.305054)
			(end -0.12065 -0.305054)
			(stroke
				(width 0.1)
				(type default)
			)
			(layer "F.Fab")
		)
		(fp_line
			(start -0.12065 -0.305054)
			(end -0.12065 -0.2794)
			(stroke
				(width 0.1)
				(type default)
			)
			(layer "F.Fab")
		)
		(pad "1" smd circle
			(at -0.40005 0 270)
			(size 0 0)
			(layers "F.Cu" "F.Mask" "F.Paste")
			(net "P3V3_AUX")
		)
		(pad "2" smd circle
			(at 0.40005 0 270)
			(size 0 0)
			(layers "F.Cu" "F.Mask" "F.Paste")
			(net "FAN_6_OK_R_LED")
		)
	)
	(footprint ""
		(layer "F.Cu")
		(at 25.527 -127.889)
		(property "Reference" "R4949"
			(at 0 0 0)
			(layer "F.SilkS")
			(hide yes)
			(effects
				(font
					(size 1.27 1.27)
				)
			)
		)
		(property "Value" ""
			(at 0 0 0)
			(layer "F.Fab")
			(effects
				(font
					(size 1.27 1.27)
				)
			)
		)
		(duplicate_pad_numbers_are_jumpers no)
		(fp_line
			(start -0.7874 -0.4064)
			(end 0.7874 -0.4064)
			(stroke
				(width 0.1524)
				(type default)
			)
			(layer "F.SilkS")
		)
		(fp_line
			(start -0.7874 0.4064)
			(end -0.7874 -0.4064)
			(stroke
				(width 0.1524)
				(type default)
			)
			(layer "F.SilkS")
		)
		(fp_line
			(start 0.7874 -0.4064)
			(end 0.7874 0.4064)
			(stroke
				(width 0.1524)
				(type default)
			)
			(layer "F.SilkS")
		)
		(fp_line
			(start 0.7874 0.4064)
			(end -0.7874 0.4064)
			(stroke
				(width 0.1524)
				(type default)
			)
			(layer "F.SilkS")
		)
		(fp_line
			(start -0.67945 -0.305054)
			(end -0.12065 -0.305054)
			(stroke
				(width 0.1)
				(type default)
			)
			(layer "F.Fab")
		)
		(fp_line
			(start -0.67945 0.3048)
			(end -0.67945 -0.305054)
			(stroke
				(width 0.1)
				(type default)
			)
			(layer "F.Fab")
		)
		(fp_line
			(start -0.12065 -0.305054)
			(end -0.12065 -0.2794)
			(stroke
				(width 0.1)
				(type default)
			)
			(layer "F.Fab")
		)
		(fp_line
			(start -0.12065 -0.2794)
			(end 0.12065 -0.2794)
			(stroke
				(width 0.1)
				(type default)
			)
			(layer "F.Fab")
		)
		(fp_line
			(start -0.12065 0.2794)
			(end -0.12065 0.3048)
			(stroke
				(width 0.1)
				(type default)
			)
			(layer "F.Fab")
		)
		(fp_line
			(start -0.12065 0.3048)
			(end -0.67945 0.3048)
			(stroke
				(width 0.1)
				(type default)
			)
			(layer "F.Fab")
		)
		(fp_line
			(start 0.120396 0.2794)
			(end -0.12065 0.2794)
			(stroke
				(width 0.1)
				(type default)
			)
			(layer "F.Fab")
		)
		(fp_line
			(start 0.120396 0.3048)
			(end 0.120396 0.2794)
			(stroke
				(width 0.1)
				(type default)
			)
			(layer "F.Fab")
		)
		(fp_line
			(start 0.12065 -0.3048)
			(end 0.67945 -0.3048)
			(stroke
				(width 0.1)
				(type default)
			)
			(layer "F.Fab")
		)
		(fp_line
			(start 0.12065 -0.2794)
			(end 0.12065 -0.3048)
			(stroke
				(width 0.1)
				(type default)
			)
			(layer "F.Fab")
		)
		(fp_line
			(start 0.67945 -0.3048)
			(end 0.67945 0.3048)
			(stroke
				(width 0.1)
				(type default)
			)
			(layer "F.Fab")
		)
		(fp_line
			(start 0.67945 0.3048)
			(end 0.120396 0.3048)
			(stroke
				(width 0.1)
				(type default)
			)
			(layer "F.Fab")
		)
		(pad "1" smd circle
			(at -0.40005 0)
			(size 0 0)
			(layers "F.Cu" "F.Mask" "F.Paste")
			(net "MAX31790_U330_PWM_START1")
		)
		(pad "2" smd circle
			(at 0.40005 0)
			(size 0 0)
			(layers "F.Cu" "F.Mask" "F.Paste")
			(net "P3V3_AUX")
		)
	)
	(footprint ""
		(layer "F.Cu")
		(at 14.351 -116.135912 180)
		(property "Reference" "D246"
			(at 4.445 2.582418 0)
			(unlocked yes)
			(layer "F.SilkS")
			(effects
				(font
					(size 0.7874 0.5842)
					(thickness 0.1524)
				)
				(justify left)
			)
		)
		(property "Value" ""
			(at 0 0 180)
			(layer "F.Fab")
			(effects
				(font
					(size 1.27 1.27)
				)
			)
		)
		(duplicate_pad_numbers_are_jumpers no)
		(fp_line
			(start 0.94488 0.450088)
			(end 0.94488 -0.450088)
			(stroke
				(width 0.1524)
				(type default)
			)
			(layer "F.SilkS")
		)
		(fp_line
			(start 0.94488 -0.450088)
			(end -0.854964 -0.450088)
			(stroke
				(width 0.1524)
				(type default)
			)
			(layer "F.SilkS")
		)
		(fp_line
			(start 0.870458 -0.2794)
			(end 0.845058 0.4064)
			(stroke
				(width 0.1524)
				(type default)
			)
			(layer "F.SilkS")
		)
		(fp_line
			(start 0.845058 0.4064)
			(end 0.845058 -0.381)
			(stroke
				(width 0.1524)
				(type default)
			)
			(layer "F.SilkS")
		)
		(fp_line
			(start -0.854964 0.450088)
			(end 0.925068 0.450088)
			(stroke
				(width 0.1524)
				(type default)
			)
			(layer "F.SilkS")
		)
		(fp_line
			(start -0.854964 -0.450088)
			(end -0.854964 0.450088)
			(stroke
				(width 0.1524)
				(type default)
			)
			(layer "F.SilkS")
		)
		(fp_line
			(start 0.54991 0.350012)
			(end 0.54991 -0.350012)
			(stroke
				(width 0.1)
				(type default)
			)
			(layer "F.Fab")
		)
		(fp_line
			(start 0.54991 -0.350012)
			(end -0.54991 -0.350012)
			(stroke
				(width 0.1)
				(type default)
			)
			(layer "F.Fab")
		)
		(fp_line
			(start -0.54991 0.350012)
			(end 0.54991 0.350012)
			(stroke
				(width 0.1)
				(type default)
			)
			(layer "F.Fab")
		)
		(fp_line
			(start -0.54991 -0.350012)
			(end -0.54991 0.350012)
			(stroke
				(width 0.1)
				(type default)
			)
			(layer "F.Fab")
		)
		(fp_text user "-"
			(at 2.286 -0.470662 0)
			(unlocked yes)
			(layer "F.SilkS")
			(effects
				(font
					(size 1.905 1.4224)
					(thickness 0.1524)
				)
				(justify left)
			)
		)
		(fp_text user "+"
			(at -0.635 0.291338 0)
			(unlocked yes)
			(layer "F.SilkS")
			(effects
				(font
					(size 1.905 1.4224)
					(thickness 0.1524)
				)
				(justify left)
			)
		)
		(fp_text user "-"
			(at 2.48539 0.239014 0)
			(unlocked yes)
			(layer "F.Fab")
			(effects
				(font
					(size 1.905 1.4224)
					(thickness 0.1524)
				)
				(justify left)
			)
		)
		(fp_text user "+"
			(at -0.808228 0.239014 0)
			(unlocked yes)
			(layer "F.Fab")
			(effects
				(font
					(size 1.905 1.4224)
					(thickness 0.1524)
				)
				(justify left)
			)
		)
		(pad "A" smd rect
			(at -0.424942 0 180)
			(size 0.5588 0.6096)
			(layers "F.Cu" "F.Mask" "F.Paste")
			(net "GND")
		)
		(pad "C" smd rect
			(at 0.424942 0)
			(size 0.5588 0.6096)
			(layers "F.Cu" "F.Mask" "F.Paste")
			(net "FAN_5_OK_R_LED_N")
		)
	)
	(footprint ""
		(layer "F.Cu")
		(at 39.243 -73.66 90)
		(property "Reference" "PR37"
			(at 0 0 90)
			(layer "F.SilkS")
			(hide yes)
			(effects
				(font
					(size 1.27 1.27)
				)
			)
		)
		(property "Value" ""
			(at 0 0 90)
			(layer "F.Fab")
			(effects
				(font
					(size 1.27 1.27)
				)
			)
		)
		(duplicate_pad_numbers_are_jumpers no)
		(fp_line
			(start 0.7874 -0.4064)
			(end 0.7874 0.4064)
			(stroke
				(width 0.1524)
				(type default)
			)
			(layer "F.SilkS")
		)
		(fp_line
			(start -0.7874 -0.4064)
			(end 0.7874 -0.4064)
			(stroke
				(width 0.1524)
				(type default)
			)
			(layer "F.SilkS")
		)
		(fp_line
			(start 0.7874 0.4064)
			(end -0.7874 0.4064)
			(stroke
				(width 0.1524)
				(type default)
			)
			(layer "F.SilkS")
		)
		(fp_line
			(start -0.7874 0.4064)
			(end -0.7874 -0.4064)
			(stroke
				(width 0.1524)
				(type default)
			)
			(layer "F.SilkS")
		)
		(fp_line
			(start -0.12065 -0.305054)
			(end -0.12065 -0.2794)
			(stroke
				(width 0.1)
				(type default)
			)
			(layer "F.Fab")
		)
		(fp_line
			(start -0.67945 -0.305054)
			(end -0.12065 -0.305054)
			(stroke
				(width 0.1)
				(type default)
			)
			(layer "F.Fab")
		)
		(fp_line
			(start 0.67945 -0.3048)
			(end 0.67945 0.3048)
			(stroke
				(width 0.1)
				(type default)
			)
			(layer "F.Fab")
		)
		(fp_line
			(start 0.12065 -0.3048)
			(end 0.67945 -0.3048)
			(stroke
				(width 0.1)
				(type default)
			)
			(layer "F.Fab")
		)
		(fp_line
			(start 0.12065 -0.2794)
			(end 0.12065 -0.3048)
			(stroke
				(width 0.1)
				(type default)
			)
			(layer "F.Fab")
		)
		(fp_line
			(start -0.12065 -0.2794)
			(end 0.12065 -0.2794)
			(stroke
				(width 0.1)
				(type default)
			)
			(layer "F.Fab")
		)
		(fp_line
			(start 0.120396 0.2794)
			(end -0.12065 0.2794)
			(stroke
				(width 0.1)
				(type default)
			)
			(layer "F.Fab")
		)
		(fp_line
			(start -0.12065 0.2794)
			(end -0.12065 0.3048)
			(stroke
				(width 0.1)
				(type default)
			)
			(layer "F.Fab")
		)
		(fp_line
			(start 0.67945 0.3048)
			(end 0.120396 0.3048)
			(stroke
				(width 0.1)
				(type default)
			)
			(layer "F.Fab")
		)
		(fp_line
			(start 0.120396 0.3048)
			(end 0.120396 0.2794)
			(stroke
				(width 0.1)
				(type default)
			)
			(layer "F.Fab")
		)
		(fp_line
			(start -0.12065 0.3048)
			(end -0.67945 0.3048)
			(stroke
				(width 0.1)
				(type default)
			)
			(layer "F.Fab")
		)
		(fp_line
			(start -0.67945 0.3048)
			(end -0.67945 -0.305054)
			(stroke
				(width 0.1)
				(type default)
			)
			(layer "F.Fab")
		)
		(pad "1" smd circle
			(at -0.40005 0 90)
			(size 0 0)
			(layers "F.Cu" "F.Mask" "F.Paste")
			(net "FAN_2_P3V_R")
		)
		(pad "2" smd circle
			(at 0.40005 0 90)
			(size 0 0)
			(layers "F.Cu" "F.Mask" "F.Paste")
			(net "FAN_2_MODE")
		)
	)
	(footprint ""
		(layer "F.Cu")
		(at 37.465 -119.564912)
		(property "Reference" "R5216"
			(at 0 0 0)
			(layer "F.SilkS")
			(hide yes)
			(effects
				(font
					(size 1.27 1.27)
				)
			)
		)
		(property "Value" ""
			(at 0 0 0)
			(layer "F.Fab")
			(effects
				(font
					(size 1.27 1.27)
				)
			)
		)
		(duplicate_pad_numbers_are_jumpers no)
		(fp_line
			(start -0.7874 -0.4064)
			(end 0.7874 -0.4064)
			(stroke
				(width 0.1524)
				(type default)
			)
			(layer "F.SilkS")
		)
		(fp_line
			(start -0.7874 0.4064)
			(end -0.7874 -0.4064)
			(stroke
				(width 0.1524)
				(type default)
			)
			(layer "F.SilkS")
		)
		(fp_line
			(start 0.7874 -0.4064)
			(end 0.7874 0.4064)
			(stroke
				(width 0.1524)
				(type default)
			)
			(layer "F.SilkS")
		)
		(fp_line
			(start 0.7874 0.4064)
			(end -0.7874 0.4064)
			(stroke
				(width 0.1524)
				(type default)
			)
			(layer "F.SilkS")
		)
		(fp_line
			(start -0.67945 -0.305054)
			(end -0.12065 -0.305054)
			(stroke
				(width 0.1)
				(type default)
			)
			(layer "F.Fab")
		)
		(fp_line
			(start -0.67945 0.3048)
			(end -0.67945 -0.305054)
			(stroke
				(width 0.1)
				(type default)
			)
			(layer "F.Fab")
		)
		(fp_line
			(start -0.12065 -0.305054)
			(end -0.12065 -0.2794)
			(stroke
				(width 0.1)
				(type default)
			)
			(layer "F.Fab")
		)
		(fp_line
			(start -0.12065 -0.2794)
			(end 0.12065 -0.2794)
			(stroke
				(width 0.1)
				(type default)
			)
			(layer "F.Fab")
		)
		(fp_line
			(start -0.12065 0.2794)
			(end -0.12065 0.3048)
			(stroke
				(width 0.1)
				(type default)
			)
			(layer "F.Fab")
		)
		(fp_line
			(start -0.12065 0.3048)
			(end -0.67945 0.3048)
			(stroke
				(width 0.1)
				(type default)
			)
			(layer "F.Fab")
		)
		(fp_line
			(start 0.120396 0.2794)
			(end -0.12065 0.2794)
			(stroke
				(width 0.1)
				(type default)
			)
			(layer "F.Fab")
		)
		(fp_line
			(start 0.120396 0.3048)
			(end 0.120396 0.2794)
			(stroke
				(width 0.1)
				(type default)
			)
			(layer "F.Fab")
		)
		(fp_line
			(start 0.12065 -0.3048)
			(end 0.67945 -0.3048)
			(stroke
				(width 0.1)
				(type default)
			)
			(layer "F.Fab")
		)
		(fp_line
			(start 0.12065 -0.2794)
			(end 0.12065 -0.3048)
			(stroke
				(width 0.1)
				(type default)
			)
			(layer "F.Fab")
		)
		(fp_line
			(start 0.67945 -0.3048)
			(end 0.67945 0.3048)
			(stroke
				(width 0.1)
				(type default)
			)
			(layer "F.Fab")
		)
		(fp_line
			(start 0.67945 0.3048)
			(end 0.120396 0.3048)
			(stroke
				(width 0.1)
				(type default)
			)
			(layer "F.Fab")
		)
		(pad "1" smd circle
			(at -0.40005 0)
			(size 0 0)
			(layers "F.Cu" "F.Mask" "F.Paste")
			(net "FAN_2_PWM_OL")
		)
		(pad "2" smd circle
			(at 0.40005 0)
			(size 0 0)
			(layers "F.Cu" "F.Mask" "F.Paste")
			(net "FAN_2_PWM_OL_R")
		)
	)
	(footprint ""
		(layer "F.Cu")
		(at 18.415 -189.611)
		(property "Reference" "R309"
			(at 0 0 0)
			(layer "F.SilkS")
			(hide yes)
			(effects
				(font
					(size 1.27 1.27)
				)
			)
		)
		(property "Value" ""
			(at 0 0 0)
			(layer "F.Fab")
			(effects
				(font
					(size 1.27 1.27)
				)
			)
		)
		(duplicate_pad_numbers_are_jumpers no)
		(fp_line
			(start -0.7874 -0.4064)
			(end 0.7874 -0.4064)
			(stroke
				(width 0.1524)
				(type default)
			)
			(layer "F.SilkS")
		)
		(fp_line
			(start -0.7874 0.4064)
			(end -0.7874 -0.4064)
			(stroke
				(width 0.1524)
				(type default)
			)
			(layer "F.SilkS")
		)
		(fp_line
			(start 0.7874 -0.4064)
			(end 0.7874 0.4064)
			(stroke
				(width 0.1524)
				(type default)
			)
			(layer "F.SilkS")
		)
		(fp_line
			(start 0.7874 0.4064)
			(end -0.7874 0.4064)
			(stroke
				(width 0.1524)
				(type default)
			)
			(layer "F.SilkS")
		)
		(fp_line
			(start -0.67945 -0.305054)
			(end -0.12065 -0.305054)
			(stroke
				(width 0.1)
				(type default)
			)
			(layer "F.Fab")
		)
		(fp_line
			(start -0.67945 0.3048)
			(end -0.67945 -0.305054)
			(stroke
				(width 0.1)
				(type default)
			)
			(layer "F.Fab")
		)
		(fp_line
			(start -0.12065 -0.305054)
			(end -0.12065 -0.2794)
			(stroke
				(width 0.1)
				(type default)
			)
			(layer "F.Fab")
		)
		(fp_line
			(start -0.12065 -0.2794)
			(end 0.12065 -0.2794)
			(stroke
				(width 0.1)
				(type default)
			)
			(layer "F.Fab")
		)
		(fp_line
			(start -0.12065 0.2794)
			(end -0.12065 0.3048)
			(stroke
				(width 0.1)
				(type default)
			)
			(layer "F.Fab")
		)
		(fp_line
			(start -0.12065 0.3048)
			(end -0.67945 0.3048)
			(stroke
				(width 0.1)
				(type default)
			)
			(layer "F.Fab")
		)
		(fp_line
			(start 0.120396 0.2794)
			(end -0.12065 0.2794)
			(stroke
				(width 0.1)
				(type default)
			)
			(layer "F.Fab")
		)
		(fp_line
			(start 0.120396 0.3048)
			(end 0.120396 0.2794)
			(stroke
				(width 0.1)
				(type default)
			)
			(layer "F.Fab")
		)
		(fp_line
			(start 0.12065 -0.3048)
			(end 0.67945 -0.3048)
			(stroke
				(width 0.1)
				(type default)
			)
			(layer "F.Fab")
		)
		(fp_line
			(start 0.12065 -0.2794)
			(end 0.12065 -0.3048)
			(stroke
				(width 0.1)
				(type default)
			)
			(layer "F.Fab")
		)
		(fp_line
			(start 0.67945 -0.3048)
			(end 0.67945 0.3048)
			(stroke
				(width 0.1)
				(type default)
			)
			(layer "F.Fab")
		)
		(fp_line
			(start 0.67945 0.3048)
			(end 0.120396 0.3048)
			(stroke
				(width 0.1)
				(type default)
			)
			(layer "F.Fab")
		)
		(pad "1" smd rect
			(at -0.40005 0 180)
			(size 0.4572 0.508)
			(layers "F.Cu" "F.Mask" "F.Paste")
			(net "FRU_WP_N")
		)
		(pad "2" smd rect
			(at 0.40005 0 180)
			(size 0.4572 0.508)
			(layers "F.Cu" "F.Mask" "F.Paste")
			(net "GND")
		)
	)
	(footprint ""
		(layer "F.Cu")
		(at 19.431 -133.985 -90)
		(property "Reference" "R4848"
			(at 0 0 270)
			(layer "F.SilkS")
			(hide yes)
			(effects
				(font
					(size 1.27 1.27)
				)
			)
		)
		(property "Value" ""
			(at 0 0 270)
			(layer "F.Fab")
			(effects
				(font
					(size 1.27 1.27)
				)
			)
		)
		(duplicate_pad_numbers_are_jumpers no)
		(fp_line
			(start -0.7874 0.4064)
			(end -0.7874 -0.4064)
			(stroke
				(width 0.1524)
				(type default)
			)
			(layer "F.SilkS")
		)
		(fp_line
			(start 0.7874 0.4064)
			(end -0.7874 0.4064)
			(stroke
				(width 0.1524)
				(type default)
			)
			(layer "F.SilkS")
		)
		(fp_line
			(start -0.7874 -0.4064)
			(end 0.7874 -0.4064)
			(stroke
				(width 0.1524)
				(type default)
			)
			(layer "F.SilkS")
		)
		(fp_line
			(start 0.7874 -0.4064)
			(end 0.7874 0.4064)
			(stroke
				(width 0.1524)
				(type default)
			)
			(layer "F.SilkS")
		)
		(fp_line
			(start -0.67945 0.3048)
			(end -0.67945 -0.305054)
			(stroke
				(width 0.1)
				(type default)
			)
			(layer "F.Fab")
		)
		(fp_line
			(start -0.12065 0.3048)
			(end -0.67945 0.3048)
			(stroke
				(width 0.1)
				(type default)
			)
			(layer "F.Fab")
		)
		(fp_line
			(start 0.120396 0.3048)
			(end 0.120396 0.2794)
			(stroke
				(width 0.1)
				(type default)
			)
			(layer "F.Fab")
		)
		(fp_line
			(start 0.67945 0.3048)
			(end 0.120396 0.3048)
			(stroke
				(width 0.1)
				(type default)
			)
			(layer "F.Fab")
		)
		(fp_line
			(start -0.12065 0.2794)
			(end -0.12065 0.3048)
			(stroke
				(width 0.1)
				(type default)
			)
			(layer "F.Fab")
		)
		(fp_line
			(start 0.120396 0.2794)
			(end -0.12065 0.2794)
			(stroke
				(width 0.1)
				(type default)
			)
			(layer "F.Fab")
		)
		(fp_line
			(start -0.12065 -0.2794)
			(end 0.12065 -0.2794)
			(stroke
				(width 0.1)
				(type default)
			)
			(layer "F.Fab")
		)
		(fp_line
			(start 0.12065 -0.2794)
			(end 0.12065 -0.3048)
			(stroke
				(width 0.1)
				(type default)
			)
			(layer "F.Fab")
		)
		(fp_line
			(start 0.12065 -0.3048)
			(end 0.67945 -0.3048)
			(stroke
				(width 0.1)
				(type default)
			)
			(layer "F.Fab")
		)
		(fp_line
			(start 0.67945 -0.3048)
			(end 0.67945 0.3048)
			(stroke
				(width 0.1)
				(type default)
			)
			(layer "F.Fab")
		)
		(fp_line
			(start -0.67945 -0.305054)
			(end -0.12065 -0.305054)
			(stroke
				(width 0.1)
				(type default)
			)
			(layer "F.Fab")
		)
		(fp_line
			(start -0.12065 -0.305054)
			(end -0.12065 -0.2794)
			(stroke
				(width 0.1)
				(type default)
			)
			(layer "F.Fab")
		)
		(pad "1" smd circle
			(at -0.40005 0 270)
			(size 0 0)
			(layers "F.Cu" "F.Mask" "F.Paste")
			(net "P3V3_AUX")
		)
		(pad "2" smd circle
			(at 0.40005 0 270)
			(size 0 0)
			(layers "F.Cu" "F.Mask" "F.Paste")
			(net "MAX31790_U330_ADD0")
		)
	)
	(footprint ""
		(layer "F.Cu")
		(at 23.241 -31.369 180)
		(property "Reference" "U409"
			(at 1.4478 -1.74371 0)
			(unlocked yes)
			(layer "F.SilkS")
			(effects
				(font
					(size 0.7874 0.5842)
					(thickness 0.1524)
				)
				(justify left)
			)
		)
		(property "Value" ""
			(at 0 0 180)
			(layer "F.Fab")
			(effects
				(font
					(size 1.27 1.27)
				)
			)
		)
		(duplicate_pad_numbers_are_jumpers no)
		(fp_line
			(start 1.335278 1.100074)
			(end 1.335278 -1.100074)
			(stroke
				(width 0.1524)
				(type default)
			)
			(layer "F.SilkS")
		)
		(fp_line
			(start 1.335278 -1.100074)
			(end -1.335278 -1.100074)
			(stroke
				(width 0.1524)
				(type default)
			)
			(layer "F.SilkS")
		)
		(fp_line
			(start -1.335278 1.100074)
			(end 1.335278 1.100074)
			(stroke
				(width 0.1524)
				(type default)
			)
			(layer "F.SilkS")
		)
		(fp_line
			(start -1.335278 -1.100074)
			(end -1.335278 1.100074)
			(stroke
				(width 0.1524)
				(type default)
			)
			(layer "F.SilkS")
		)
		(fp_line
			(start 0.674878 1.100074)
			(end 0.674878 -1.100074)
			(stroke
				(width 0.1)
				(type default)
			)
			(layer "F.Fab")
		)
		(fp_line
			(start 0.674878 -1.100074)
			(end -0.674878 -1.100074)
			(stroke
				(width 0.1)
				(type default)
			)
			(layer "F.Fab")
		)
		(fp_line
			(start -0.674878 1.100074)
			(end 0.674878 1.100074)
			(stroke
				(width 0.1)
				(type default)
			)
			(layer "F.Fab")
		)
		(fp_line
			(start -0.674878 -1.100074)
			(end -0.674878 1.100074)
			(stroke
				(width 0.1)
				(type default)
			)
			(layer "F.Fab")
		)
		(pad "D" smd rect
			(at 0.8001 0 90)
			(size 0.6096 0.8128)
			(layers "F.Cu" "F.Mask" "F.Paste")
			(net "U409_D1")
		)
		(pad "G" smd rect
			(at -0.8001 -0.649986 90)
			(size 0.6096 0.8128)
			(layers "F.Cu" "F.Mask" "F.Paste")
			(net "FAN_4_PRESENT")
		)
		(pad "S" smd rect
			(at -0.8001 0.649986 90)
			(size 0.6096 0.8128)
			(layers "F.Cu" "F.Mask" "F.Paste")
			(net "GND")
		)
	)
	(footprint ""
		(layer "F.Cu")
		(at 10.2362 -39.403274 180)
		(property "Reference" "PC22"
			(at -2.401824 -5.99567 0)
			(unlocked yes)
			(layer "F.SilkS")
			(effects
				(font
					(size 0.7874 0.5842)
					(thickness 0.1524)
				)
				(justify left)
			)
		)
		(property "Value" ""
			(at 0 0 180)
			(layer "F.Fab")
			(effects
				(font
					(size 1.27 1.27)
				)
			)
		)
		(duplicate_pad_numbers_are_jumpers no)
		(fp_line
			(start 5.249926 5.249926)
			(end 5.249926 1.2446)
			(stroke
				(width 0.1524)
				(type default)
			)
			(layer "F.SilkS")
		)
		(fp_line
			(start 5.249926 -1.2446)
			(end 5.249926 -5.249926)
			(stroke
				(width 0.1524)
				(type default)
			)
			(layer "F.SilkS")
		)
		(fp_line
			(start 5.249926 -5.249926)
			(end -3.979926 -5.249926)
			(stroke
				(width 0.1524)
				(type default)
			)
			(layer "F.SilkS")
		)
		(fp_line
			(start -3.979926 5.249926)
			(end 5.249926 5.249926)
			(stroke
				(width 0.1524)
				(type default)
			)
			(layer "F.SilkS")
		)
		(fp_line
			(start -3.979926 -5.249926)
			(end -5.249926 -3.979926)
			(stroke
				(width 0.1524)
				(type default)
			)
			(layer "F.SilkS")
		)
		(fp_line
			(start -5.249926 3.979926)
			(end -3.979926 5.249926)
			(stroke
				(width 0.1524)
				(type default)
			)
			(layer "F.SilkS")
		)
		(fp_line
			(start -5.249926 1.2446)
			(end -5.249926 3.979926)
			(stroke
				(width 0.1524)
				(type default)
			)
			(layer "F.SilkS")
		)
		(fp_line
			(start -5.249926 -3.979926)
			(end -5.249926 -1.2446)
			(stroke
				(width 0.1524)
				(type default)
			)
			(layer "F.SilkS")
		)
		(fp_line
			(start 5.249926 5.249926)
			(end 5.249926 -5.249926)
			(stroke
				(width 0.1)
				(type default)
			)
			(layer "F.Fab")
		)
		(fp_line
			(start 5.249926 -5.249926)
			(end -5.249926 -5.249926)
			(stroke
				(width 0.1)
				(type default)
			)
			(layer "F.Fab")
		)
		(fp_line
			(start -5.249926 5.249926)
			(end 5.249926 5.249926)
			(stroke
				(width 0.1)
				(type default)
			)
			(layer "F.Fab")
		)
		(fp_line
			(start -5.249926 -5.249926)
			(end -5.249926 5.249926)
			(stroke
				(width 0.1)
				(type default)
			)
			(layer "F.Fab")
		)
		(pad "1" smd rect
			(at -4.45008 0 270)
			(size 2.2098 4.4196)
			(layers "F.Cu" "F.Mask" "F.Paste")
			(net "P52V_FAN_4")
		)
		(pad "2" smd rect
			(at 4.45008 0 270)
			(size 2.2098 4.4196)
			(layers "F.Cu" "F.Mask" "F.Paste")
			(net "GND")
		)
	)
	(footprint ""
		(layer "F.Cu")
		(at 3.81 -99.822)
		(property "Reference" "R5659"
			(at 0 0 0)
			(layer "F.SilkS")
			(hide yes)
			(effects
				(font
					(size 1.27 1.27)
				)
			)
		)
		(property "Value" ""
			(at 0 0 0)
			(layer "F.Fab")
			(effects
				(font
					(size 1.27 1.27)
				)
			)
		)
		(duplicate_pad_numbers_are_jumpers no)
		(fp_line
			(start -0.7874 -0.4064)
			(end 0.7874 -0.4064)
			(stroke
				(width 0.1524)
				(type default)
			)
			(layer "F.SilkS")
		)
		(fp_line
			(start -0.7874 0.4064)
			(end -0.7874 -0.4064)
			(stroke
				(width 0.1524)
				(type default)
			)
			(layer "F.SilkS")
		)
		(fp_line
			(start 0.7874 -0.4064)
			(end 0.7874 0.4064)
			(stroke
				(width 0.1524)
				(type default)
			)
			(layer "F.SilkS")
		)
		(fp_line
			(start 0.7874 0.4064)
			(end -0.7874 0.4064)
			(stroke
				(width 0.1524)
				(type default)
			)
			(layer "F.SilkS")
		)
		(fp_line
			(start -0.67945 -0.305054)
			(end -0.12065 -0.305054)
			(stroke
				(width 0.1)
				(type default)
			)
			(layer "F.Fab")
		)
		(fp_line
			(start -0.67945 0.3048)
			(end -0.67945 -0.305054)
			(stroke
				(width 0.1)
				(type default)
			)
			(layer "F.Fab")
		)
		(fp_line
			(start -0.12065 -0.305054)
			(end -0.12065 -0.2794)
			(stroke
				(width 0.1)
				(type default)
			)
			(layer "F.Fab")
		)
		(fp_line
			(start -0.12065 -0.2794)
			(end 0.12065 -0.2794)
			(stroke
				(width 0.1)
				(type default)
			)
			(layer "F.Fab")
		)
		(fp_line
			(start -0.12065 0.2794)
			(end -0.12065 0.3048)
			(stroke
				(width 0.1)
				(type default)
			)
			(layer "F.Fab")
		)
		(fp_line
			(start -0.12065 0.3048)
			(end -0.67945 0.3048)
			(stroke
				(width 0.1)
				(type default)
			)
			(layer "F.Fab")
		)
		(fp_line
			(start 0.120396 0.2794)
			(end -0.12065 0.2794)
			(stroke
				(width 0.1)
				(type default)
			)
			(layer "F.Fab")
		)
		(fp_line
			(start 0.120396 0.3048)
			(end 0.120396 0.2794)
			(stroke
				(width 0.1)
				(type default)
			)
			(layer "F.Fab")
		)
		(fp_line
			(start 0.12065 -0.3048)
			(end 0.67945 -0.3048)
			(stroke
				(width 0.1)
				(type default)
			)
			(layer "F.Fab")
		)
		(fp_line
			(start 0.12065 -0.2794)
			(end 0.12065 -0.3048)
			(stroke
				(width 0.1)
				(type default)
			)
			(layer "F.Fab")
		)
		(fp_line
			(start 0.67945 -0.3048)
			(end 0.67945 0.3048)
			(stroke
				(width 0.1)
				(type default)
			)
			(layer "F.Fab")
		)
		(fp_line
			(start 0.67945 0.3048)
			(end 0.120396 0.3048)
			(stroke
				(width 0.1)
				(type default)
			)
			(layer "F.Fab")
		)
		(pad "1" smd rect
			(at -0.40005 0 180)
			(size 0.4572 0.508)
			(layers "F.Cu" "F.Mask" "F.Paste")
			(net "P12V_LED")
		)
		(pad "2" smd rect
			(at 0.40005 0 180)
			(size 0.4572 0.508)
			(layers "F.Cu" "F.Mask" "F.Paste")
			(net "U410_D1")
		)
	)
	(footprint ""
		(layer "F.Cu")
		(at 36.322 -288.29)
		(property "Reference" "D132"
			(at 2.286 1.04267 0)
			(unlocked yes)
			(layer "F.SilkS")
			(effects
				(font
					(size 0.7874 0.5842)
					(thickness 0.1524)
				)
				(justify left)
			)
		)
		(property "Value" ""
			(at 0 0 0)
			(layer "F.Fab")
			(effects
				(font
					(size 1.27 1.27)
				)
			)
		)
		(duplicate_pad_numbers_are_jumpers no)
		(fp_line
			(start -0.299974 -0.500126)
			(end -0.299974 0.500126)
			(stroke
				(width 0.1524)
				(type default)
			)
			(layer "F.SilkS")
		)
		(fp_line
			(start -0.299974 0.500126)
			(end 0.199898 0)
			(stroke
				(width 0.1524)
				(type default)
			)
			(layer "F.SilkS")
		)
		(fp_line
			(start 0.199898 0)
			(end -0.299974 -0.500126)
			(stroke
				(width 0.1524)
				(type default)
			)
			(layer "F.SilkS")
		)
		(fp_line
			(start 0.299974 -0.500126)
			(end 0.299974 0.500126)
			(stroke
				(width 0.1524)
				(type default)
			)
			(layer "F.SilkS")
		)
		(fp_line
			(start 1.651 -0.6858)
			(end 1.651 0.6858)
			(stroke
				(width 0.1524)
				(type default)
			)
			(layer "F.SilkS")
		)
		(fp_line
			(start 1.778 0.6858)
			(end 1.778 -0.6858)
			(stroke
				(width 0.1524)
				(type default)
			)
			(layer "F.SilkS")
		)
		(fp_line
			(start -1.35001 -0.225044)
			(end -0.899922 -0.225044)
			(stroke
				(width 0.1)
				(type default)
			)
			(layer "F.Fab")
		)
		(fp_line
			(start -1.35001 0.175006)
			(end -1.35001 -0.225044)
			(stroke
				(width 0.1)
				(type default)
			)
			(layer "F.Fab")
		)
		(fp_line
			(start -0.899922 -0.700024)
			(end 0.899922 -0.700024)
			(stroke
				(width 0.1)
				(type default)
			)
			(layer "F.Fab")
		)
		(fp_line
			(start -0.899922 -0.225044)
			(end -0.899922 -0.700024)
			(stroke
				(width 0.1)
				(type default)
			)
			(layer "F.Fab")
		)
		(fp_line
			(start -0.899922 0.175006)
			(end -1.35001 0.175006)
			(stroke
				(width 0.1)
				(type default)
			)
			(layer "F.Fab")
		)
		(fp_line
			(start -0.899922 0.700024)
			(end -0.899922 0.175006)
			(stroke
				(width 0.1)
				(type default)
			)
			(layer "F.Fab")
		)
		(fp_line
			(start -0.299974 -0.500126)
			(end -0.299974 0.500126)
			(stroke
				(width 0.1)
				(type default)
			)
			(layer "F.Fab")
		)
		(fp_line
			(start -0.299974 0.500126)
			(end 0.199898 0)
			(stroke
				(width 0.1)
				(type default)
			)
			(layer "F.Fab")
		)
		(fp_line
			(start 0.199898 0)
			(end -0.299974 -0.500126)
			(stroke
				(width 0.1)
				(type default)
			)
			(layer "F.Fab")
		)
		(fp_line
			(start 0.299974 -0.500126)
			(end 0.299974 0.500126)
			(stroke
				(width 0.1)
				(type default)
			)
			(layer "F.Fab")
		)
		(fp_line
			(start 0.899922 -0.700024)
			(end 0.899922 -0.225044)
			(stroke
				(width 0.1)
				(type default)
			)
			(layer "F.Fab")
		)
		(fp_line
			(start 0.899922 -0.225044)
			(end 1.35001 -0.225044)
			(stroke
				(width 0.1)
				(type default)
			)
			(layer "F.Fab")
		)
		(fp_line
			(start 0.899922 0.175006)
			(end 0.899922 0.700024)
			(stroke
				(width 0.1)
				(type default)
			)
			(layer "F.Fab")
		)
		(fp_line
			(start 0.899922 0.700024)
			(end -0.899922 0.700024)
			(stroke
				(width 0.1)
				(type default)
			)
			(layer "F.Fab")
		)
		(fp_line
			(start 1.35001 -0.225044)
			(end 1.35001 0.175006)
			(stroke
				(width 0.1)
				(type default)
			)
			(layer "F.Fab")
		)
		(fp_line
			(start 1.35001 0.175006)
			(end 0.899922 0.175006)
			(stroke
				(width 0.1)
				(type default)
			)
			(layer "F.Fab")
		)
		(fp_text user "+"
			(at -2.3368 1.12395 0)
			(unlocked yes)
			(layer "F.SilkS")
			(effects
				(font
					(size 1.905 1.4224)
					(thickness 0.1524)
				)
				(justify left)
			)
		)
		(fp_text user "-"
			(at 0.889 0.79375 0)
			(unlocked yes)
			(layer "F.SilkS")
			(effects
				(font
					(size 1.905 1.4224)
					(thickness 0.1524)
				)
				(justify left)
			)
		)
		(fp_text user "+"
			(at -2.794 -0.19685 0)
			(unlocked yes)
			(layer "F.Fab")
			(effects
				(font
					(size 1.905 1.4224)
					(thickness 0.1524)
				)
				(justify left)
			)
		)
		(fp_text user "-"
			(at 1.8288 -0.24765 0)
			(unlocked yes)
			(layer "F.Fab")
			(effects
				(font
					(size 1.905 1.4224)
					(thickness 0.1524)
				)
				(justify left)
			)
		)
		(pad "1" smd rect
			(at -1.0922 0 180)
			(size 0.8128 0.8636)
			(layers "F.Cu" "F.Mask" "F.Paste")
			(net "FAN_0_TACH_OL_R")
		)
		(pad "2" smd rect
			(at 1.0922 0)
			(size 0.8128 0.8636)
			(layers "F.Cu" "F.Mask" "F.Paste")
			(net "FAN_0_TACH_OL_D")
		)
	)
	(footprint ""
		(layer "F.Cu")
		(at 20.828 -136.017 -90)
		(property "Reference" "R4851"
			(at 0 0 270)
			(layer "F.SilkS")
			(hide yes)
			(effects
				(font
					(size 1.27 1.27)
				)
			)
		)
		(property "Value" ""
			(at 0 0 270)
			(layer "F.Fab")
			(effects
				(font
					(size 1.27 1.27)
				)
			)
		)
		(duplicate_pad_numbers_are_jumpers no)
		(fp_line
			(start -0.7874 0.4064)
			(end -0.7874 -0.4064)
			(stroke
				(width 0.1524)
				(type default)
			)
			(layer "F.SilkS")
		)
		(fp_line
			(start 0.7874 0.4064)
			(end -0.7874 0.4064)
			(stroke
				(width 0.1524)
				(type default)
			)
			(layer "F.SilkS")
		)
		(fp_line
			(start -0.7874 -0.4064)
			(end 0.7874 -0.4064)
			(stroke
				(width 0.1524)
				(type default)
			)
			(layer "F.SilkS")
		)
		(fp_line
			(start 0.7874 -0.4064)
			(end 0.7874 0.4064)
			(stroke
				(width 0.1524)
				(type default)
			)
			(layer "F.SilkS")
		)
		(fp_line
			(start -0.67945 0.3048)
			(end -0.67945 -0.305054)
			(stroke
				(width 0.1)
				(type default)
			)
			(layer "F.Fab")
		)
		(fp_line
			(start -0.12065 0.3048)
			(end -0.67945 0.3048)
			(stroke
				(width 0.1)
				(type default)
			)
			(layer "F.Fab")
		)
		(fp_line
			(start 0.120396 0.3048)
			(end 0.120396 0.2794)
			(stroke
				(width 0.1)
				(type default)
			)
			(layer "F.Fab")
		)
		(fp_line
			(start 0.67945 0.3048)
			(end 0.120396 0.3048)
			(stroke
				(width 0.1)
				(type default)
			)
			(layer "F.Fab")
		)
		(fp_line
			(start -0.12065 0.2794)
			(end -0.12065 0.3048)
			(stroke
				(width 0.1)
				(type default)
			)
			(layer "F.Fab")
		)
		(fp_line
			(start 0.120396 0.2794)
			(end -0.12065 0.2794)
			(stroke
				(width 0.1)
				(type default)
			)
			(layer "F.Fab")
		)
		(fp_line
			(start -0.12065 -0.2794)
			(end 0.12065 -0.2794)
			(stroke
				(width 0.1)
				(type default)
			)
			(layer "F.Fab")
		)
		(fp_line
			(start 0.12065 -0.2794)
			(end 0.12065 -0.3048)
			(stroke
				(width 0.1)
				(type default)
			)
			(layer "F.Fab")
		)
		(fp_line
			(start 0.12065 -0.3048)
			(end 0.67945 -0.3048)
			(stroke
				(width 0.1)
				(type default)
			)
			(layer "F.Fab")
		)
		(fp_line
			(start 0.67945 -0.3048)
			(end 0.67945 0.3048)
			(stroke
				(width 0.1)
				(type default)
			)
			(layer "F.Fab")
		)
		(fp_line
			(start -0.67945 -0.305054)
			(end -0.12065 -0.305054)
			(stroke
				(width 0.1)
				(type default)
			)
			(layer "F.Fab")
		)
		(fp_line
			(start -0.12065 -0.305054)
			(end -0.12065 -0.2794)
			(stroke
				(width 0.1)
				(type default)
			)
			(layer "F.Fab")
		)
		(pad "1" smd circle
			(at -0.40005 0 270)
			(size 0 0)
			(layers "F.Cu" "F.Mask" "F.Paste")
			(net "GND")
		)
		(pad "2" smd circle
			(at 0.40005 0 270)
			(size 0 0)
			(layers "F.Cu" "F.Mask" "F.Paste")
			(net "MAX31790_U330_ADD1")
		)
	)
	(footprint ""
		(layer "F.Cu")
		(at 15.377922 -210.125056 180)
		(property "Reference" "D140"
			(at 5.852922 -0.093726 0)
			(unlocked yes)
			(layer "F.SilkS")
			(effects
				(font
					(size 0.7874 0.5842)
					(thickness 0.1524)
				)
				(justify left)
			)
		)
		(property "Value" ""
			(at 0 0 180)
			(layer "F.Fab")
			(effects
				(font
					(size 1.27 1.27)
				)
			)
		)
		(duplicate_pad_numbers_are_jumpers no)
		(fp_line
			(start 1.778 0.6858)
			(end 1.778 -0.6858)
			(stroke
				(width 0.1524)
				(type default)
			)
			(layer "F.SilkS")
		)
		(fp_line
			(start 1.738122 0.7112)
			(end -1.651 0.7112)
			(stroke
				(width 0.1524)
				(type default)
			)
			(layer "F.SilkS")
		)
		(fp_line
			(start 1.651 -0.6858)
			(end 1.651 0.6858)
			(stroke
				(width 0.1524)
				(type default)
			)
			(layer "F.SilkS")
		)
		(fp_line
			(start 0.299974 -0.500126)
			(end 0.299974 0.500126)
			(stroke
				(width 0.1524)
				(type default)
			)
			(layer "F.SilkS")
		)
		(fp_line
			(start 0.199898 0)
			(end -0.299974 -0.500126)
			(stroke
				(width 0.1524)
				(type default)
			)
			(layer "F.SilkS")
		)
		(fp_line
			(start -0.299974 0.500126)
			(end 0.199898 0)
			(stroke
				(width 0.1524)
				(type default)
			)
			(layer "F.SilkS")
		)
		(fp_line
			(start -0.299974 -0.500126)
			(end -0.299974 0.500126)
			(stroke
				(width 0.1524)
				(type default)
			)
			(layer "F.SilkS")
		)
		(fp_line
			(start -1.651 0.7112)
			(end -1.651 -0.7112)
			(stroke
				(width 0.1524)
				(type default)
			)
			(layer "F.SilkS")
		)
		(fp_line
			(start -1.651 -0.7112)
			(end 1.738122 -0.7112)
			(stroke
				(width 0.1524)
				(type default)
			)
			(layer "F.SilkS")
		)
		(fp_line
			(start 1.35001 0.175006)
			(end 0.899922 0.175006)
			(stroke
				(width 0.1)
				(type default)
			)
			(layer "F.Fab")
		)
		(fp_line
			(start 1.35001 -0.225044)
			(end 1.35001 0.175006)
			(stroke
				(width 0.1)
				(type default)
			)
			(layer "F.Fab")
		)
		(fp_line
			(start 0.899922 0.700024)
			(end -0.899922 0.700024)
			(stroke
				(width 0.1)
				(type default)
			)
			(layer "F.Fab")
		)
		(fp_line
			(start 0.899922 0.175006)
			(end 0.899922 0.700024)
			(stroke
				(width 0.1)
				(type default)
			)
			(layer "F.Fab")
		)
		(fp_line
			(start 0.899922 -0.225044)
			(end 1.35001 -0.225044)
			(stroke
				(width 0.1)
				(type default)
			)
			(layer "F.Fab")
		)
		(fp_line
			(start 0.899922 -0.700024)
			(end 0.899922 -0.225044)
			(stroke
				(width 0.1)
				(type default)
			)
			(layer "F.Fab")
		)
		(fp_line
			(start 0.299974 -0.500126)
			(end 0.299974 0.500126)
			(stroke
				(width 0.1)
				(type default)
			)
			(layer "F.Fab")
		)
		(fp_line
			(start 0.199898 0)
			(end -0.299974 -0.500126)
			(stroke
				(width 0.1)
				(type default)
			)
			(layer "F.Fab")
		)
		(fp_line
			(start -0.299974 0.500126)
			(end 0.199898 0)
			(stroke
				(width 0.1)
				(type default)
			)
			(layer "F.Fab")
		)
		(fp_line
			(start -0.299974 -0.500126)
			(end -0.299974 0.500126)
			(stroke
				(width 0.1)
				(type default)
			)
			(layer "F.Fab")
		)
		(fp_line
			(start -0.899922 0.700024)
			(end -0.899922 0.175006)
			(stroke
				(width 0.1)
				(type default)
			)
			(layer "F.Fab")
		)
		(fp_line
			(start -0.899922 0.175006)
			(end -1.35001 0.175006)
			(stroke
				(width 0.1)
				(type default)
			)
			(layer "F.Fab")
		)
		(fp_line
			(start -0.899922 -0.225044)
			(end -0.899922 -0.700024)
			(stroke
				(width 0.1)
				(type default)
			)
			(layer "F.Fab")
		)
		(fp_line
			(start -0.899922 -0.700024)
			(end 0.899922 -0.700024)
			(stroke
				(width 0.1)
				(type default)
			)
			(layer "F.Fab")
		)
		(fp_line
			(start -1.35001 0.175006)
			(end -1.35001 -0.225044)
			(stroke
				(width 0.1)
				(type default)
			)
			(layer "F.Fab")
		)
		(fp_line
			(start -1.35001 -0.225044)
			(end -0.899922 -0.225044)
			(stroke
				(width 0.1)
				(type default)
			)
			(layer "F.Fab")
		)
		(fp_text user "-"
			(at 1.026922 0.853694 180)
			(unlocked yes)
			(layer "F.SilkS")
			(effects
				(font
					(size 1.905 1.4224)
					(thickness 0.1524)
				)
				(justify left)
			)
		)
		(fp_text user "+"
			(at -2.656078 -1.178306 180)
			(unlocked yes)
			(layer "F.SilkS")
			(effects
				(font
					(size 1.905 1.4224)
					(thickness 0.1524)
				)
				(justify left)
			)
		)
		(fp_text user "-"
			(at 1.8288 -0.24765 180)
			(unlocked yes)
			(layer "F.Fab")
			(effects
				(font
					(size 1.905 1.4224)
					(thickness 0.1524)
				)
				(justify left)
			)
		)
		(fp_text user "+"
			(at -2.794 -0.19685 180)
			(unlocked yes)
			(layer "F.Fab")
			(effects
				(font
					(size 1.905 1.4224)
					(thickness 0.1524)
				)
				(justify left)
			)
		)
		(pad "1" smd rect
			(at -1.0922 0)
			(size 0.8128 0.8636)
			(layers "F.Cu" "F.Mask" "F.Paste")
			(net "FAN_6_TACH_OL_R")
		)
		(pad "2" smd rect
			(at 1.0922 0 180)
			(size 0.8128 0.8636)
			(layers "F.Cu" "F.Mask" "F.Paste")
			(net "FAN_6_TACH_OL_D")
		)
	)
	(footprint ""
		(layer "F.Cu")
		(at 13.589 -203.073 90)
		(property "Reference" "R5700"
			(at 0 0 90)
			(layer "F.SilkS")
			(hide yes)
			(effects
				(font
					(size 1.27 1.27)
				)
			)
		)
		(property "Value" ""
			(at 0 0 90)
			(layer "F.Fab")
			(effects
				(font
					(size 1.27 1.27)
				)
			)
		)
		(duplicate_pad_numbers_are_jumpers no)
		(fp_line
			(start 0.7874 -0.4064)
			(end 0.7874 0.4064)
			(stroke
				(width 0.1524)
				(type default)
			)
			(layer "F.SilkS")
		)
		(fp_line
			(start -0.7874 -0.4064)
			(end 0.7874 -0.4064)
			(stroke
				(width 0.1524)
				(type default)
			)
			(layer "F.SilkS")
		)
		(fp_line
			(start 0.7874 0.4064)
			(end -0.7874 0.4064)
			(stroke
				(width 0.1524)
				(type default)
			)
			(layer "F.SilkS")
		)
		(fp_line
			(start -0.7874 0.4064)
			(end -0.7874 -0.4064)
			(stroke
				(width 0.1524)
				(type default)
			)
			(layer "F.SilkS")
		)
		(fp_line
			(start -0.12065 -0.305054)
			(end -0.12065 -0.2794)
			(stroke
				(width 0.1)
				(type default)
			)
			(layer "F.Fab")
		)
		(fp_line
			(start -0.67945 -0.305054)
			(end -0.12065 -0.305054)
			(stroke
				(width 0.1)
				(type default)
			)
			(layer "F.Fab")
		)
		(fp_line
			(start 0.67945 -0.3048)
			(end 0.67945 0.3048)
			(stroke
				(width 0.1)
				(type default)
			)
			(layer "F.Fab")
		)
		(fp_line
			(start 0.12065 -0.3048)
			(end 0.67945 -0.3048)
			(stroke
				(width 0.1)
				(type default)
			)
			(layer "F.Fab")
		)
		(fp_line
			(start 0.12065 -0.2794)
			(end 0.12065 -0.3048)
			(stroke
				(width 0.1)
				(type default)
			)
			(layer "F.Fab")
		)
		(fp_line
			(start -0.12065 -0.2794)
			(end 0.12065 -0.2794)
			(stroke
				(width 0.1)
				(type default)
			)
			(layer "F.Fab")
		)
		(fp_line
			(start 0.120396 0.2794)
			(end -0.12065 0.2794)
			(stroke
				(width 0.1)
				(type default)
			)
			(layer "F.Fab")
		)
		(fp_line
			(start -0.12065 0.2794)
			(end -0.12065 0.3048)
			(stroke
				(width 0.1)
				(type default)
			)
			(layer "F.Fab")
		)
		(fp_line
			(start 0.67945 0.3048)
			(end 0.120396 0.3048)
			(stroke
				(width 0.1)
				(type default)
			)
			(layer "F.Fab")
		)
		(fp_line
			(start 0.120396 0.3048)
			(end 0.120396 0.2794)
			(stroke
				(width 0.1)
				(type default)
			)
			(layer "F.Fab")
		)
		(fp_line
			(start -0.12065 0.3048)
			(end -0.67945 0.3048)
			(stroke
				(width 0.1)
				(type default)
			)
			(layer "F.Fab")
		)
		(fp_line
			(start -0.67945 0.3048)
			(end -0.67945 -0.305054)
			(stroke
				(width 0.1)
				(type default)
			)
			(layer "F.Fab")
		)
		(pad "1" smd rect
			(at -0.40005 0 270)
			(size 0.4572 0.508)
			(layers "F.Cu" "F.Mask" "F.Paste")
			(net "P12V_LED_R_FAN6")
		)
		(pad "2" smd rect
			(at 0.40005 0 270)
			(size 0.4572 0.508)
			(layers "F.Cu" "F.Mask" "F.Paste")
			(net "P12V_LED_R1_FAN6")
		)
	)
	(footprint ""
		(layer "F.Cu")
		(at 14.0589 -123.317 180)
		(property "Reference" "R5586"
			(at 0 0 180)
			(layer "F.SilkS")
			(hide yes)
			(effects
				(font
					(size 1.27 1.27)
				)
			)
		)
		(property "Value" ""
			(at 0 0 180)
			(layer "F.Fab")
			(effects
				(font
					(size 1.27 1.27)
				)
			)
		)
		(duplicate_pad_numbers_are_jumpers no)
		(fp_line
			(start 0.7874 0.4064)
			(end -0.7874 0.4064)
			(stroke
				(width 0.1524)
				(type default)
			)
			(layer "F.SilkS")
		)
		(fp_line
			(start 0.7874 -0.4064)
			(end 0.7874 0.4064)
			(stroke
				(width 0.1524)
				(type default)
			)
			(layer "F.SilkS")
		)
		(fp_line
			(start -0.7874 0.4064)
			(end -0.7874 -0.4064)
			(stroke
				(width 0.1524)
				(type default)
			)
			(layer "F.SilkS")
		)
		(fp_line
			(start -0.7874 -0.4064)
			(end 0.7874 -0.4064)
			(stroke
				(width 0.1524)
				(type default)
			)
			(layer "F.SilkS")
		)
		(fp_line
			(start 0.67945 0.3048)
			(end 0.120396 0.3048)
			(stroke
				(width 0.1)
				(type default)
			)
			(layer "F.Fab")
		)
		(fp_line
			(start 0.67945 -0.3048)
			(end 0.67945 0.3048)
			(stroke
				(width 0.1)
				(type default)
			)
			(layer "F.Fab")
		)
		(fp_line
			(start 0.12065 -0.2794)
			(end 0.12065 -0.3048)
			(stroke
				(width 0.1)
				(type default)
			)
			(layer "F.Fab")
		)
		(fp_line
			(start 0.12065 -0.3048)
			(end 0.67945 -0.3048)
			(stroke
				(width 0.1)
				(type default)
			)
			(layer "F.Fab")
		)
		(fp_line
			(start 0.120396 0.3048)
			(end 0.120396 0.2794)
			(stroke
				(width 0.1)
				(type default)
			)
			(layer "F.Fab")
		)
		(fp_line
			(start 0.120396 0.2794)
			(end -0.12065 0.2794)
			(stroke
				(width 0.1)
				(type default)
			)
			(layer "F.Fab")
		)
		(fp_line
			(start -0.12065 0.3048)
			(end -0.67945 0.3048)
			(stroke
				(width 0.1)
				(type default)
			)
			(layer "F.Fab")
		)
		(fp_line
			(start -0.12065 0.2794)
			(end -0.12065 0.3048)
			(stroke
				(width 0.1)
				(type default)
			)
			(layer "F.Fab")
		)
		(fp_line
			(start -0.12065 -0.2794)
			(end 0.12065 -0.2794)
			(stroke
				(width 0.1)
				(type default)
			)
			(layer "F.Fab")
		)
		(fp_line
			(start -0.12065 -0.305054)
			(end -0.12065 -0.2794)
			(stroke
				(width 0.1)
				(type default)
			)
			(layer "F.Fab")
		)
		(fp_line
			(start -0.67945 0.3048)
			(end -0.67945 -0.305054)
			(stroke
				(width 0.1)
				(type default)
			)
			(layer "F.Fab")
		)
		(fp_line
			(start -0.67945 -0.305054)
			(end -0.12065 -0.305054)
			(stroke
				(width 0.1)
				(type default)
			)
			(layer "F.Fab")
		)
		(pad "1" smd rect
			(at -0.40005 0)
			(size 0.4572 0.508)
			(layers "F.Cu" "F.Mask" "F.Paste")
			(net "FAN_4_TACH_IL")
		)
		(pad "2" smd rect
			(at 0.40005 0)
			(size 0.4572 0.508)
			(layers "F.Cu" "F.Mask" "F.Paste")
			(net "FAN_4_TACH_IL_R2")
		)
	)
	(footprint ""
		(layer "F.Cu")
		(at 18.669 -291.465 180)
		(property "Reference" "D262"
			(at 2.0193 1.41097 0)
			(unlocked yes)
			(layer "F.SilkS")
			(effects
				(font
					(size 0.7874 0.5842)
					(thickness 0.1524)
				)
				(justify left)
			)
		)
		(property "Value" ""
			(at 0 0 180)
			(layer "F.Fab")
			(effects
				(font
					(size 1.27 1.27)
				)
			)
		)
		(duplicate_pad_numbers_are_jumpers no)
		(fp_line
			(start 0.94488 0.450088)
			(end 0.94488 -0.450088)
			(stroke
				(width 0.1524)
				(type default)
			)
			(layer "F.SilkS")
		)
		(fp_line
			(start 0.94488 -0.450088)
			(end -0.854964 -0.450088)
			(stroke
				(width 0.1524)
				(type default)
			)
			(layer "F.SilkS")
		)
		(fp_line
			(start 0.870458 -0.2794)
			(end 0.845058 0.4064)
			(stroke
				(width 0.1524)
				(type default)
			)
			(layer "F.SilkS")
		)
		(fp_line
			(start 0.845058 0.4064)
			(end 0.845058 -0.381)
			(stroke
				(width 0.1524)
				(type default)
			)
			(layer "F.SilkS")
		)
		(fp_line
			(start -0.854964 0.450088)
			(end 0.925068 0.450088)
			(stroke
				(width 0.1524)
				(type default)
			)
			(layer "F.SilkS")
		)
		(fp_line
			(start -0.854964 -0.450088)
			(end -0.854964 0.450088)
			(stroke
				(width 0.1524)
				(type default)
			)
			(layer "F.SilkS")
		)
		(fp_line
			(start 0.54991 0.350012)
			(end 0.54991 -0.350012)
			(stroke
				(width 0.1)
				(type default)
			)
			(layer "F.Fab")
		)
		(fp_line
			(start 0.54991 -0.350012)
			(end -0.54991 -0.350012)
			(stroke
				(width 0.1)
				(type default)
			)
			(layer "F.Fab")
		)
		(fp_line
			(start -0.54991 0.350012)
			(end 0.54991 0.350012)
			(stroke
				(width 0.1)
				(type default)
			)
			(layer "F.Fab")
		)
		(fp_line
			(start -0.54991 -0.350012)
			(end -0.54991 0.350012)
			(stroke
				(width 0.1)
				(type default)
			)
			(layer "F.Fab")
		)
		(fp_text user "-"
			(at 1.778 0.98425 0)
			(unlocked yes)
			(layer "F.SilkS")
			(effects
				(font
					(size 1.905 1.4224)
					(thickness 0.1524)
				)
				(justify left)
			)
		)
		(fp_text user "+"
			(at -0.635 0.22225 0)
			(unlocked yes)
			(layer "F.SilkS")
			(effects
				(font
					(size 1.905 1.4224)
					(thickness 0.1524)
				)
				(justify left)
			)
		)
		(fp_text user "-"
			(at 2.48539 0.239014 0)
			(unlocked yes)
			(layer "F.Fab")
			(effects
				(font
					(size 1.905 1.4224)
					(thickness 0.1524)
				)
				(justify left)
			)
		)
		(fp_text user "+"
			(at -0.808228 0.239014 0)
			(unlocked yes)
			(layer "F.Fab")
			(effects
				(font
					(size 1.905 1.4224)
					(thickness 0.1524)
				)
				(justify left)
			)
		)
		(pad "A" smd rect
			(at -0.424942 0 180)
			(size 0.5588 0.6096)
			(layers "F.Cu" "F.Mask" "F.Paste")
			(net "GND")
		)
		(pad "C" smd rect
			(at 0.424942 0)
			(size 0.5588 0.6096)
			(layers "F.Cu" "F.Mask" "F.Paste")
			(net "FAN_7_PWM_IL_R")
		)
	)
	(footprint ""
		(layer "F.Cu")
		(at 33.274 -103.632 180)
		(property "Reference" "C2043"
			(at 0 0 180)
			(layer "F.SilkS")
			(hide yes)
			(effects
				(font
					(size 1.27 1.27)
				)
			)
		)
		(property "Value" ""
			(at 0 0 180)
			(layer "F.Fab")
			(effects
				(font
					(size 1.27 1.27)
				)
			)
		)
		(duplicate_pad_numbers_are_jumpers no)
		(fp_line
			(start 0.7874 0.4064)
			(end -0.7874 0.4064)
			(stroke
				(width 0.1524)
				(type default)
			)
			(layer "F.SilkS")
		)
		(fp_line
			(start 0.7874 -0.4064)
			(end 0.7874 0.4064)
			(stroke
				(width 0.1524)
				(type default)
			)
			(layer "F.SilkS")
		)
		(fp_line
			(start -0.7874 0.4064)
			(end -0.7874 -0.4064)
			(stroke
				(width 0.1524)
				(type default)
			)
			(layer "F.SilkS")
		)
		(fp_line
			(start -0.7874 -0.4064)
			(end 0.7874 -0.4064)
			(stroke
				(width 0.1524)
				(type default)
			)
			(layer "F.SilkS")
		)
		(fp_line
			(start 0.67945 0.3048)
			(end 0.120396 0.3048)
			(stroke
				(width 0.1)
				(type default)
			)
			(layer "F.Fab")
		)
		(fp_line
			(start 0.67945 -0.3048)
			(end 0.67945 0.3048)
			(stroke
				(width 0.1)
				(type default)
			)
			(layer "F.Fab")
		)
		(fp_line
			(start 0.12065 -0.2794)
			(end 0.12065 -0.3048)
			(stroke
				(width 0.1)
				(type default)
			)
			(layer "F.Fab")
		)
		(fp_line
			(start 0.12065 -0.3048)
			(end 0.67945 -0.3048)
			(stroke
				(width 0.1)
				(type default)
			)
			(layer "F.Fab")
		)
		(fp_line
			(start 0.120396 0.3048)
			(end 0.120396 0.2794)
			(stroke
				(width 0.1)
				(type default)
			)
			(layer "F.Fab")
		)
		(fp_line
			(start 0.120396 0.2794)
			(end -0.12065 0.2794)
			(stroke
				(width 0.1)
				(type default)
			)
			(layer "F.Fab")
		)
		(fp_line
			(start -0.12065 0.3048)
			(end -0.67945 0.3048)
			(stroke
				(width 0.1)
				(type default)
			)
			(layer "F.Fab")
		)
		(fp_line
			(start -0.12065 0.2794)
			(end -0.12065 0.3048)
			(stroke
				(width 0.1)
				(type default)
			)
			(layer "F.Fab")
		)
		(fp_line
			(start -0.12065 -0.2794)
			(end 0.12065 -0.2794)
			(stroke
				(width 0.1)
				(type default)
			)
			(layer "F.Fab")
		)
		(fp_line
			(start -0.12065 -0.305054)
			(end -0.12065 -0.2794)
			(stroke
				(width 0.1)
				(type default)
			)
			(layer "F.Fab")
		)
		(fp_line
			(start -0.67945 0.3048)
			(end -0.67945 -0.305054)
			(stroke
				(width 0.1)
				(type default)
			)
			(layer "F.Fab")
		)
		(fp_line
			(start -0.67945 -0.305054)
			(end -0.12065 -0.305054)
			(stroke
				(width 0.1)
				(type default)
			)
			(layer "F.Fab")
		)
		(pad "1" smd circle
			(at -0.40005 0 180)
			(size 0 0)
			(layers "F.Cu" "F.Mask" "F.Paste")
			(net "FAN_2_TACH_OL_R")
		)
		(pad "2" smd circle
			(at 0.40005 0 180)
			(size 0 0)
			(layers "F.Cu" "F.Mask" "F.Paste")
			(net "GND")
		)
	)
	(footprint ""
		(layer "F.Cu")
		(at 25.527 -122.78995 180)
		(property "Reference" "R5461"
			(at 0 0 180)
			(layer "F.SilkS")
			(hide yes)
			(effects
				(font
					(size 1.27 1.27)
				)
			)
		)
		(property "Value" ""
			(at 0 0 180)
			(layer "F.Fab")
			(effects
				(font
					(size 1.27 1.27)
				)
			)
		)
		(duplicate_pad_numbers_are_jumpers no)
		(fp_line
			(start 0.7874 0.4064)
			(end -0.7874 0.4064)
			(stroke
				(width 0.1524)
				(type default)
			)
			(layer "F.SilkS")
		)
		(fp_line
			(start 0.7874 -0.4064)
			(end 0.7874 0.4064)
			(stroke
				(width 0.1524)
				(type default)
			)
			(layer "F.SilkS")
		)
		(fp_line
			(start -0.7874 0.4064)
			(end -0.7874 -0.4064)
			(stroke
				(width 0.1524)
				(type default)
			)
			(layer "F.SilkS")
		)
		(fp_line
			(start -0.7874 -0.4064)
			(end 0.7874 -0.4064)
			(stroke
				(width 0.1524)
				(type default)
			)
			(layer "F.SilkS")
		)
		(fp_line
			(start 0.67945 0.3048)
			(end 0.120396 0.3048)
			(stroke
				(width 0.1)
				(type default)
			)
			(layer "F.Fab")
		)
		(fp_line
			(start 0.67945 -0.3048)
			(end 0.67945 0.3048)
			(stroke
				(width 0.1)
				(type default)
			)
			(layer "F.Fab")
		)
		(fp_line
			(start 0.12065 -0.2794)
			(end 0.12065 -0.3048)
			(stroke
				(width 0.1)
				(type default)
			)
			(layer "F.Fab")
		)
		(fp_line
			(start 0.12065 -0.3048)
			(end 0.67945 -0.3048)
			(stroke
				(width 0.1)
				(type default)
			)
			(layer "F.Fab")
		)
		(fp_line
			(start 0.120396 0.3048)
			(end 0.120396 0.2794)
			(stroke
				(width 0.1)
				(type default)
			)
			(layer "F.Fab")
		)
		(fp_line
			(start 0.120396 0.2794)
			(end -0.12065 0.2794)
			(stroke
				(width 0.1)
				(type default)
			)
			(layer "F.Fab")
		)
		(fp_line
			(start -0.12065 0.3048)
			(end -0.67945 0.3048)
			(stroke
				(width 0.1)
				(type default)
			)
			(layer "F.Fab")
		)
		(fp_line
			(start -0.12065 0.2794)
			(end -0.12065 0.3048)
			(stroke
				(width 0.1)
				(type default)
			)
			(layer "F.Fab")
		)
		(fp_line
			(start -0.12065 -0.2794)
			(end 0.12065 -0.2794)
			(stroke
				(width 0.1)
				(type default)
			)
			(layer "F.Fab")
		)
		(fp_line
			(start -0.12065 -0.305054)
			(end -0.12065 -0.2794)
			(stroke
				(width 0.1)
				(type default)
			)
			(layer "F.Fab")
		)
		(fp_line
			(start -0.67945 0.3048)
			(end -0.67945 -0.305054)
			(stroke
				(width 0.1)
				(type default)
			)
			(layer "F.Fab")
		)
		(fp_line
			(start -0.67945 -0.305054)
			(end -0.12065 -0.305054)
			(stroke
				(width 0.1)
				(type default)
			)
			(layer "F.Fab")
		)
		(pad "1" smd circle
			(at -0.40005 0 180)
			(size 0 0)
			(layers "F.Cu" "F.Mask" "F.Paste")
			(net "SMB_PDBV_FAN_SCL")
		)
		(pad "2" smd circle
			(at 0.40005 0 180)
			(size 0 0)
			(layers "F.Cu" "F.Mask" "F.Paste")
			(net "SMB_PDBV_FAN_R_U330_SCL")
		)
	)
	(footprint ""
		(layer "F.Cu")
		(at 36.195 -181.61)
		(property "Reference" "U390"
			(at -0.635 3.32867 0)
			(unlocked yes)
			(layer "F.SilkS")
			(effects
				(font
					(size 0.7874 0.5842)
					(thickness 0.1524)
				)
				(justify left)
			)
		)
		(property "Value" ""
			(at 0 0 0)
			(layer "F.Fab")
			(effects
				(font
					(size 1.27 1.27)
				)
			)
		)
		(duplicate_pad_numbers_are_jumpers no)
		(fp_line
			(start -2.0066 -2.5527)
			(end -0.5715 -2.5527)
			(stroke
				(width 0.1524)
				(type default)
			)
			(layer "F.SilkS")
		)
		(fp_line
			(start -2.0066 2.5527)
			(end -2.0066 -2.5527)
			(stroke
				(width 0.1524)
				(type default)
			)
			(layer "F.SilkS")
		)
		(fp_line
			(start -0.5715 -2.5527)
			(end 0 -1.9812)
			(stroke
				(width 0.1524)
				(type default)
			)
			(layer "F.SilkS")
		)
		(fp_line
			(start 0 -1.9812)
			(end 0.5715 -2.5527)
			(stroke
				(width 0.1524)
				(type default)
			)
			(layer "F.SilkS")
		)
		(fp_line
			(start 0.5715 -2.5527)
			(end 2.0066 -2.5527)
			(stroke
				(width 0.1524)
				(type default)
			)
			(layer "F.SilkS")
		)
		(fp_line
			(start 2.0066 -2.5527)
			(end 2.0066 2.5527)
			(stroke
				(width 0.1524)
				(type default)
			)
			(layer "F.SilkS")
		)
		(fp_line
			(start 2.0066 2.5527)
			(end -2.0066 2.5527)
			(stroke
				(width 0.1524)
				(type default)
			)
			(layer "F.SilkS")
		)
		(fp_poly
			(pts
				(xy -4.36372 -1.608328) (xy -4.36372 -2.233168) (xy -3.81 -1.905)
			)
			(stroke
				(width 0)
				(type default)
			)
			(fill yes)
			(layer "F.SilkS")
		)
		(fp_line
			(start -2.249932 -2.549906)
			(end 2.249932 -2.549906)
			(stroke
				(width 0.1)
				(type default)
			)
			(layer "F.Fab")
		)
		(fp_line
			(start -2.249932 2.549906)
			(end -2.249932 -2.549906)
			(stroke
				(width 0.1)
				(type default)
			)
			(layer "F.Fab")
		)
		(fp_line
			(start 2.249932 -2.549906)
			(end 2.249932 2.549906)
			(stroke
				(width 0.1)
				(type default)
			)
			(layer "F.Fab")
		)
		(fp_line
			(start 2.249932 2.549906)
			(end -2.249932 2.549906)
			(stroke
				(width 0.1)
				(type default)
			)
			(layer "F.Fab")
		)
		(fp_poly
			(pts
				(xy -4.36372 -1.608328) (xy -4.36372 -2.233168) (xy -3.81 -1.905)
			)
			(stroke
				(width 0)
				(type default)
			)
			(fill yes)
			(layer "F.Fab")
		)
		(pad "1" smd rect
			(at -2.921 -1.949958 270)
			(size 0.3556 1.4986)
			(layers "F.Cu" "F.Mask" "F.Paste")
			(net "P52V_FAN_BUFF_EN_R")
		)
		(pad "2" smd rect
			(at -2.921 -1.299972 270)
			(size 0.3556 1.4986)
			(layers "F.Cu" "F.Mask" "F.Paste")
			(net "P52V_FAN_0_BUFF_EN")
		)
		(pad "3" smd rect
			(at -2.921 -0.649986 270)
			(size 0.3556 1.4986)
			(layers "F.Cu" "F.Mask" "F.Paste")
			(net "P52V_FAN_BUFF_EN_R")
		)
		(pad "4" smd rect
			(at -2.921 0 270)
			(size 0.3556 1.4986)
			(layers "F.Cu" "F.Mask" "F.Paste")
			(net "P52V_FAN_1_BUFF_EN")
		)
		(pad "5" smd rect
			(at -2.921 0.649986 270)
			(size 0.3556 1.4986)
			(layers "F.Cu" "F.Mask" "F.Paste")
			(net "P52V_FAN_BUFF_EN_R")
		)
		(pad "6" smd rect
			(at -2.921 1.299972 270)
			(size 0.3556 1.4986)
			(layers "F.Cu" "F.Mask" "F.Paste")
			(net "P52V_FAN_2_BUFF_EN")
		)
		(pad "7" smd rect
			(at -2.921 1.949958 270)
			(size 0.3556 1.4986)
			(layers "F.Cu" "F.Mask" "F.Paste")
			(net "GND")
		)
		(pad "8" smd rect
			(at 2.921 1.949958 270)
			(size 0.3556 1.4986)
			(layers "F.Cu" "F.Mask" "F.Paste")
			(net "P52V_FAN_3_BUFF_EN")
		)
		(pad "9" smd rect
			(at 2.921 1.299972 270)
			(size 0.3556 1.4986)
			(layers "F.Cu" "F.Mask" "F.Paste")
			(net "P52V_FAN_BUFF_EN_R")
		)
		(pad "10" smd rect
			(at 2.921 0.649986 270)
			(size 0.3556 1.4986)
			(layers "F.Cu" "F.Mask" "F.Paste")
			(net "NC_U390_E")
		)
		(pad "11" smd rect
			(at 2.921 0 270)
			(size 0.3556 1.4986)
			(layers "F.Cu" "F.Mask" "F.Paste")
			(net "PD_FAN_BUFF_INPUT_U336E")
		)
		(pad "12" smd rect
			(at 2.921 -0.649986 270)
			(size 0.3556 1.4986)
			(layers "F.Cu" "F.Mask" "F.Paste")
			(net "NC_U390_F")
		)
		(pad "13" smd rect
			(at 2.921 -1.299972 270)
			(size 0.3556 1.4986)
			(layers "F.Cu" "F.Mask" "F.Paste")
			(net "PD_FAN_BUFF_INPUT_U336F")
		)
		(pad "14" smd rect
			(at 2.921 -1.949958 270)
			(size 0.3556 1.4986)
			(layers "F.Cu" "F.Mask" "F.Paste")
			(net "P3V3_AUX")
		)
	)
	(footprint ""
		(layer "F.Cu")
		(at 45.466 -217.424 90)
		(property "Reference" "R5649"
			(at 0 0 90)
			(layer "F.SilkS")
			(hide yes)
			(effects
				(font
					(size 1.27 1.27)
				)
			)
		)
		(property "Value" ""
			(at 0 0 90)
			(layer "F.Fab")
			(effects
				(font
					(size 1.27 1.27)
				)
			)
		)
		(duplicate_pad_numbers_are_jumpers no)
		(fp_line
			(start 0.7874 -0.4064)
			(end 0.7874 0.4064)
			(stroke
				(width 0.1524)
				(type default)
			)
			(layer "F.SilkS")
		)
		(fp_line
			(start -0.7874 -0.4064)
			(end 0.7874 -0.4064)
			(stroke
				(width 0.1524)
				(type default)
			)
			(layer "F.SilkS")
		)
		(fp_line
			(start 0.7874 0.4064)
			(end -0.7874 0.4064)
			(stroke
				(width 0.1524)
				(type default)
			)
			(layer "F.SilkS")
		)
		(fp_line
			(start -0.7874 0.4064)
			(end -0.7874 -0.4064)
			(stroke
				(width 0.1524)
				(type default)
			)
			(layer "F.SilkS")
		)
		(fp_line
			(start -0.12065 -0.305054)
			(end -0.12065 -0.2794)
			(stroke
				(width 0.1)
				(type default)
			)
			(layer "F.Fab")
		)
		(fp_line
			(start -0.67945 -0.305054)
			(end -0.12065 -0.305054)
			(stroke
				(width 0.1)
				(type default)
			)
			(layer "F.Fab")
		)
		(fp_line
			(start 0.67945 -0.3048)
			(end 0.67945 0.3048)
			(stroke
				(width 0.1)
				(type default)
			)
			(layer "F.Fab")
		)
		(fp_line
			(start 0.12065 -0.3048)
			(end 0.67945 -0.3048)
			(stroke
				(width 0.1)
				(type default)
			)
			(layer "F.Fab")
		)
		(fp_line
			(start 0.12065 -0.2794)
			(end 0.12065 -0.3048)
			(stroke
				(width 0.1)
				(type default)
			)
			(layer "F.Fab")
		)
		(fp_line
			(start -0.12065 -0.2794)
			(end 0.12065 -0.2794)
			(stroke
				(width 0.1)
				(type default)
			)
			(layer "F.Fab")
		)
		(fp_line
			(start 0.120396 0.2794)
			(end -0.12065 0.2794)
			(stroke
				(width 0.1)
				(type default)
			)
			(layer "F.Fab")
		)
		(fp_line
			(start -0.12065 0.2794)
			(end -0.12065 0.3048)
			(stroke
				(width 0.1)
				(type default)
			)
			(layer "F.Fab")
		)
		(fp_line
			(start 0.67945 0.3048)
			(end 0.120396 0.3048)
			(stroke
				(width 0.1)
				(type default)
			)
			(layer "F.Fab")
		)
		(fp_line
			(start 0.120396 0.3048)
			(end 0.120396 0.2794)
			(stroke
				(width 0.1)
				(type default)
			)
			(layer "F.Fab")
		)
		(fp_line
			(start -0.12065 0.3048)
			(end -0.67945 0.3048)
			(stroke
				(width 0.1)
				(type default)
			)
			(layer "F.Fab")
		)
		(fp_line
			(start -0.67945 0.3048)
			(end -0.67945 -0.305054)
			(stroke
				(width 0.1)
				(type default)
			)
			(layer "F.Fab")
		)
		(pad "1" smd rect
			(at -0.40005 0 270)
			(size 0.4572 0.508)
			(layers "F.Cu" "F.Mask" "F.Paste")
			(net "P12V_LED")
		)
		(pad "2" smd rect
			(at 0.40005 0 270)
			(size 0.4572 0.508)
			(layers "F.Cu" "F.Mask" "F.Paste")
			(net "U406_D1")
		)
	)
	(footprint ""
		(layer "F.Cu")
		(at 34.417 -18.542)
		(property "Reference" "U375"
			(at 4.064 0.28067 0)
			(unlocked yes)
			(layer "F.SilkS")
			(effects
				(font
					(size 0.7874 0.5842)
					(thickness 0.1524)
				)
				(justify left)
			)
		)
		(property "Value" ""
			(at 0 0 0)
			(layer "F.Fab")
			(effects
				(font
					(size 1.27 1.27)
				)
			)
		)
		(duplicate_pad_numbers_are_jumpers no)
		(fp_line
			(start -1.335278 -1.100074)
			(end -1.335278 1.100074)
			(stroke
				(width 0.1524)
				(type default)
			)
			(layer "F.SilkS")
		)
		(fp_line
			(start -1.335278 1.100074)
			(end 1.335278 1.100074)
			(stroke
				(width 0.1524)
				(type default)
			)
			(layer "F.SilkS")
		)
		(fp_line
			(start 1.335278 -1.100074)
			(end -1.335278 -1.100074)
			(stroke
				(width 0.1524)
				(type default)
			)
			(layer "F.SilkS")
		)
		(fp_line
			(start 1.335278 1.100074)
			(end 1.335278 -1.100074)
			(stroke
				(width 0.1524)
				(type default)
			)
			(layer "F.SilkS")
		)
		(fp_line
			(start -0.674878 -1.100074)
			(end -0.674878 1.100074)
			(stroke
				(width 0.1)
				(type default)
			)
			(layer "F.Fab")
		)
		(fp_line
			(start -0.674878 1.100074)
			(end 0.674878 1.100074)
			(stroke
				(width 0.1)
				(type default)
			)
			(layer "F.Fab")
		)
		(fp_line
			(start 0.674878 -1.100074)
			(end -0.674878 -1.100074)
			(stroke
				(width 0.1)
				(type default)
			)
			(layer "F.Fab")
		)
		(fp_line
			(start 0.674878 1.100074)
			(end 0.674878 -1.100074)
			(stroke
				(width 0.1)
				(type default)
			)
			(layer "F.Fab")
		)
		(pad "D" smd rect
			(at 0.8001 0 270)
			(size 0.6096 0.8128)
			(layers "F.Cu" "F.Mask" "F.Paste")
			(net "FAN_3_OK_LED_R_N")
		)
		(pad "G" smd rect
			(at -0.8001 -0.649986 270)
			(size 0.6096 0.8128)
			(layers "F.Cu" "F.Mask" "F.Paste")
			(net "FAN_3_OK_R_LED")
		)
		(pad "S" smd rect
			(at -0.8001 0.649986 270)
			(size 0.6096 0.8128)
			(layers "F.Cu" "F.Mask" "F.Paste")
			(net "GND")
		)
	)
	(footprint ""
		(layer "F.Cu")
		(at 8.001 -311.15 -90)
		(property "Reference" "Q16"
			(at 0.70866 -2.54635 90)
			(unlocked yes)
			(layer "F.SilkS")
			(effects
				(font
					(size 0.7874 0.5842)
					(thickness 0.1524)
				)
				(justify left)
			)
		)
		(property "Value" ""
			(at 0 0 270)
			(layer "F.Fab")
			(effects
				(font
					(size 1.27 1.27)
				)
			)
		)
		(duplicate_pad_numbers_are_jumpers no)
		(fp_line
			(start -1.905 1.651)
			(end -1.905 -1.651)
			(stroke
				(width 0.1524)
				(type default)
			)
			(layer "F.SilkS")
		)
		(fp_line
			(start 1.905 1.651)
			(end -1.905 1.651)
			(stroke
				(width 0.1524)
				(type default)
			)
			(layer "F.SilkS")
		)
		(fp_line
			(start -1.905 -1.651)
			(end 1.905 -1.651)
			(stroke
				(width 0.1524)
				(type default)
			)
			(layer "F.SilkS")
		)
		(fp_line
			(start 1.905 -1.651)
			(end 1.905 1.651)
			(stroke
				(width 0.1524)
				(type default)
			)
			(layer "F.SilkS")
		)
		(fp_line
			(start -0.6985 1.524)
			(end -0.6985 1.169924)
			(stroke
				(width 0.1)
				(type default)
			)
			(layer "F.Fab")
		)
		(fp_line
			(start 0.6985 1.524)
			(end -0.6985 1.524)
			(stroke
				(width 0.1)
				(type default)
			)
			(layer "F.Fab")
		)
		(fp_line
			(start -1.249934 1.169924)
			(end -1.249934 0.729996)
			(stroke
				(width 0.1)
				(type default)
			)
			(layer "F.Fab")
		)
		(fp_line
			(start -0.6985 1.169924)
			(end -1.249934 1.169924)
			(stroke
				(width 0.1)
				(type default)
			)
			(layer "F.Fab")
		)
		(fp_line
			(start -1.249934 0.729996)
			(end -0.6985 0.729996)
			(stroke
				(width 0.1)
				(type default)
			)
			(layer "F.Fab")
		)
		(fp_line
			(start -0.6985 0.729996)
			(end -0.6985 -0.729996)
			(stroke
				(width 0.1)
				(type default)
			)
			(layer "F.Fab")
		)
		(fp_line
			(start 0.6985 0.219964)
			(end 0.6985 1.524)
			(stroke
				(width 0.1)
				(type default)
			)
			(layer "F.Fab")
		)
		(fp_line
			(start 1.249934 0.219964)
			(end 0.6985 0.219964)
			(stroke
				(width 0.1)
				(type default)
			)
			(layer "F.Fab")
		)
		(fp_line
			(start 0.6985 -0.219964)
			(end 1.249934 -0.219964)
			(stroke
				(width 0.1)
				(type default)
			)
			(layer "F.Fab")
		)
		(fp_line
			(start 1.249934 -0.219964)
			(end 1.249934 0.219964)
			(stroke
				(width 0.1)
				(type default)
			)
			(layer "F.Fab")
		)
		(fp_line
			(start -1.249934 -0.729996)
			(end -1.249934 -1.169924)
			(stroke
				(width 0.1)
				(type default)
			)
			(layer "F.Fab")
		)
		(fp_line
			(start -0.6985 -0.729996)
			(end -1.249934 -0.729996)
			(stroke
				(width 0.1)
				(type default)
			)
			(layer "F.Fab")
		)
		(fp_line
			(start -1.249934 -1.169924)
			(end -0.6985 -1.169924)
			(stroke
				(width 0.1)
				(type default)
			)
			(layer "F.Fab")
		)
		(fp_line
			(start -0.6985 -1.169924)
			(end -0.6985 -1.524)
			(stroke
				(width 0.1)
				(type default)
			)
			(layer "F.Fab")
		)
		(fp_line
			(start -0.6985 -1.524)
			(end 0.6985 -1.524)
			(stroke
				(width 0.1)
				(type default)
			)
			(layer "F.Fab")
		)
		(fp_line
			(start 0.6985 -1.524)
			(end 0.6985 -0.219964)
			(stroke
				(width 0.1)
				(type default)
			)
			(layer "F.Fab")
		)
		(fp_rect
			(start -0.6985 1.524)
			(end 0.6985 -1.524)
			(stroke
				(width 0)
				(type default)
			)
			(fill no)
			(layer "F.Fab")
		)
		(pad "D" smd rect
			(at 1.1176 0 180)
			(size 1.016 1.27)
			(layers "F.Cu" "F.Mask" "F.Paste")
			(net "P12V_LED_FAN7")
		)
		(pad "G" smd rect
			(at -1.1176 -1.016 180)
			(size 1.016 1.27)
			(layers "F.Cu" "F.Mask" "F.Paste")
			(net "U412_D1")
		)
		(pad "S" smd rect
			(at -1.1176 1.016 180)
			(size 1.016 1.27)
			(layers "F.Cu" "F.Mask" "F.Paste")
			(net "P12V_LED")
		)
	)
	(footprint ""
		(layer "F.Cu")
		(at 14.859 -133.604)
		(property "Reference" "R5618"
			(at 0 0 0)
			(layer "F.SilkS")
			(hide yes)
			(effects
				(font
					(size 1.27 1.27)
				)
			)
		)
		(property "Value" ""
			(at 0 0 0)
			(layer "F.Fab")
			(effects
				(font
					(size 1.27 1.27)
				)
			)
		)
		(duplicate_pad_numbers_are_jumpers no)
		(fp_line
			(start -0.7874 -0.4064)
			(end 0.7874 -0.4064)
			(stroke
				(width 0.1524)
				(type default)
			)
			(layer "F.SilkS")
		)
		(fp_line
			(start -0.7874 0.4064)
			(end -0.7874 -0.4064)
			(stroke
				(width 0.1524)
				(type default)
			)
			(layer "F.SilkS")
		)
		(fp_line
			(start 0.7874 -0.4064)
			(end 0.7874 0.4064)
			(stroke
				(width 0.1524)
				(type default)
			)
			(layer "F.SilkS")
		)
		(fp_line
			(start 0.7874 0.4064)
			(end -0.7874 0.4064)
			(stroke
				(width 0.1524)
				(type default)
			)
			(layer "F.SilkS")
		)
		(fp_line
			(start -0.67945 -0.305054)
			(end -0.12065 -0.305054)
			(stroke
				(width 0.1)
				(type default)
			)
			(layer "F.Fab")
		)
		(fp_line
			(start -0.67945 0.3048)
			(end -0.67945 -0.305054)
			(stroke
				(width 0.1)
				(type default)
			)
			(layer "F.Fab")
		)
		(fp_line
			(start -0.12065 -0.305054)
			(end -0.12065 -0.2794)
			(stroke
				(width 0.1)
				(type default)
			)
			(layer "F.Fab")
		)
		(fp_line
			(start -0.12065 -0.2794)
			(end 0.12065 -0.2794)
			(stroke
				(width 0.1)
				(type default)
			)
			(layer "F.Fab")
		)
		(fp_line
			(start -0.12065 0.2794)
			(end -0.12065 0.3048)
			(stroke
				(width 0.1)
				(type default)
			)
			(layer "F.Fab")
		)
		(fp_line
			(start -0.12065 0.3048)
			(end -0.67945 0.3048)
			(stroke
				(width 0.1)
				(type default)
			)
			(layer "F.Fab")
		)
		(fp_line
			(start 0.120396 0.2794)
			(end -0.12065 0.2794)
			(stroke
				(width 0.1)
				(type default)
			)
			(layer "F.Fab")
		)
		(fp_line
			(start 0.120396 0.3048)
			(end 0.120396 0.2794)
			(stroke
				(width 0.1)
				(type default)
			)
			(layer "F.Fab")
		)
		(fp_line
			(start 0.12065 -0.3048)
			(end 0.67945 -0.3048)
			(stroke
				(width 0.1)
				(type default)
			)
			(layer "F.Fab")
		)
		(fp_line
			(start 0.12065 -0.2794)
			(end 0.12065 -0.3048)
			(stroke
				(width 0.1)
				(type default)
			)
			(layer "F.Fab")
		)
		(fp_line
			(start 0.67945 -0.3048)
			(end 0.67945 0.3048)
			(stroke
				(width 0.1)
				(type default)
			)
			(layer "F.Fab")
		)
		(fp_line
			(start 0.67945 0.3048)
			(end 0.120396 0.3048)
			(stroke
				(width 0.1)
				(type default)
			)
			(layer "F.Fab")
		)
		(pad "1" smd rect
			(at -0.40005 0 180)
			(size 0.4572 0.508)
			(layers "F.Cu" "F.Mask" "F.Paste")
			(net "FAN_6_TACH_OL")
		)
		(pad "2" smd rect
			(at 0.40005 0 180)
			(size 0.4572 0.508)
			(layers "F.Cu" "F.Mask" "F.Paste")
			(net "FAN_6_TACH_OL_R1")
		)
	)
	(footprint ""
		(layer "F.Cu")
		(at 18.923 -197.612 180)
		(property "Reference" "R5316"
			(at 0 0 180)
			(layer "F.SilkS")
			(hide yes)
			(effects
				(font
					(size 1.27 1.27)
				)
			)
		)
		(property "Value" ""
			(at 0 0 180)
			(layer "F.Fab")
			(effects
				(font
					(size 1.27 1.27)
				)
			)
		)
		(duplicate_pad_numbers_are_jumpers no)
		(fp_line
			(start 1.2954 0.5842)
			(end -1.2954 0.5842)
			(stroke
				(width 0.1524)
				(type default)
			)
			(layer "F.SilkS")
		)
		(fp_line
			(start 1.2954 -0.5842)
			(end 1.2954 0.5842)
			(stroke
				(width 0.1524)
				(type default)
			)
			(layer "F.SilkS")
		)
		(fp_line
			(start -1.2954 0.5842)
			(end -1.2954 -0.5842)
			(stroke
				(width 0.1524)
				(type default)
			)
			(layer "F.SilkS")
		)
		(fp_line
			(start -1.2954 -0.5842)
			(end 1.2954 -0.5842)
			(stroke
				(width 0.1524)
				(type default)
			)
			(layer "F.SilkS")
		)
		(fp_line
			(start 1.1938 0.4064)
			(end 0.8636 0.4064)
			(stroke
				(width 0.1)
				(type default)
			)
			(layer "F.Fab")
		)
		(fp_line
			(start 1.1938 -0.406654)
			(end 1.1938 0.4064)
			(stroke
				(width 0.1)
				(type default)
			)
			(layer "F.Fab")
		)
		(fp_line
			(start 0.8636 0.4572)
			(end -0.8636 0.4572)
			(stroke
				(width 0.1)
				(type default)
			)
			(layer "F.Fab")
		)
		(fp_line
			(start 0.8636 0.4064)
			(end 0.8636 0.4572)
			(stroke
				(width 0.1)
				(type default)
			)
			(layer "F.Fab")
		)
		(fp_line
			(start 0.8636 -0.406654)
			(end 1.1938 -0.406654)
			(stroke
				(width 0.1)
				(type default)
			)
			(layer "F.Fab")
		)
		(fp_line
			(start 0.8636 -0.4572)
			(end 0.8636 -0.406654)
			(stroke
				(width 0.1)
				(type default)
			)
			(layer "F.Fab")
		)
		(fp_line
			(start -0.8636 0.4572)
			(end -0.8636 0.4318)
			(stroke
				(width 0.1)
				(type default)
			)
			(layer "F.Fab")
		)
		(fp_line
			(start -0.8636 0.4318)
			(end -0.8636 0.4064)
			(stroke
				(width 0.1)
				(type default)
			)
			(layer "F.Fab")
		)
		(fp_line
			(start -0.8636 0.4064)
			(end -1.1938 0.4064)
			(stroke
				(width 0.1)
				(type default)
			)
			(layer "F.Fab")
		)
		(fp_line
			(start -0.8636 -0.406654)
			(end -0.8636 -0.4572)
			(stroke
				(width 0.1)
				(type default)
			)
			(layer "F.Fab")
		)
		(fp_line
			(start -0.8636 -0.4572)
			(end 0.8636 -0.4572)
			(stroke
				(width 0.1)
				(type default)
			)
			(layer "F.Fab")
		)
		(fp_line
			(start -1.1938 0.4064)
			(end -1.1938 -0.406654)
			(stroke
				(width 0.1)
				(type default)
			)
			(layer "F.Fab")
		)
		(fp_line
			(start -1.1938 -0.406654)
			(end -0.8636 -0.406654)
			(stroke
				(width 0.1)
				(type default)
			)
			(layer "F.Fab")
		)
		(pad "1" smd rect
			(at -0.7366 0 90)
			(size 0.7112 0.8128)
			(layers "F.Cu" "F.Mask" "F.Paste")
			(net "P52V_FAN_6")
		)
		(pad "2" smd rect
			(at 0.7366 0 90)
			(size 0.7112 0.8128)
			(layers "F.Cu" "F.Mask" "F.Paste")
			(net "FAN_6_TACH_IL_R")
		)
	)
	(footprint ""
		(layer "F.Cu")
		(at 25.527 -129.413)
		(property "Reference" "R4944"
			(at 0 0 0)
			(layer "F.SilkS")
			(hide yes)
			(effects
				(font
					(size 1.27 1.27)
				)
			)
		)
		(property "Value" ""
			(at 0 0 0)
			(layer "F.Fab")
			(effects
				(font
					(size 1.27 1.27)
				)
			)
		)
		(duplicate_pad_numbers_are_jumpers no)
		(fp_line
			(start -0.7874 -0.4064)
			(end 0.7874 -0.4064)
			(stroke
				(width 0.1524)
				(type default)
			)
			(layer "F.SilkS")
		)
		(fp_line
			(start -0.7874 0.4064)
			(end -0.7874 -0.4064)
			(stroke
				(width 0.1524)
				(type default)
			)
			(layer "F.SilkS")
		)
		(fp_line
			(start 0.7874 -0.4064)
			(end 0.7874 0.4064)
			(stroke
				(width 0.1524)
				(type default)
			)
			(layer "F.SilkS")
		)
		(fp_line
			(start 0.7874 0.4064)
			(end -0.7874 0.4064)
			(stroke
				(width 0.1524)
				(type default)
			)
			(layer "F.SilkS")
		)
		(fp_line
			(start -0.67945 -0.305054)
			(end -0.12065 -0.305054)
			(stroke
				(width 0.1)
				(type default)
			)
			(layer "F.Fab")
		)
		(fp_line
			(start -0.67945 0.3048)
			(end -0.67945 -0.305054)
			(stroke
				(width 0.1)
				(type default)
			)
			(layer "F.Fab")
		)
		(fp_line
			(start -0.12065 -0.305054)
			(end -0.12065 -0.2794)
			(stroke
				(width 0.1)
				(type default)
			)
			(layer "F.Fab")
		)
		(fp_line
			(start -0.12065 -0.2794)
			(end 0.12065 -0.2794)
			(stroke
				(width 0.1)
				(type default)
			)
			(layer "F.Fab")
		)
		(fp_line
			(start -0.12065 0.2794)
			(end -0.12065 0.3048)
			(stroke
				(width 0.1)
				(type default)
			)
			(layer "F.Fab")
		)
		(fp_line
			(start -0.12065 0.3048)
			(end -0.67945 0.3048)
			(stroke
				(width 0.1)
				(type default)
			)
			(layer "F.Fab")
		)
		(fp_line
			(start 0.120396 0.2794)
			(end -0.12065 0.2794)
			(stroke
				(width 0.1)
				(type default)
			)
			(layer "F.Fab")
		)
		(fp_line
			(start 0.120396 0.3048)
			(end 0.120396 0.2794)
			(stroke
				(width 0.1)
				(type default)
			)
			(layer "F.Fab")
		)
		(fp_line
			(start 0.12065 -0.3048)
			(end 0.67945 -0.3048)
			(stroke
				(width 0.1)
				(type default)
			)
			(layer "F.Fab")
		)
		(fp_line
			(start 0.12065 -0.2794)
			(end 0.12065 -0.3048)
			(stroke
				(width 0.1)
				(type default)
			)
			(layer "F.Fab")
		)
		(fp_line
			(start 0.67945 -0.3048)
			(end 0.67945 0.3048)
			(stroke
				(width 0.1)
				(type default)
			)
			(layer "F.Fab")
		)
		(fp_line
			(start 0.67945 0.3048)
			(end 0.120396 0.3048)
			(stroke
				(width 0.1)
				(type default)
			)
			(layer "F.Fab")
		)
		(pad "1" smd circle
			(at -0.40005 0)
			(size 0 0)
			(layers "F.Cu" "F.Mask" "F.Paste")
			(net "GND")
		)
		(pad "2" smd circle
			(at 0.40005 0)
			(size 0 0)
			(layers "F.Cu" "F.Mask" "F.Paste")
			(net "MAX31790_U317_PWM_START1")
		)
	)
	(footprint ""
		(layer "F.Cu")
		(at 4.826 -97.409)
		(property "Reference" "Q14"
			(at -0.01016 -2.36093 0)
			(unlocked yes)
			(layer "F.SilkS")
			(effects
				(font
					(size 0.7874 0.5842)
					(thickness 0.1524)
				)
				(justify left)
			)
		)
		(property "Value" ""
			(at 0 0 0)
			(layer "F.Fab")
			(effects
				(font
					(size 1.27 1.27)
				)
			)
		)
		(duplicate_pad_numbers_are_jumpers no)
		(fp_line
			(start -1.905 -1.651)
			(end 1.905 -1.651)
			(stroke
				(width 0.1524)
				(type default)
			)
			(layer "F.SilkS")
		)
		(fp_line
			(start -1.905 1.651)
			(end -1.905 -1.651)
			(stroke
				(width 0.1524)
				(type default)
			)
			(layer "F.SilkS")
		)
		(fp_line
			(start 1.905 -1.651)
			(end 1.905 1.651)
			(stroke
				(width 0.1524)
				(type default)
			)
			(layer "F.SilkS")
		)
		(fp_line
			(start 1.905 1.651)
			(end -1.905 1.651)
			(stroke
				(width 0.1524)
				(type default)
			)
			(layer "F.SilkS")
		)
		(fp_line
			(start -1.249934 -1.169924)
			(end -0.6985 -1.169924)
			(stroke
				(width 0.1)
				(type default)
			)
			(layer "F.Fab")
		)
		(fp_line
			(start -1.249934 -0.729996)
			(end -1.249934 -1.169924)
			(stroke
				(width 0.1)
				(type default)
			)
			(layer "F.Fab")
		)
		(fp_line
			(start -1.249934 0.729996)
			(end -0.6985 0.729996)
			(stroke
				(width 0.1)
				(type default)
			)
			(layer "F.Fab")
		)
		(fp_line
			(start -1.249934 1.169924)
			(end -1.249934 0.729996)
			(stroke
				(width 0.1)
				(type default)
			)
			(layer "F.Fab")
		)
		(fp_line
			(start -0.6985 -1.524)
			(end 0.6985 -1.524)
			(stroke
				(width 0.1)
				(type default)
			)
			(layer "F.Fab")
		)
		(fp_line
			(start -0.6985 -1.169924)
			(end -0.6985 -1.524)
			(stroke
				(width 0.1)
				(type default)
			)
			(layer "F.Fab")
		)
		(fp_line
			(start -0.6985 -0.729996)
			(end -1.249934 -0.729996)
			(stroke
				(width 0.1)
				(type default)
			)
			(layer "F.Fab")
		)
		(fp_line
			(start -0.6985 0.729996)
			(end -0.6985 -0.729996)
			(stroke
				(width 0.1)
				(type default)
			)
			(layer "F.Fab")
		)
		(fp_line
			(start -0.6985 1.169924)
			(end -1.249934 1.169924)
			(stroke
				(width 0.1)
				(type default)
			)
			(layer "F.Fab")
		)
		(fp_line
			(start -0.6985 1.524)
			(end -0.6985 1.169924)
			(stroke
				(width 0.1)
				(type default)
			)
			(layer "F.Fab")
		)
		(fp_line
			(start 0.6985 -1.524)
			(end 0.6985 -0.219964)
			(stroke
				(width 0.1)
				(type default)
			)
			(layer "F.Fab")
		)
		(fp_line
			(start 0.6985 -0.219964)
			(end 1.249934 -0.219964)
			(stroke
				(width 0.1)
				(type default)
			)
			(layer "F.Fab")
		)
		(fp_line
			(start 0.6985 0.219964)
			(end 0.6985 1.524)
			(stroke
				(width 0.1)
				(type default)
			)
			(layer "F.Fab")
		)
		(fp_line
			(start 0.6985 1.524)
			(end -0.6985 1.524)
			(stroke
				(width 0.1)
				(type default)
			)
			(layer "F.Fab")
		)
		(fp_line
			(start 1.249934 -0.219964)
			(end 1.249934 0.219964)
			(stroke
				(width 0.1)
				(type default)
			)
			(layer "F.Fab")
		)
		(fp_line
			(start 1.249934 0.219964)
			(end 0.6985 0.219964)
			(stroke
				(width 0.1)
				(type default)
			)
			(layer "F.Fab")
		)
		(fp_rect
			(start -0.6985 1.524)
			(end 0.6985 -1.524)
			(stroke
				(width 0)
				(type default)
			)
			(fill no)
			(layer "F.Fab")
		)
		(pad "D" smd rect
			(at 1.1176 0 270)
			(size 1.016 1.27)
			(layers "F.Cu" "F.Mask" "F.Paste")
			(net "P12V_LED_FAN5")
		)
		(pad "G" smd rect
			(at -1.1176 -1.016 270)
			(size 1.016 1.27)
			(layers "F.Cu" "F.Mask" "F.Paste")
			(net "U410_D1")
		)
		(pad "S" smd rect
			(at -1.1176 1.016 270)
			(size 1.016 1.27)
			(layers "F.Cu" "F.Mask" "F.Paste")
			(net "P12V_LED")
		)
	)
	(footprint ""
		(layer "F.Cu")
		(at 18.415 -187.579)
		(property "Reference" "R314"
			(at 0 0 0)
			(layer "F.SilkS")
			(hide yes)
			(effects
				(font
					(size 1.27 1.27)
				)
			)
		)
		(property "Value" ""
			(at 0 0 0)
			(layer "F.Fab")
			(effects
				(font
					(size 1.27 1.27)
				)
			)
		)
		(duplicate_pad_numbers_are_jumpers no)
		(fp_line
			(start -0.7874 -0.4064)
			(end 0.7874 -0.4064)
			(stroke
				(width 0.1524)
				(type default)
			)
			(layer "F.SilkS")
		)
		(fp_line
			(start -0.7874 0.4064)
			(end -0.7874 -0.4064)
			(stroke
				(width 0.1524)
				(type default)
			)
			(layer "F.SilkS")
		)
		(fp_line
			(start 0.7874 -0.4064)
			(end 0.7874 0.4064)
			(stroke
				(width 0.1524)
				(type default)
			)
			(layer "F.SilkS")
		)
		(fp_line
			(start 0.7874 0.4064)
			(end -0.7874 0.4064)
			(stroke
				(width 0.1524)
				(type default)
			)
			(layer "F.SilkS")
		)
		(fp_line
			(start -0.67945 -0.305054)
			(end -0.12065 -0.305054)
			(stroke
				(width 0.1)
				(type default)
			)
			(layer "F.Fab")
		)
		(fp_line
			(start -0.67945 0.3048)
			(end -0.67945 -0.305054)
			(stroke
				(width 0.1)
				(type default)
			)
			(layer "F.Fab")
		)
		(fp_line
			(start -0.12065 -0.305054)
			(end -0.12065 -0.2794)
			(stroke
				(width 0.1)
				(type default)
			)
			(layer "F.Fab")
		)
		(fp_line
			(start -0.12065 -0.2794)
			(end 0.12065 -0.2794)
			(stroke
				(width 0.1)
				(type default)
			)
			(layer "F.Fab")
		)
		(fp_line
			(start -0.12065 0.2794)
			(end -0.12065 0.3048)
			(stroke
				(width 0.1)
				(type default)
			)
			(layer "F.Fab")
		)
		(fp_line
			(start -0.12065 0.3048)
			(end -0.67945 0.3048)
			(stroke
				(width 0.1)
				(type default)
			)
			(layer "F.Fab")
		)
		(fp_line
			(start 0.120396 0.2794)
			(end -0.12065 0.2794)
			(stroke
				(width 0.1)
				(type default)
			)
			(layer "F.Fab")
		)
		(fp_line
			(start 0.120396 0.3048)
			(end 0.120396 0.2794)
			(stroke
				(width 0.1)
				(type default)
			)
			(layer "F.Fab")
		)
		(fp_line
			(start 0.12065 -0.3048)
			(end 0.67945 -0.3048)
			(stroke
				(width 0.1)
				(type default)
			)
			(layer "F.Fab")
		)
		(fp_line
			(start 0.12065 -0.2794)
			(end 0.12065 -0.3048)
			(stroke
				(width 0.1)
				(type default)
			)
			(layer "F.Fab")
		)
		(fp_line
			(start 0.67945 -0.3048)
			(end 0.67945 0.3048)
			(stroke
				(width 0.1)
				(type default)
			)
			(layer "F.Fab")
		)
		(fp_line
			(start 0.67945 0.3048)
			(end 0.120396 0.3048)
			(stroke
				(width 0.1)
				(type default)
			)
			(layer "F.Fab")
		)
		(pad "1" smd circle
			(at -0.40005 0)
			(size 0 0)
			(layers "F.Cu" "F.Mask" "F.Paste")
			(net "SMB_FRU_CLK")
		)
		(pad "2" smd circle
			(at 0.40005 0)
			(size 0 0)
			(layers "F.Cu" "F.Mask" "F.Paste")
			(net "SMB_PDBV_FAN_SCL")
		)
	)
	(footprint ""
		(layer "F.Cu")
		(at 34.417 -141.351 -90)
		(property "Reference" "R5282"
			(at 0 0 270)
			(layer "F.SilkS")
			(hide yes)
			(effects
				(font
					(size 1.27 1.27)
				)
			)
		)
		(property "Value" ""
			(at 0 0 270)
			(layer "F.Fab")
			(effects
				(font
					(size 1.27 1.27)
				)
			)
		)
		(duplicate_pad_numbers_are_jumpers no)
		(fp_line
			(start -0.7874 0.4064)
			(end -0.7874 -0.4064)
			(stroke
				(width 0.1524)
				(type default)
			)
			(layer "F.SilkS")
		)
		(fp_line
			(start 0.7874 0.4064)
			(end -0.7874 0.4064)
			(stroke
				(width 0.1524)
				(type default)
			)
			(layer "F.SilkS")
		)
		(fp_line
			(start -0.7874 -0.4064)
			(end 0.7874 -0.4064)
			(stroke
				(width 0.1524)
				(type default)
			)
			(layer "F.SilkS")
		)
		(fp_line
			(start 0.7874 -0.4064)
			(end 0.7874 0.4064)
			(stroke
				(width 0.1524)
				(type default)
			)
			(layer "F.SilkS")
		)
		(fp_line
			(start -0.67945 0.3048)
			(end -0.67945 -0.305054)
			(stroke
				(width 0.1)
				(type default)
			)
			(layer "F.Fab")
		)
		(fp_line
			(start -0.12065 0.3048)
			(end -0.67945 0.3048)
			(stroke
				(width 0.1)
				(type default)
			)
			(layer "F.Fab")
		)
		(fp_line
			(start 0.120396 0.3048)
			(end 0.120396 0.2794)
			(stroke
				(width 0.1)
				(type default)
			)
			(layer "F.Fab")
		)
		(fp_line
			(start 0.67945 0.3048)
			(end 0.120396 0.3048)
			(stroke
				(width 0.1)
				(type default)
			)
			(layer "F.Fab")
		)
		(fp_line
			(start -0.12065 0.2794)
			(end -0.12065 0.3048)
			(stroke
				(width 0.1)
				(type default)
			)
			(layer "F.Fab")
		)
		(fp_line
			(start 0.120396 0.2794)
			(end -0.12065 0.2794)
			(stroke
				(width 0.1)
				(type default)
			)
			(layer "F.Fab")
		)
		(fp_line
			(start -0.12065 -0.2794)
			(end 0.12065 -0.2794)
			(stroke
				(width 0.1)
				(type default)
			)
			(layer "F.Fab")
		)
		(fp_line
			(start 0.12065 -0.2794)
			(end 0.12065 -0.3048)
			(stroke
				(width 0.1)
				(type default)
			)
			(layer "F.Fab")
		)
		(fp_line
			(start 0.12065 -0.3048)
			(end 0.67945 -0.3048)
			(stroke
				(width 0.1)
				(type default)
			)
			(layer "F.Fab")
		)
		(fp_line
			(start 0.67945 -0.3048)
			(end 0.67945 0.3048)
			(stroke
				(width 0.1)
				(type default)
			)
			(layer "F.Fab")
		)
		(fp_line
			(start -0.67945 -0.305054)
			(end -0.12065 -0.305054)
			(stroke
				(width 0.1)
				(type default)
			)
			(layer "F.Fab")
		)
		(fp_line
			(start -0.12065 -0.305054)
			(end -0.12065 -0.2794)
			(stroke
				(width 0.1)
				(type default)
			)
			(layer "F.Fab")
		)
		(pad "1" smd circle
			(at -0.40005 0 270)
			(size 0 0)
			(layers "F.Cu" "F.Mask" "F.Paste")
			(net "SMB_FAN3_R_SCL")
		)
		(pad "2" smd circle
			(at 0.40005 0 270)
			(size 0 0)
			(layers "F.Cu" "F.Mask" "F.Paste")
			(net "P3V3_AUX")
		)
	)
	(footprint ""
		(layer "F.Cu")
		(at 45.085 -179.324)
		(property "Reference" "R5490"
			(at 0 0 0)
			(layer "F.SilkS")
			(hide yes)
			(effects
				(font
					(size 1.27 1.27)
				)
			)
		)
		(property "Value" ""
			(at 0 0 0)
			(layer "F.Fab")
			(effects
				(font
					(size 1.27 1.27)
				)
			)
		)
		(duplicate_pad_numbers_are_jumpers no)
		(fp_line
			(start -0.7874 -0.4064)
			(end 0.7874 -0.4064)
			(stroke
				(width 0.1524)
				(type default)
			)
			(layer "F.SilkS")
		)
		(fp_line
			(start -0.7874 0.4064)
			(end -0.7874 -0.4064)
			(stroke
				(width 0.1524)
				(type default)
			)
			(layer "F.SilkS")
		)
		(fp_line
			(start 0.7874 -0.4064)
			(end 0.7874 0.4064)
			(stroke
				(width 0.1524)
				(type default)
			)
			(layer "F.SilkS")
		)
		(fp_line
			(start 0.7874 0.4064)
			(end -0.7874 0.4064)
			(stroke
				(width 0.1524)
				(type default)
			)
			(layer "F.SilkS")
		)
		(fp_line
			(start -0.67945 -0.305054)
			(end -0.12065 -0.305054)
			(stroke
				(width 0.1)
				(type default)
			)
			(layer "F.Fab")
		)
		(fp_line
			(start -0.67945 0.3048)
			(end -0.67945 -0.305054)
			(stroke
				(width 0.1)
				(type default)
			)
			(layer "F.Fab")
		)
		(fp_line
			(start -0.12065 -0.305054)
			(end -0.12065 -0.2794)
			(stroke
				(width 0.1)
				(type default)
			)
			(layer "F.Fab")
		)
		(fp_line
			(start -0.12065 -0.2794)
			(end 0.12065 -0.2794)
			(stroke
				(width 0.1)
				(type default)
			)
			(layer "F.Fab")
		)
		(fp_line
			(start -0.12065 0.2794)
			(end -0.12065 0.3048)
			(stroke
				(width 0.1)
				(type default)
			)
			(layer "F.Fab")
		)
		(fp_line
			(start -0.12065 0.3048)
			(end -0.67945 0.3048)
			(stroke
				(width 0.1)
				(type default)
			)
			(layer "F.Fab")
		)
		(fp_line
			(start 0.120396 0.2794)
			(end -0.12065 0.2794)
			(stroke
				(width 0.1)
				(type default)
			)
			(layer "F.Fab")
		)
		(fp_line
			(start 0.120396 0.3048)
			(end 0.120396 0.2794)
			(stroke
				(width 0.1)
				(type default)
			)
			(layer "F.Fab")
		)
		(fp_line
			(start 0.12065 -0.3048)
			(end 0.67945 -0.3048)
			(stroke
				(width 0.1)
				(type default)
			)
			(layer "F.Fab")
		)
		(fp_line
			(start 0.12065 -0.2794)
			(end 0.12065 -0.3048)
			(stroke
				(width 0.1)
				(type default)
			)
			(layer "F.Fab")
		)
		(fp_line
			(start 0.67945 -0.3048)
			(end 0.67945 0.3048)
			(stroke
				(width 0.1)
				(type default)
			)
			(layer "F.Fab")
		)
		(fp_line
			(start 0.67945 0.3048)
			(end 0.120396 0.3048)
			(stroke
				(width 0.1)
				(type default)
			)
			(layer "F.Fab")
		)
		(pad "1" smd circle
			(at -0.40005 0)
			(size 0 0)
			(layers "F.Cu" "F.Mask" "F.Paste")
			(net "P52V_FAN_3_BUFF_EN")
		)
		(pad "2" smd circle
			(at 0.40005 0)
			(size 0 0)
			(layers "F.Cu" "F.Mask" "F.Paste")
			(net "P52V_FAN_3_BUFF_EN_R")
		)
	)
	(footprint ""
		(layer "F.Cu")
		(at 3.81 -182.626)
		(property "Reference" "R2356"
			(at 0 0 0)
			(layer "F.SilkS")
			(hide yes)
			(effects
				(font
					(size 1.27 1.27)
				)
			)
		)
		(property "Value" ""
			(at 0 0 0)
			(layer "F.Fab")
			(effects
				(font
					(size 1.27 1.27)
				)
			)
		)
		(duplicate_pad_numbers_are_jumpers no)
		(fp_line
			(start -0.7874 -0.4064)
			(end 0.7874 -0.4064)
			(stroke
				(width 0.1524)
				(type default)
			)
			(layer "F.SilkS")
		)
		(fp_line
			(start -0.7874 0.4064)
			(end -0.7874 -0.4064)
			(stroke
				(width 0.1524)
				(type default)
			)
			(layer "F.SilkS")
		)
		(fp_line
			(start 0.7874 -0.4064)
			(end 0.7874 0.4064)
			(stroke
				(width 0.1524)
				(type default)
			)
			(layer "F.SilkS")
		)
		(fp_line
			(start 0.7874 0.4064)
			(end -0.7874 0.4064)
			(stroke
				(width 0.1524)
				(type default)
			)
			(layer "F.SilkS")
		)
		(fp_line
			(start -0.67945 -0.305054)
			(end -0.12065 -0.305054)
			(stroke
				(width 0.1)
				(type default)
			)
			(layer "F.Fab")
		)
		(fp_line
			(start -0.67945 0.3048)
			(end -0.67945 -0.305054)
			(stroke
				(width 0.1)
				(type default)
			)
			(layer "F.Fab")
		)
		(fp_line
			(start -0.12065 -0.305054)
			(end -0.12065 -0.2794)
			(stroke
				(width 0.1)
				(type default)
			)
			(layer "F.Fab")
		)
		(fp_line
			(start -0.12065 -0.2794)
			(end 0.12065 -0.2794)
			(stroke
				(width 0.1)
				(type default)
			)
			(layer "F.Fab")
		)
		(fp_line
			(start -0.12065 0.2794)
			(end -0.12065 0.3048)
			(stroke
				(width 0.1)
				(type default)
			)
			(layer "F.Fab")
		)
		(fp_line
			(start -0.12065 0.3048)
			(end -0.67945 0.3048)
			(stroke
				(width 0.1)
				(type default)
			)
			(layer "F.Fab")
		)
		(fp_line
			(start 0.120396 0.2794)
			(end -0.12065 0.2794)
			(stroke
				(width 0.1)
				(type default)
			)
			(layer "F.Fab")
		)
		(fp_line
			(start 0.120396 0.3048)
			(end 0.120396 0.2794)
			(stroke
				(width 0.1)
				(type default)
			)
			(layer "F.Fab")
		)
		(fp_line
			(start 0.12065 -0.3048)
			(end 0.67945 -0.3048)
			(stroke
				(width 0.1)
				(type default)
			)
			(layer "F.Fab")
		)
		(fp_line
			(start 0.12065 -0.2794)
			(end 0.12065 -0.3048)
			(stroke
				(width 0.1)
				(type default)
			)
			(layer "F.Fab")
		)
		(fp_line
			(start 0.67945 -0.3048)
			(end 0.67945 0.3048)
			(stroke
				(width 0.1)
				(type default)
			)
			(layer "F.Fab")
		)
		(fp_line
			(start 0.67945 0.3048)
			(end 0.120396 0.3048)
			(stroke
				(width 0.1)
				(type default)
			)
			(layer "F.Fab")
		)
		(pad "1" smd circle
			(at -0.40005 0)
			(size 0 0)
			(layers "F.Cu" "F.Mask" "F.Paste")
			(net "P3V3_AUX")
		)
		(pad "2" smd circle
			(at 0.40005 0)
			(size 0 0)
			(layers "F.Cu" "F.Mask" "F.Paste")
			(net "PCA9555_MB0_A2")
		)
	)
	(footprint ""
		(layer "F.Cu")
		(at 18.669 -106.737912 180)
		(property "Reference" "D250"
			(at -1.397 1.566418 0)
			(unlocked yes)
			(layer "F.SilkS")
			(effects
				(font
					(size 0.7874 0.5842)
					(thickness 0.1524)
				)
				(justify left)
			)
		)
		(property "Value" ""
			(at 0 0 180)
			(layer "F.Fab")
			(effects
				(font
					(size 1.27 1.27)
				)
			)
		)
		(duplicate_pad_numbers_are_jumpers no)
		(fp_line
			(start 0.94488 0.450088)
			(end 0.94488 -0.450088)
			(stroke
				(width 0.1524)
				(type default)
			)
			(layer "F.SilkS")
		)
		(fp_line
			(start 0.94488 -0.450088)
			(end -0.854964 -0.450088)
			(stroke
				(width 0.1524)
				(type default)
			)
			(layer "F.SilkS")
		)
		(fp_line
			(start 0.870458 -0.2794)
			(end 0.845058 0.4064)
			(stroke
				(width 0.1524)
				(type default)
			)
			(layer "F.SilkS")
		)
		(fp_line
			(start 0.845058 0.4064)
			(end 0.845058 -0.381)
			(stroke
				(width 0.1524)
				(type default)
			)
			(layer "F.SilkS")
		)
		(fp_line
			(start -0.854964 0.450088)
			(end 0.925068 0.450088)
			(stroke
				(width 0.1524)
				(type default)
			)
			(layer "F.SilkS")
		)
		(fp_line
			(start -0.854964 -0.450088)
			(end -0.854964 0.450088)
			(stroke
				(width 0.1524)
				(type default)
			)
			(layer "F.SilkS")
		)
		(fp_line
			(start 0.54991 0.350012)
			(end 0.54991 -0.350012)
			(stroke
				(width 0.1)
				(type default)
			)
			(layer "F.Fab")
		)
		(fp_line
			(start 0.54991 -0.350012)
			(end -0.54991 -0.350012)
			(stroke
				(width 0.1)
				(type default)
			)
			(layer "F.Fab")
		)
		(fp_line
			(start -0.54991 0.350012)
			(end 0.54991 0.350012)
			(stroke
				(width 0.1)
				(type default)
			)
			(layer "F.Fab")
		)
		(fp_line
			(start -0.54991 -0.350012)
			(end -0.54991 0.350012)
			(stroke
				(width 0.1)
				(type default)
			)
			(layer "F.Fab")
		)
		(fp_text user "-"
			(at 1.397 1.053338 0)
			(unlocked yes)
			(layer "F.SilkS")
			(effects
				(font
					(size 1.905 1.4224)
					(thickness 0.1524)
				)
				(justify left)
			)
		)
		(fp_text user "+"
			(at -0.762 0.545338 0)
			(unlocked yes)
			(layer "F.SilkS")
			(effects
				(font
					(size 1.905 1.4224)
					(thickness 0.1524)
				)
				(justify left)
			)
		)
		(fp_text user "-"
			(at 2.48539 0.239014 0)
			(unlocked yes)
			(layer "F.Fab")
			(effects
				(font
					(size 1.905 1.4224)
					(thickness 0.1524)
				)
				(justify left)
			)
		)
		(fp_text user "+"
			(at -0.808228 0.239014 0)
			(unlocked yes)
			(layer "F.Fab")
			(effects
				(font
					(size 1.905 1.4224)
					(thickness 0.1524)
				)
				(justify left)
			)
		)
		(pad "A" smd rect
			(at -0.424942 0 180)
			(size 0.5588 0.6096)
			(layers "F.Cu" "F.Mask" "F.Paste")
			(net "GND")
		)
		(pad "C" smd rect
			(at 0.424942 0)
			(size 0.5588 0.6096)
			(layers "F.Cu" "F.Mask" "F.Paste")
			(net "FAN_5_PWM_IL_R")
		)
	)
	(footprint ""
		(layer "F.Cu")
		(at 14.874494 -72.066912)
		(property "Reference" "R5355"
			(at 0 0 0)
			(layer "F.SilkS")
			(hide yes)
			(effects
				(font
					(size 1.27 1.27)
				)
			)
		)
		(property "Value" ""
			(at 0 0 0)
			(layer "F.Fab")
			(effects
				(font
					(size 1.27 1.27)
				)
			)
		)
		(duplicate_pad_numbers_are_jumpers no)
		(fp_line
			(start -0.7874 -0.4064)
			(end 0.7874 -0.4064)
			(stroke
				(width 0.1524)
				(type default)
			)
			(layer "F.SilkS")
		)
		(fp_line
			(start -0.7874 0.4064)
			(end -0.7874 -0.4064)
			(stroke
				(width 0.1524)
				(type default)
			)
			(layer "F.SilkS")
		)
		(fp_line
			(start 0.7874 -0.4064)
			(end 0.7874 0.4064)
			(stroke
				(width 0.1524)
				(type default)
			)
			(layer "F.SilkS")
		)
		(fp_line
			(start 0.7874 0.4064)
			(end -0.7874 0.4064)
			(stroke
				(width 0.1524)
				(type default)
			)
			(layer "F.SilkS")
		)
		(fp_line
			(start -0.67945 -0.305054)
			(end -0.12065 -0.305054)
			(stroke
				(width 0.1)
				(type default)
			)
			(layer "F.Fab")
		)
		(fp_line
			(start -0.67945 0.3048)
			(end -0.67945 -0.305054)
			(stroke
				(width 0.1)
				(type default)
			)
			(layer "F.Fab")
		)
		(fp_line
			(start -0.12065 -0.305054)
			(end -0.12065 -0.2794)
			(stroke
				(width 0.1)
				(type default)
			)
			(layer "F.Fab")
		)
		(fp_line
			(start -0.12065 -0.2794)
			(end 0.12065 -0.2794)
			(stroke
				(width 0.1)
				(type default)
			)
			(layer "F.Fab")
		)
		(fp_line
			(start -0.12065 0.2794)
			(end -0.12065 0.3048)
			(stroke
				(width 0.1)
				(type default)
			)
			(layer "F.Fab")
		)
		(fp_line
			(start -0.12065 0.3048)
			(end -0.67945 0.3048)
			(stroke
				(width 0.1)
				(type default)
			)
			(layer "F.Fab")
		)
		(fp_line
			(start 0.120396 0.2794)
			(end -0.12065 0.2794)
			(stroke
				(width 0.1)
				(type default)
			)
			(layer "F.Fab")
		)
		(fp_line
			(start 0.120396 0.3048)
			(end 0.120396 0.2794)
			(stroke
				(width 0.1)
				(type default)
			)
			(layer "F.Fab")
		)
		(fp_line
			(start 0.12065 -0.3048)
			(end 0.67945 -0.3048)
			(stroke
				(width 0.1)
				(type default)
			)
			(layer "F.Fab")
		)
		(fp_line
			(start 0.12065 -0.2794)
			(end 0.12065 -0.3048)
			(stroke
				(width 0.1)
				(type default)
			)
			(layer "F.Fab")
		)
		(fp_line
			(start 0.67945 -0.3048)
			(end 0.67945 0.3048)
			(stroke
				(width 0.1)
				(type default)
			)
			(layer "F.Fab")
		)
		(fp_line
			(start 0.67945 0.3048)
			(end 0.120396 0.3048)
			(stroke
				(width 0.1)
				(type default)
			)
			(layer "F.Fab")
		)
		(pad "1" smd circle
			(at -0.40005 0)
			(size 0 0)
			(layers "F.Cu" "F.Mask" "F.Paste")
			(net "FAN_5_PRESENT_R")
		)
		(pad "2" smd circle
			(at 0.40005 0)
			(size 0 0)
			(layers "F.Cu" "F.Mask" "F.Paste")
			(net "FAN_5_PRESENT")
		)
	)
	(footprint ""
		(layer "F.Cu")
		(at 38.6461 -130.048)
		(property "Reference" "R5579"
			(at 0 0 0)
			(layer "F.SilkS")
			(hide yes)
			(effects
				(font
					(size 1.27 1.27)
				)
			)
		)
		(property "Value" ""
			(at 0 0 0)
			(layer "F.Fab")
			(effects
				(font
					(size 1.27 1.27)
				)
			)
		)
		(duplicate_pad_numbers_are_jumpers no)
		(fp_line
			(start -0.7874 -0.4064)
			(end 0.7874 -0.4064)
			(stroke
				(width 0.1524)
				(type default)
			)
			(layer "F.SilkS")
		)
		(fp_line
			(start -0.7874 0.4064)
			(end -0.7874 -0.4064)
			(stroke
				(width 0.1524)
				(type default)
			)
			(layer "F.SilkS")
		)
		(fp_line
			(start 0.7874 -0.4064)
			(end 0.7874 0.4064)
			(stroke
				(width 0.1524)
				(type default)
			)
			(layer "F.SilkS")
		)
		(fp_line
			(start 0.7874 0.4064)
			(end -0.7874 0.4064)
			(stroke
				(width 0.1524)
				(type default)
			)
			(layer "F.SilkS")
		)
		(fp_line
			(start -0.67945 -0.305054)
			(end -0.12065 -0.305054)
			(stroke
				(width 0.1)
				(type default)
			)
			(layer "F.Fab")
		)
		(fp_line
			(start -0.67945 0.3048)
			(end -0.67945 -0.305054)
			(stroke
				(width 0.1)
				(type default)
			)
			(layer "F.Fab")
		)
		(fp_line
			(start -0.12065 -0.305054)
			(end -0.12065 -0.2794)
			(stroke
				(width 0.1)
				(type default)
			)
			(layer "F.Fab")
		)
		(fp_line
			(start -0.12065 -0.2794)
			(end 0.12065 -0.2794)
			(stroke
				(width 0.1)
				(type default)
			)
			(layer "F.Fab")
		)
		(fp_line
			(start -0.12065 0.2794)
			(end -0.12065 0.3048)
			(stroke
				(width 0.1)
				(type default)
			)
			(layer "F.Fab")
		)
		(fp_line
			(start -0.12065 0.3048)
			(end -0.67945 0.3048)
			(stroke
				(width 0.1)
				(type default)
			)
			(layer "F.Fab")
		)
		(fp_line
			(start 0.120396 0.2794)
			(end -0.12065 0.2794)
			(stroke
				(width 0.1)
				(type default)
			)
			(layer "F.Fab")
		)
		(fp_line
			(start 0.120396 0.3048)
			(end 0.120396 0.2794)
			(stroke
				(width 0.1)
				(type default)
			)
			(layer "F.Fab")
		)
		(fp_line
			(start 0.12065 -0.3048)
			(end 0.67945 -0.3048)
			(stroke
				(width 0.1)
				(type default)
			)
			(layer "F.Fab")
		)
		(fp_line
			(start 0.12065 -0.2794)
			(end 0.12065 -0.3048)
			(stroke
				(width 0.1)
				(type default)
			)
			(layer "F.Fab")
		)
		(fp_line
			(start 0.67945 -0.3048)
			(end 0.67945 0.3048)
			(stroke
				(width 0.1)
				(type default)
			)
			(layer "F.Fab")
		)
		(fp_line
			(start 0.67945 0.3048)
			(end 0.120396 0.3048)
			(stroke
				(width 0.1)
				(type default)
			)
			(layer "F.Fab")
		)
		(pad "1" smd rect
			(at -0.40005 0 180)
			(size 0.4572 0.508)
			(layers "F.Cu" "F.Mask" "F.Paste")
			(net "FAN_2_PWM")
		)
		(pad "2" smd rect
			(at 0.40005 0 180)
			(size 0.4572 0.508)
			(layers "F.Cu" "F.Mask" "F.Paste")
			(net "FAN_2_PWM_R2")
		)
	)
	(footprint ""
		(layer "F.Cu")
		(at 21.717 -211.328 90)
		(property "Reference" "C2087"
			(at 0 0 90)
			(layer "F.SilkS")
			(hide yes)
			(effects
				(font
					(size 1.27 1.27)
				)
			)
		)
		(property "Value" ""
			(at 0 0 90)
			(layer "F.Fab")
			(effects
				(font
					(size 1.27 1.27)
				)
			)
		)
		(duplicate_pad_numbers_are_jumpers no)
		(fp_line
			(start 0.7874 -0.4064)
			(end 0.7874 0.4064)
			(stroke
				(width 0.1524)
				(type default)
			)
			(layer "F.SilkS")
		)
		(fp_line
			(start -0.7874 -0.4064)
			(end 0.7874 -0.4064)
			(stroke
				(width 0.1524)
				(type default)
			)
			(layer "F.SilkS")
		)
		(fp_line
			(start 0.7874 0.4064)
			(end -0.7874 0.4064)
			(stroke
				(width 0.1524)
				(type default)
			)
			(layer "F.SilkS")
		)
		(fp_line
			(start -0.7874 0.4064)
			(end -0.7874 -0.4064)
			(stroke
				(width 0.1524)
				(type default)
			)
			(layer "F.SilkS")
		)
		(fp_line
			(start -0.12065 -0.305054)
			(end -0.12065 -0.2794)
			(stroke
				(width 0.1)
				(type default)
			)
			(layer "F.Fab")
		)
		(fp_line
			(start -0.67945 -0.305054)
			(end -0.12065 -0.305054)
			(stroke
				(width 0.1)
				(type default)
			)
			(layer "F.Fab")
		)
		(fp_line
			(start 0.67945 -0.3048)
			(end 0.67945 0.3048)
			(stroke
				(width 0.1)
				(type default)
			)
			(layer "F.Fab")
		)
		(fp_line
			(start 0.12065 -0.3048)
			(end 0.67945 -0.3048)
			(stroke
				(width 0.1)
				(type default)
			)
			(layer "F.Fab")
		)
		(fp_line
			(start 0.12065 -0.2794)
			(end 0.12065 -0.3048)
			(stroke
				(width 0.1)
				(type default)
			)
			(layer "F.Fab")
		)
		(fp_line
			(start -0.12065 -0.2794)
			(end 0.12065 -0.2794)
			(stroke
				(width 0.1)
				(type default)
			)
			(layer "F.Fab")
		)
		(fp_line
			(start 0.120396 0.2794)
			(end -0.12065 0.2794)
			(stroke
				(width 0.1)
				(type default)
			)
			(layer "F.Fab")
		)
		(fp_line
			(start -0.12065 0.2794)
			(end -0.12065 0.3048)
			(stroke
				(width 0.1)
				(type default)
			)
			(layer "F.Fab")
		)
		(fp_line
			(start 0.67945 0.3048)
			(end 0.120396 0.3048)
			(stroke
				(width 0.1)
				(type default)
			)
			(layer "F.Fab")
		)
		(fp_line
			(start 0.120396 0.3048)
			(end 0.120396 0.2794)
			(stroke
				(width 0.1)
				(type default)
			)
			(layer "F.Fab")
		)
		(fp_line
			(start -0.12065 0.3048)
			(end -0.67945 0.3048)
			(stroke
				(width 0.1)
				(type default)
			)
			(layer "F.Fab")
		)
		(fp_line
			(start -0.67945 0.3048)
			(end -0.67945 -0.305054)
			(stroke
				(width 0.1)
				(type default)
			)
			(layer "F.Fab")
		)
		(pad "1" smd circle
			(at -0.40005 0 90)
			(size 0 0)
			(layers "F.Cu" "F.Mask" "F.Paste")
			(net "P3V3_AUX")
		)
		(pad "2" smd circle
			(at 0.40005 0 90)
			(size 0 0)
			(layers "F.Cu" "F.Mask" "F.Paste")
			(net "GND")
		)
	)
	(footprint ""
		(layer "F.Cu")
		(at 33.782 -287.147 -90)
		(property "Reference" "R5303"
			(at 0 0 270)
			(layer "F.SilkS")
			(hide yes)
			(effects
				(font
					(size 1.27 1.27)
				)
			)
		)
		(property "Value" ""
			(at 0 0 270)
			(layer "F.Fab")
			(effects
				(font
					(size 1.27 1.27)
				)
			)
		)
		(duplicate_pad_numbers_are_jumpers no)
		(fp_line
			(start -0.7874 0.4064)
			(end -0.7874 -0.4064)
			(stroke
				(width 0.1524)
				(type default)
			)
			(layer "F.SilkS")
		)
		(fp_line
			(start 0.7874 0.4064)
			(end -0.7874 0.4064)
			(stroke
				(width 0.1524)
				(type default)
			)
			(layer "F.SilkS")
		)
		(fp_line
			(start -0.7874 -0.4064)
			(end 0.7874 -0.4064)
			(stroke
				(width 0.1524)
				(type default)
			)
			(layer "F.SilkS")
		)
		(fp_line
			(start 0.7874 -0.4064)
			(end 0.7874 0.4064)
			(stroke
				(width 0.1524)
				(type default)
			)
			(layer "F.SilkS")
		)
		(fp_line
			(start -0.67945 0.3048)
			(end -0.67945 -0.305054)
			(stroke
				(width 0.1)
				(type default)
			)
			(layer "F.Fab")
		)
		(fp_line
			(start -0.12065 0.3048)
			(end -0.67945 0.3048)
			(stroke
				(width 0.1)
				(type default)
			)
			(layer "F.Fab")
		)
		(fp_line
			(start 0.120396 0.3048)
			(end 0.120396 0.2794)
			(stroke
				(width 0.1)
				(type default)
			)
			(layer "F.Fab")
		)
		(fp_line
			(start 0.67945 0.3048)
			(end 0.120396 0.3048)
			(stroke
				(width 0.1)
				(type default)
			)
			(layer "F.Fab")
		)
		(fp_line
			(start -0.12065 0.2794)
			(end -0.12065 0.3048)
			(stroke
				(width 0.1)
				(type default)
			)
			(layer "F.Fab")
		)
		(fp_line
			(start 0.120396 0.2794)
			(end -0.12065 0.2794)
			(stroke
				(width 0.1)
				(type default)
			)
			(layer "F.Fab")
		)
		(fp_line
			(start -0.12065 -0.2794)
			(end 0.12065 -0.2794)
			(stroke
				(width 0.1)
				(type default)
			)
			(layer "F.Fab")
		)
		(fp_line
			(start 0.12065 -0.2794)
			(end 0.12065 -0.3048)
			(stroke
				(width 0.1)
				(type default)
			)
			(layer "F.Fab")
		)
		(fp_line
			(start 0.12065 -0.3048)
			(end 0.67945 -0.3048)
			(stroke
				(width 0.1)
				(type default)
			)
			(layer "F.Fab")
		)
		(fp_line
			(start 0.67945 -0.3048)
			(end 0.67945 0.3048)
			(stroke
				(width 0.1)
				(type default)
			)
			(layer "F.Fab")
		)
		(fp_line
			(start -0.67945 -0.305054)
			(end -0.12065 -0.305054)
			(stroke
				(width 0.1)
				(type default)
			)
			(layer "F.Fab")
		)
		(fp_line
			(start -0.12065 -0.305054)
			(end -0.12065 -0.2794)
			(stroke
				(width 0.1)
				(type default)
			)
			(layer "F.Fab")
		)
		(pad "1" smd rect
			(at -0.40005 0 90)
			(size 0.4572 0.508)
			(layers "F.Cu" "F.Mask" "F.Paste")
			(net "FAN_0_TACH_OL_R")
		)
		(pad "2" smd rect
			(at 0.40005 0 90)
			(size 0.4572 0.508)
			(layers "F.Cu" "F.Mask" "F.Paste")
			(net "FAN_0_TACH_OL")
		)
	)
	(footprint ""
		(layer "F.Cu")
		(at 14.478 -28.877768 180)
		(property "Reference" "D240"
			(at 5.0292 -0.088138 0)
			(unlocked yes)
			(layer "F.SilkS")
			(effects
				(font
					(size 0.7874 0.5842)
					(thickness 0.1524)
				)
				(justify left)
			)
		)
		(property "Value" ""
			(at 0 0 180)
			(layer "F.Fab")
			(effects
				(font
					(size 1.27 1.27)
				)
			)
		)
		(duplicate_pad_numbers_are_jumpers no)
		(fp_line
			(start 0.94488 0.450088)
			(end 0.94488 -0.450088)
			(stroke
				(width 0.1524)
				(type default)
			)
			(layer "F.SilkS")
		)
		(fp_line
			(start 0.94488 -0.450088)
			(end -0.854964 -0.450088)
			(stroke
				(width 0.1524)
				(type default)
			)
			(layer "F.SilkS")
		)
		(fp_line
			(start 0.870458 -0.2794)
			(end 0.845058 0.4064)
			(stroke
				(width 0.1524)
				(type default)
			)
			(layer "F.SilkS")
		)
		(fp_line
			(start 0.845058 0.4064)
			(end 0.845058 -0.381)
			(stroke
				(width 0.1524)
				(type default)
			)
			(layer "F.SilkS")
		)
		(fp_line
			(start -0.854964 0.450088)
			(end 0.925068 0.450088)
			(stroke
				(width 0.1524)
				(type default)
			)
			(layer "F.SilkS")
		)
		(fp_line
			(start -0.854964 -0.450088)
			(end -0.854964 0.450088)
			(stroke
				(width 0.1524)
				(type default)
			)
			(layer "F.SilkS")
		)
		(fp_line
			(start 0.54991 0.350012)
			(end 0.54991 -0.350012)
			(stroke
				(width 0.1)
				(type default)
			)
			(layer "F.Fab")
		)
		(fp_line
			(start 0.54991 -0.350012)
			(end -0.54991 -0.350012)
			(stroke
				(width 0.1)
				(type default)
			)
			(layer "F.Fab")
		)
		(fp_line
			(start -0.54991 0.350012)
			(end 0.54991 0.350012)
			(stroke
				(width 0.1)
				(type default)
			)
			(layer "F.Fab")
		)
		(fp_line
			(start -0.54991 -0.350012)
			(end -0.54991 0.350012)
			(stroke
				(width 0.1)
				(type default)
			)
			(layer "F.Fab")
		)
		(fp_text user "-"
			(at 2.159 0.935482 0)
			(unlocked yes)
			(layer "F.SilkS")
			(effects
				(font
					(size 1.905 1.4224)
					(thickness 0.1524)
				)
				(justify left)
			)
		)
		(fp_text user "+"
			(at -1.016 0.300482 0)
			(unlocked yes)
			(layer "F.SilkS")
			(effects
				(font
					(size 1.905 1.4224)
					(thickness 0.1524)
				)
				(justify left)
			)
		)
		(fp_text user "-"
			(at 2.48539 0.239014 0)
			(unlocked yes)
			(layer "F.Fab")
			(effects
				(font
					(size 1.905 1.4224)
					(thickness 0.1524)
				)
				(justify left)
			)
		)
		(fp_text user "+"
			(at -0.808228 0.239014 0)
			(unlocked yes)
			(layer "F.Fab")
			(effects
				(font
					(size 1.905 1.4224)
					(thickness 0.1524)
				)
				(justify left)
			)
		)
		(pad "A" smd rect
			(at -0.424942 0 180)
			(size 0.5588 0.6096)
			(layers "F.Cu" "F.Mask" "F.Paste")
			(net "GND")
		)
		(pad "C" smd rect
			(at 0.424942 0)
			(size 0.5588 0.6096)
			(layers "F.Cu" "F.Mask" "F.Paste")
			(net "FAN_4_OK_R_LED_N")
		)
	)
	(footprint ""
		(layer "F.Cu")
		(at 27.686 -124.206 -90)
		(property "Reference" "R5679"
			(at 0 0 270)
			(layer "F.SilkS")
			(hide yes)
			(effects
				(font
					(size 1.27 1.27)
				)
			)
		)
		(property "Value" ""
			(at 0 0 270)
			(layer "F.Fab")
			(effects
				(font
					(size 1.27 1.27)
				)
			)
		)
		(duplicate_pad_numbers_are_jumpers no)
		(fp_line
			(start -0.7874 0.4064)
			(end -0.7874 -0.4064)
			(stroke
				(width 0.1524)
				(type default)
			)
			(layer "F.SilkS")
		)
		(fp_line
			(start 0.7874 0.4064)
			(end -0.7874 0.4064)
			(stroke
				(width 0.1524)
				(type default)
			)
			(layer "F.SilkS")
		)
		(fp_line
			(start -0.7874 -0.4064)
			(end 0.7874 -0.4064)
			(stroke
				(width 0.1524)
				(type default)
			)
			(layer "F.SilkS")
		)
		(fp_line
			(start 0.7874 -0.4064)
			(end 0.7874 0.4064)
			(stroke
				(width 0.1524)
				(type default)
			)
			(layer "F.SilkS")
		)
		(fp_line
			(start -0.67945 0.3048)
			(end -0.67945 -0.305054)
			(stroke
				(width 0.1)
				(type default)
			)
			(layer "F.Fab")
		)
		(fp_line
			(start -0.12065 0.3048)
			(end -0.67945 0.3048)
			(stroke
				(width 0.1)
				(type default)
			)
			(layer "F.Fab")
		)
		(fp_line
			(start 0.120396 0.3048)
			(end 0.120396 0.2794)
			(stroke
				(width 0.1)
				(type default)
			)
			(layer "F.Fab")
		)
		(fp_line
			(start 0.67945 0.3048)
			(end 0.120396 0.3048)
			(stroke
				(width 0.1)
				(type default)
			)
			(layer "F.Fab")
		)
		(fp_line
			(start -0.12065 0.2794)
			(end -0.12065 0.3048)
			(stroke
				(width 0.1)
				(type default)
			)
			(layer "F.Fab")
		)
		(fp_line
			(start 0.120396 0.2794)
			(end -0.12065 0.2794)
			(stroke
				(width 0.1)
				(type default)
			)
			(layer "F.Fab")
		)
		(fp_line
			(start -0.12065 -0.2794)
			(end 0.12065 -0.2794)
			(stroke
				(width 0.1)
				(type default)
			)
			(layer "F.Fab")
		)
		(fp_line
			(start 0.12065 -0.2794)
			(end 0.12065 -0.3048)
			(stroke
				(width 0.1)
				(type default)
			)
			(layer "F.Fab")
		)
		(fp_line
			(start 0.12065 -0.3048)
			(end 0.67945 -0.3048)
			(stroke
				(width 0.1)
				(type default)
			)
			(layer "F.Fab")
		)
		(fp_line
			(start 0.67945 -0.3048)
			(end 0.67945 0.3048)
			(stroke
				(width 0.1)
				(type default)
			)
			(layer "F.Fab")
		)
		(fp_line
			(start -0.67945 -0.305054)
			(end -0.12065 -0.305054)
			(stroke
				(width 0.1)
				(type default)
			)
			(layer "F.Fab")
		)
		(fp_line
			(start -0.12065 -0.305054)
			(end -0.12065 -0.2794)
			(stroke
				(width 0.1)
				(type default)
			)
			(layer "F.Fab")
		)
		(pad "1" smd rect
			(at -0.40005 0 90)
			(size 0.4572 0.508)
			(layers "F.Cu" "F.Mask" "F.Paste")
			(net "U317_FAN FS_N")
		)
		(pad "2" smd rect
			(at 0.40005 0 90)
			(size 0.4572 0.508)
			(layers "F.Cu" "F.Mask" "F.Paste")
			(net "U317_FAN FAIL_N")
		)
	)
	(footprint ""
		(layer "F.Cu")
		(at 42.037 -179.324 180)
		(property "Reference" "R512"
			(at 0 0 180)
			(layer "F.SilkS")
			(hide yes)
			(effects
				(font
					(size 1.27 1.27)
				)
			)
		)
		(property "Value" ""
			(at 0 0 180)
			(layer "F.Fab")
			(effects
				(font
					(size 1.27 1.27)
				)
			)
		)
		(duplicate_pad_numbers_are_jumpers no)
		(fp_line
			(start 0.7874 0.4064)
			(end -0.7874 0.4064)
			(stroke
				(width 0.1524)
				(type default)
			)
			(layer "F.SilkS")
		)
		(fp_line
			(start 0.7874 -0.4064)
			(end 0.7874 0.4064)
			(stroke
				(width 0.1524)
				(type default)
			)
			(layer "F.SilkS")
		)
		(fp_line
			(start -0.7874 0.4064)
			(end -0.7874 -0.4064)
			(stroke
				(width 0.1524)
				(type default)
			)
			(layer "F.SilkS")
		)
		(fp_line
			(start -0.7874 -0.4064)
			(end 0.7874 -0.4064)
			(stroke
				(width 0.1524)
				(type default)
			)
			(layer "F.SilkS")
		)
		(fp_line
			(start 0.67945 0.3048)
			(end 0.120396 0.3048)
			(stroke
				(width 0.1)
				(type default)
			)
			(layer "F.Fab")
		)
		(fp_line
			(start 0.67945 -0.3048)
			(end 0.67945 0.3048)
			(stroke
				(width 0.1)
				(type default)
			)
			(layer "F.Fab")
		)
		(fp_line
			(start 0.12065 -0.2794)
			(end 0.12065 -0.3048)
			(stroke
				(width 0.1)
				(type default)
			)
			(layer "F.Fab")
		)
		(fp_line
			(start 0.12065 -0.3048)
			(end 0.67945 -0.3048)
			(stroke
				(width 0.1)
				(type default)
			)
			(layer "F.Fab")
		)
		(fp_line
			(start 0.120396 0.3048)
			(end 0.120396 0.2794)
			(stroke
				(width 0.1)
				(type default)
			)
			(layer "F.Fab")
		)
		(fp_line
			(start 0.120396 0.2794)
			(end -0.12065 0.2794)
			(stroke
				(width 0.1)
				(type default)
			)
			(layer "F.Fab")
		)
		(fp_line
			(start -0.12065 0.3048)
			(end -0.67945 0.3048)
			(stroke
				(width 0.1)
				(type default)
			)
			(layer "F.Fab")
		)
		(fp_line
			(start -0.12065 0.2794)
			(end -0.12065 0.3048)
			(stroke
				(width 0.1)
				(type default)
			)
			(layer "F.Fab")
		)
		(fp_line
			(start -0.12065 -0.2794)
			(end 0.12065 -0.2794)
			(stroke
				(width 0.1)
				(type default)
			)
			(layer "F.Fab")
		)
		(fp_line
			(start -0.12065 -0.305054)
			(end -0.12065 -0.2794)
			(stroke
				(width 0.1)
				(type default)
			)
			(layer "F.Fab")
		)
		(fp_line
			(start -0.67945 0.3048)
			(end -0.67945 -0.305054)
			(stroke
				(width 0.1)
				(type default)
			)
			(layer "F.Fab")
		)
		(fp_line
			(start -0.67945 -0.305054)
			(end -0.12065 -0.305054)
			(stroke
				(width 0.1)
				(type default)
			)
			(layer "F.Fab")
		)
		(pad "1" smd circle
			(at -0.40005 0 180)
			(size 0 0)
			(layers "F.Cu" "F.Mask" "F.Paste")
			(net "P3V3_AUX")
		)
		(pad "2" smd circle
			(at 0.40005 0 180)
			(size 0 0)
			(layers "F.Cu" "F.Mask" "F.Paste")
			(net "P52V_FAN_3_BUFF_EN")
		)
	)
	(footprint ""
		(layer "F.Cu")
		(at 15.377922 -288.5821 180)
		(property "Reference" "D142"
			(at 5.217922 -0.95377 0)
			(unlocked yes)
			(layer "F.SilkS")
			(effects
				(font
					(size 0.7874 0.5842)
					(thickness 0.1524)
				)
				(justify left)
			)
		)
		(property "Value" ""
			(at 0 0 180)
			(layer "F.Fab")
			(effects
				(font
					(size 1.27 1.27)
				)
			)
		)
		(duplicate_pad_numbers_are_jumpers no)
		(fp_line
			(start 2.032 0.7112)
			(end -1.651 0.7112)
			(stroke
				(width 0.1524)
				(type default)
			)
			(layer "F.SilkS")
		)
		(fp_line
			(start 2.032 -0.7112)
			(end 2.032 0.7112)
			(stroke
				(width 0.1524)
				(type default)
			)
			(layer "F.SilkS")
		)
		(fp_line
			(start 1.905 -0.6858)
			(end 1.905 0.6858)
			(stroke
				(width 0.1524)
				(type default)
			)
			(layer "F.SilkS")
		)
		(fp_line
			(start 1.778 0.6858)
			(end 1.778 -0.6858)
			(stroke
				(width 0.1524)
				(type default)
			)
			(layer "F.SilkS")
		)
		(fp_line
			(start 1.651 -0.6858)
			(end 1.651 0.6858)
			(stroke
				(width 0.1524)
				(type default)
			)
			(layer "F.SilkS")
		)
		(fp_line
			(start 0.299974 -0.500126)
			(end 0.299974 0.500126)
			(stroke
				(width 0.1524)
				(type default)
			)
			(layer "F.SilkS")
		)
		(fp_line
			(start 0.199898 0)
			(end -0.299974 -0.500126)
			(stroke
				(width 0.1524)
				(type default)
			)
			(layer "F.SilkS")
		)
		(fp_line
			(start -0.299974 0.500126)
			(end 0.199898 0)
			(stroke
				(width 0.1524)
				(type default)
			)
			(layer "F.SilkS")
		)
		(fp_line
			(start -0.299974 -0.500126)
			(end -0.299974 0.500126)
			(stroke
				(width 0.1524)
				(type default)
			)
			(layer "F.SilkS")
		)
		(fp_line
			(start -1.651 0.7112)
			(end -1.651 -0.7112)
			(stroke
				(width 0.1524)
				(type default)
			)
			(layer "F.SilkS")
		)
		(fp_line
			(start -1.651 -0.7112)
			(end 2.032 -0.7112)
			(stroke
				(width 0.1524)
				(type default)
			)
			(layer "F.SilkS")
		)
		(fp_line
			(start 1.35001 0.175006)
			(end 0.899922 0.175006)
			(stroke
				(width 0.1)
				(type default)
			)
			(layer "F.Fab")
		)
		(fp_line
			(start 1.35001 -0.225044)
			(end 1.35001 0.175006)
			(stroke
				(width 0.1)
				(type default)
			)
			(layer "F.Fab")
		)
		(fp_line
			(start 0.899922 0.700024)
			(end -0.899922 0.700024)
			(stroke
				(width 0.1)
				(type default)
			)
			(layer "F.Fab")
		)
		(fp_line
			(start 0.899922 0.175006)
			(end 0.899922 0.700024)
			(stroke
				(width 0.1)
				(type default)
			)
			(layer "F.Fab")
		)
		(fp_line
			(start 0.899922 -0.225044)
			(end 1.35001 -0.225044)
			(stroke
				(width 0.1)
				(type default)
			)
			(layer "F.Fab")
		)
		(fp_line
			(start 0.899922 -0.700024)
			(end 0.899922 -0.225044)
			(stroke
				(width 0.1)
				(type default)
			)
			(layer "F.Fab")
		)
		(fp_line
			(start 0.299974 -0.500126)
			(end 0.299974 0.500126)
			(stroke
				(width 0.1)
				(type default)
			)
			(layer "F.Fab")
		)
		(fp_line
			(start 0.199898 0)
			(end -0.299974 -0.500126)
			(stroke
				(width 0.1)
				(type default)
			)
			(layer "F.Fab")
		)
		(fp_line
			(start -0.299974 0.500126)
			(end 0.199898 0)
			(stroke
				(width 0.1)
				(type default)
			)
			(layer "F.Fab")
		)
		(fp_line
			(start -0.299974 -0.500126)
			(end -0.299974 0.500126)
			(stroke
				(width 0.1)
				(type default)
			)
			(layer "F.Fab")
		)
		(fp_line
			(start -0.899922 0.700024)
			(end -0.899922 0.175006)
			(stroke
				(width 0.1)
				(type default)
			)
			(layer "F.Fab")
		)
		(fp_line
			(start -0.899922 0.175006)
			(end -1.35001 0.175006)
			(stroke
				(width 0.1)
				(type default)
			)
			(layer "F.Fab")
		)
		(fp_line
			(start -0.899922 -0.225044)
			(end -0.899922 -0.700024)
			(stroke
				(width 0.1)
				(type default)
			)
			(layer "F.Fab")
		)
		(fp_line
			(start -0.899922 -0.700024)
			(end 0.899922 -0.700024)
			(stroke
				(width 0.1)
				(type default)
			)
			(layer "F.Fab")
		)
		(fp_line
			(start -1.35001 0.175006)
			(end -1.35001 -0.225044)
			(stroke
				(width 0.1)
				(type default)
			)
			(layer "F.Fab")
		)
		(fp_line
			(start -1.35001 -0.225044)
			(end -0.899922 -0.225044)
			(stroke
				(width 0.1)
				(type default)
			)
			(layer "F.Fab")
		)
		(fp_text user "-"
			(at 0.518922 -1.27635 180)
			(unlocked yes)
			(layer "F.SilkS")
			(effects
				(font
					(size 1.905 1.4224)
					(thickness 0.1524)
				)
				(justify left)
			)
		)
		(fp_text user "+"
			(at -2.808478 0.32385 180)
			(unlocked yes)
			(layer "F.SilkS")
			(effects
				(font
					(size 1.905 1.4224)
					(thickness 0.1524)
				)
				(justify left)
			)
		)
		(fp_text user "-"
			(at 1.8288 -0.24765 180)
			(unlocked yes)
			(layer "F.Fab")
			(effects
				(font
					(size 1.905 1.4224)
					(thickness 0.1524)
				)
				(justify left)
			)
		)
		(fp_text user "+"
			(at -2.794 -0.19685 180)
			(unlocked yes)
			(layer "F.Fab")
			(effects
				(font
					(size 1.905 1.4224)
					(thickness 0.1524)
				)
				(justify left)
			)
		)
		(pad "1" smd rect
			(at -1.0922 0)
			(size 0.8128 0.8636)
			(layers "F.Cu" "F.Mask" "F.Paste")
			(net "FAN_7_TACH_IL_R")
		)
		(pad "2" smd rect
			(at 1.0922 0 180)
			(size 0.8128 0.8636)
			(layers "F.Cu" "F.Mask" "F.Paste")
			(net "FAN_7_TACH_IL_D")
		)
	)
	(footprint ""
		(layer "F.Cu")
		(at 37.465 -250.19 180)
		(property "Reference" "PR29"
			(at 0 0 180)
			(layer "F.SilkS")
			(hide yes)
			(effects
				(font
					(size 1.27 1.27)
				)
			)
		)
		(property "Value" ""
			(at 0 0 180)
			(layer "F.Fab")
			(effects
				(font
					(size 1.27 1.27)
				)
			)
		)
		(duplicate_pad_numbers_are_jumpers no)
		(fp_line
			(start 0.7874 0.4064)
			(end -0.7874 0.4064)
			(stroke
				(width 0.1524)
				(type default)
			)
			(layer "F.SilkS")
		)
		(fp_line
			(start 0.7874 -0.4064)
			(end 0.7874 0.4064)
			(stroke
				(width 0.1524)
				(type default)
			)
			(layer "F.SilkS")
		)
		(fp_line
			(start -0.7874 0.4064)
			(end -0.7874 -0.4064)
			(stroke
				(width 0.1524)
				(type default)
			)
			(layer "F.SilkS")
		)
		(fp_line
			(start -0.7874 -0.4064)
			(end 0.7874 -0.4064)
			(stroke
				(width 0.1524)
				(type default)
			)
			(layer "F.SilkS")
		)
		(fp_line
			(start 0.67945 0.3048)
			(end 0.120396 0.3048)
			(stroke
				(width 0.1)
				(type default)
			)
			(layer "F.Fab")
		)
		(fp_line
			(start 0.67945 -0.3048)
			(end 0.67945 0.3048)
			(stroke
				(width 0.1)
				(type default)
			)
			(layer "F.Fab")
		)
		(fp_line
			(start 0.12065 -0.2794)
			(end 0.12065 -0.3048)
			(stroke
				(width 0.1)
				(type default)
			)
			(layer "F.Fab")
		)
		(fp_line
			(start 0.12065 -0.3048)
			(end 0.67945 -0.3048)
			(stroke
				(width 0.1)
				(type default)
			)
			(layer "F.Fab")
		)
		(fp_line
			(start 0.120396 0.3048)
			(end 0.120396 0.2794)
			(stroke
				(width 0.1)
				(type default)
			)
			(layer "F.Fab")
		)
		(fp_line
			(start 0.120396 0.2794)
			(end -0.12065 0.2794)
			(stroke
				(width 0.1)
				(type default)
			)
			(layer "F.Fab")
		)
		(fp_line
			(start -0.12065 0.3048)
			(end -0.67945 0.3048)
			(stroke
				(width 0.1)
				(type default)
			)
			(layer "F.Fab")
		)
		(fp_line
			(start -0.12065 0.2794)
			(end -0.12065 0.3048)
			(stroke
				(width 0.1)
				(type default)
			)
			(layer "F.Fab")
		)
		(fp_line
			(start -0.12065 -0.2794)
			(end 0.12065 -0.2794)
			(stroke
				(width 0.1)
				(type default)
			)
			(layer "F.Fab")
		)
		(fp_line
			(start -0.12065 -0.305054)
			(end -0.12065 -0.2794)
			(stroke
				(width 0.1)
				(type default)
			)
			(layer "F.Fab")
		)
		(fp_line
			(start -0.67945 0.3048)
			(end -0.67945 -0.305054)
			(stroke
				(width 0.1)
				(type default)
			)
			(layer "F.Fab")
		)
		(fp_line
			(start -0.67945 -0.305054)
			(end -0.12065 -0.305054)
			(stroke
				(width 0.1)
				(type default)
			)
			(layer "F.Fab")
		)
		(pad "1" smd circle
			(at -0.40005 0 180)
			(size 0 0)
			(layers "F.Cu" "F.Mask" "F.Paste")
			(net "FAN_1_P3V_R")
		)
		(pad "2" smd circle
			(at 0.40005 0 180)
			(size 0 0)
			(layers "F.Cu" "F.Mask" "F.Paste")
			(net "FAN_1_MODE")
		)
	)
	(footprint ""
		(layer "F.Cu")
		(at 30.226 -121.92 90)
		(property "Reference" "R4936"
			(at 0 0 90)
			(layer "F.SilkS")
			(hide yes)
			(effects
				(font
					(size 1.27 1.27)
				)
			)
		)
		(property "Value" ""
			(at 0 0 90)
			(layer "F.Fab")
			(effects
				(font
					(size 1.27 1.27)
				)
			)
		)
		(duplicate_pad_numbers_are_jumpers no)
		(fp_line
			(start 0.7874 -0.4064)
			(end 0.7874 0.4064)
			(stroke
				(width 0.1524)
				(type default)
			)
			(layer "F.SilkS")
		)
		(fp_line
			(start -0.7874 -0.4064)
			(end 0.7874 -0.4064)
			(stroke
				(width 0.1524)
				(type default)
			)
			(layer "F.SilkS")
		)
		(fp_line
			(start 0.7874 0.4064)
			(end -0.7874 0.4064)
			(stroke
				(width 0.1524)
				(type default)
			)
			(layer "F.SilkS")
		)
		(fp_line
			(start -0.7874 0.4064)
			(end -0.7874 -0.4064)
			(stroke
				(width 0.1524)
				(type default)
			)
			(layer "F.SilkS")
		)
		(fp_line
			(start -0.12065 -0.305054)
			(end -0.12065 -0.2794)
			(stroke
				(width 0.1)
				(type default)
			)
			(layer "F.Fab")
		)
		(fp_line
			(start -0.67945 -0.305054)
			(end -0.12065 -0.305054)
			(stroke
				(width 0.1)
				(type default)
			)
			(layer "F.Fab")
		)
		(fp_line
			(start 0.67945 -0.3048)
			(end 0.67945 0.3048)
			(stroke
				(width 0.1)
				(type default)
			)
			(layer "F.Fab")
		)
		(fp_line
			(start 0.12065 -0.3048)
			(end 0.67945 -0.3048)
			(stroke
				(width 0.1)
				(type default)
			)
			(layer "F.Fab")
		)
		(fp_line
			(start 0.12065 -0.2794)
			(end 0.12065 -0.3048)
			(stroke
				(width 0.1)
				(type default)
			)
			(layer "F.Fab")
		)
		(fp_line
			(start -0.12065 -0.2794)
			(end 0.12065 -0.2794)
			(stroke
				(width 0.1)
				(type default)
			)
			(layer "F.Fab")
		)
		(fp_line
			(start 0.120396 0.2794)
			(end -0.12065 0.2794)
			(stroke
				(width 0.1)
				(type default)
			)
			(layer "F.Fab")
		)
		(fp_line
			(start -0.12065 0.2794)
			(end -0.12065 0.3048)
			(stroke
				(width 0.1)
				(type default)
			)
			(layer "F.Fab")
		)
		(fp_line
			(start 0.67945 0.3048)
			(end 0.120396 0.3048)
			(stroke
				(width 0.1)
				(type default)
			)
			(layer "F.Fab")
		)
		(fp_line
			(start 0.120396 0.3048)
			(end 0.120396 0.2794)
			(stroke
				(width 0.1)
				(type default)
			)
			(layer "F.Fab")
		)
		(fp_line
			(start -0.12065 0.3048)
			(end -0.67945 0.3048)
			(stroke
				(width 0.1)
				(type default)
			)
			(layer "F.Fab")
		)
		(fp_line
			(start -0.67945 0.3048)
			(end -0.67945 -0.305054)
			(stroke
				(width 0.1)
				(type default)
			)
			(layer "F.Fab")
		)
		(pad "1" smd circle
			(at -0.40005 0 90)
			(size 0 0)
			(layers "F.Cu" "F.Mask" "F.Paste")
			(net "GND")
		)
		(pad "2" smd circle
			(at 0.40005 0 90)
			(size 0 0)
			(layers "F.Cu" "F.Mask" "F.Paste")
			(net "MAX31790_U317_SPIN_START")
		)
	)
	(footprint ""
		(layer "F.Cu")
		(at 42.291 -260.477 180)
		(property "Reference" "PR7"
			(at 0 0 180)
			(layer "F.SilkS")
			(hide yes)
			(effects
				(font
					(size 1.27 1.27)
				)
			)
		)
		(property "Value" ""
			(at 0 0 180)
			(layer "F.Fab")
			(effects
				(font
					(size 1.27 1.27)
				)
			)
		)
		(duplicate_pad_numbers_are_jumpers no)
		(fp_line
			(start 0.7874 0.4064)
			(end -0.7874 0.4064)
			(stroke
				(width 0.1524)
				(type default)
			)
			(layer "F.SilkS")
		)
		(fp_line
			(start 0.7874 -0.4064)
			(end 0.7874 0.4064)
			(stroke
				(width 0.1524)
				(type default)
			)
			(layer "F.SilkS")
		)
		(fp_line
			(start -0.7874 0.4064)
			(end -0.7874 -0.4064)
			(stroke
				(width 0.1524)
				(type default)
			)
			(layer "F.SilkS")
		)
		(fp_line
			(start -0.7874 -0.4064)
			(end 0.7874 -0.4064)
			(stroke
				(width 0.1524)
				(type default)
			)
			(layer "F.SilkS")
		)
		(fp_line
			(start 0.67945 0.3048)
			(end 0.120396 0.3048)
			(stroke
				(width 0.1)
				(type default)
			)
			(layer "F.Fab")
		)
		(fp_line
			(start 0.67945 -0.3048)
			(end 0.67945 0.3048)
			(stroke
				(width 0.1)
				(type default)
			)
			(layer "F.Fab")
		)
		(fp_line
			(start 0.12065 -0.2794)
			(end 0.12065 -0.3048)
			(stroke
				(width 0.1)
				(type default)
			)
			(layer "F.Fab")
		)
		(fp_line
			(start 0.12065 -0.3048)
			(end 0.67945 -0.3048)
			(stroke
				(width 0.1)
				(type default)
			)
			(layer "F.Fab")
		)
		(fp_line
			(start 0.120396 0.3048)
			(end 0.120396 0.2794)
			(stroke
				(width 0.1)
				(type default)
			)
			(layer "F.Fab")
		)
		(fp_line
			(start 0.120396 0.2794)
			(end -0.12065 0.2794)
			(stroke
				(width 0.1)
				(type default)
			)
			(layer "F.Fab")
		)
		(fp_line
			(start -0.12065 0.3048)
			(end -0.67945 0.3048)
			(stroke
				(width 0.1)
				(type default)
			)
			(layer "F.Fab")
		)
		(fp_line
			(start -0.12065 0.2794)
			(end -0.12065 0.3048)
			(stroke
				(width 0.1)
				(type default)
			)
			(layer "F.Fab")
		)
		(fp_line
			(start -0.12065 -0.2794)
			(end 0.12065 -0.2794)
			(stroke
				(width 0.1)
				(type default)
			)
			(layer "F.Fab")
		)
		(fp_line
			(start -0.12065 -0.305054)
			(end -0.12065 -0.2794)
			(stroke
				(width 0.1)
				(type default)
			)
			(layer "F.Fab")
		)
		(fp_line
			(start -0.67945 0.3048)
			(end -0.67945 -0.305054)
			(stroke
				(width 0.1)
				(type default)
			)
			(layer "F.Fab")
		)
		(fp_line
			(start -0.67945 -0.305054)
			(end -0.12065 -0.305054)
			(stroke
				(width 0.1)
				(type default)
			)
			(layer "F.Fab")
		)
		(pad "1" smd circle
			(at -0.40005 0 180)
			(size 0 0)
			(layers "F.Cu" "F.Mask" "F.Paste")
			(net "FAN_0_MODE")
		)
		(pad "2" smd circle
			(at 0.40005 0 180)
			(size 0 0)
			(layers "F.Cu" "F.Mask" "F.Paste")
			(net "GND")
		)
	)
	(footprint ""
		(layer "F.Cu")
		(at 14.859 -125.857)
		(property "Reference" "R5612"
			(at 0 0 0)
			(layer "F.SilkS")
			(hide yes)
			(effects
				(font
					(size 1.27 1.27)
				)
			)
		)
		(property "Value" ""
			(at 0 0 0)
			(layer "F.Fab")
			(effects
				(font
					(size 1.27 1.27)
				)
			)
		)
		(duplicate_pad_numbers_are_jumpers no)
		(fp_line
			(start -0.7874 -0.4064)
			(end 0.7874 -0.4064)
			(stroke
				(width 0.1524)
				(type default)
			)
			(layer "F.SilkS")
		)
		(fp_line
			(start -0.7874 0.4064)
			(end -0.7874 -0.4064)
			(stroke
				(width 0.1524)
				(type default)
			)
			(layer "F.SilkS")
		)
		(fp_line
			(start 0.7874 -0.4064)
			(end 0.7874 0.4064)
			(stroke
				(width 0.1524)
				(type default)
			)
			(layer "F.SilkS")
		)
		(fp_line
			(start 0.7874 0.4064)
			(end -0.7874 0.4064)
			(stroke
				(width 0.1524)
				(type default)
			)
			(layer "F.SilkS")
		)
		(fp_line
			(start -0.67945 -0.305054)
			(end -0.12065 -0.305054)
			(stroke
				(width 0.1)
				(type default)
			)
			(layer "F.Fab")
		)
		(fp_line
			(start -0.67945 0.3048)
			(end -0.67945 -0.305054)
			(stroke
				(width 0.1)
				(type default)
			)
			(layer "F.Fab")
		)
		(fp_line
			(start -0.12065 -0.305054)
			(end -0.12065 -0.2794)
			(stroke
				(width 0.1)
				(type default)
			)
			(layer "F.Fab")
		)
		(fp_line
			(start -0.12065 -0.2794)
			(end 0.12065 -0.2794)
			(stroke
				(width 0.1)
				(type default)
			)
			(layer "F.Fab")
		)
		(fp_line
			(start -0.12065 0.2794)
			(end -0.12065 0.3048)
			(stroke
				(width 0.1)
				(type default)
			)
			(layer "F.Fab")
		)
		(fp_line
			(start -0.12065 0.3048)
			(end -0.67945 0.3048)
			(stroke
				(width 0.1)
				(type default)
			)
			(layer "F.Fab")
		)
		(fp_line
			(start 0.120396 0.2794)
			(end -0.12065 0.2794)
			(stroke
				(width 0.1)
				(type default)
			)
			(layer "F.Fab")
		)
		(fp_line
			(start 0.120396 0.3048)
			(end 0.120396 0.2794)
			(stroke
				(width 0.1)
				(type default)
			)
			(layer "F.Fab")
		)
		(fp_line
			(start 0.12065 -0.3048)
			(end 0.67945 -0.3048)
			(stroke
				(width 0.1)
				(type default)
			)
			(layer "F.Fab")
		)
		(fp_line
			(start 0.12065 -0.2794)
			(end 0.12065 -0.3048)
			(stroke
				(width 0.1)
				(type default)
			)
			(layer "F.Fab")
		)
		(fp_line
			(start 0.67945 -0.3048)
			(end 0.67945 0.3048)
			(stroke
				(width 0.1)
				(type default)
			)
			(layer "F.Fab")
		)
		(fp_line
			(start 0.67945 0.3048)
			(end 0.120396 0.3048)
			(stroke
				(width 0.1)
				(type default)
			)
			(layer "F.Fab")
		)
		(pad "1" smd rect
			(at -0.40005 0 180)
			(size 0.4572 0.508)
			(layers "F.Cu" "F.Mask" "F.Paste")
			(net "FAN_4_TACH_OL")
		)
		(pad "2" smd rect
			(at 0.40005 0 180)
			(size 0.4572 0.508)
			(layers "F.Cu" "F.Mask" "F.Paste")
			(net "FAN_4_TACH_OL_R1")
		)
	)
	(footprint ""
		(layer "F.Cu")
		(at 6.096 -63.881 180)
		(property "Reference" "PR51"
			(at 0 0 180)
			(layer "F.SilkS")
			(hide yes)
			(effects
				(font
					(size 1.27 1.27)
				)
			)
		)
		(property "Value" ""
			(at 0 0 180)
			(layer "F.Fab")
			(effects
				(font
					(size 1.27 1.27)
				)
			)
		)
		(duplicate_pad_numbers_are_jumpers no)
		(fp_line
			(start 0.7874 0.4064)
			(end -0.7874 0.4064)
			(stroke
				(width 0.1524)
				(type default)
			)
			(layer "F.SilkS")
		)
		(fp_line
			(start 0.7874 -0.4064)
			(end 0.7874 0.4064)
			(stroke
				(width 0.1524)
				(type default)
			)
			(layer "F.SilkS")
		)
		(fp_line
			(start -0.7874 0.4064)
			(end -0.7874 -0.4064)
			(stroke
				(width 0.1524)
				(type default)
			)
			(layer "F.SilkS")
		)
		(fp_line
			(start -0.7874 -0.4064)
			(end 0.7874 -0.4064)
			(stroke
				(width 0.1524)
				(type default)
			)
			(layer "F.SilkS")
		)
		(fp_line
			(start 0.67945 0.3048)
			(end 0.120396 0.3048)
			(stroke
				(width 0.1)
				(type default)
			)
			(layer "F.Fab")
		)
		(fp_line
			(start 0.67945 -0.3048)
			(end 0.67945 0.3048)
			(stroke
				(width 0.1)
				(type default)
			)
			(layer "F.Fab")
		)
		(fp_line
			(start 0.12065 -0.2794)
			(end 0.12065 -0.3048)
			(stroke
				(width 0.1)
				(type default)
			)
			(layer "F.Fab")
		)
		(fp_line
			(start 0.12065 -0.3048)
			(end 0.67945 -0.3048)
			(stroke
				(width 0.1)
				(type default)
			)
			(layer "F.Fab")
		)
		(fp_line
			(start 0.120396 0.3048)
			(end 0.120396 0.2794)
			(stroke
				(width 0.1)
				(type default)
			)
			(layer "F.Fab")
		)
		(fp_line
			(start 0.120396 0.2794)
			(end -0.12065 0.2794)
			(stroke
				(width 0.1)
				(type default)
			)
			(layer "F.Fab")
		)
		(fp_line
			(start -0.12065 0.3048)
			(end -0.67945 0.3048)
			(stroke
				(width 0.1)
				(type default)
			)
			(layer "F.Fab")
		)
		(fp_line
			(start -0.12065 0.2794)
			(end -0.12065 0.3048)
			(stroke
				(width 0.1)
				(type default)
			)
			(layer "F.Fab")
		)
		(fp_line
			(start -0.12065 -0.2794)
			(end 0.12065 -0.2794)
			(stroke
				(width 0.1)
				(type default)
			)
			(layer "F.Fab")
		)
		(fp_line
			(start -0.12065 -0.305054)
			(end -0.12065 -0.2794)
			(stroke
				(width 0.1)
				(type default)
			)
			(layer "F.Fab")
		)
		(fp_line
			(start -0.67945 0.3048)
			(end -0.67945 -0.305054)
			(stroke
				(width 0.1)
				(type default)
			)
			(layer "F.Fab")
		)
		(fp_line
			(start -0.67945 -0.305054)
			(end -0.12065 -0.305054)
			(stroke
				(width 0.1)
				(type default)
			)
			(layer "F.Fab")
		)
		(pad "1" smd circle
			(at -0.40005 0 180)
			(size 0 0)
			(layers "F.Cu" "F.Mask" "F.Paste")
			(net "FAN_4_MODE")
		)
		(pad "2" smd circle
			(at 0.40005 0 180)
			(size 0 0)
			(layers "F.Cu" "F.Mask" "F.Paste")
			(net "GND")
		)
	)
	(footprint ""
		(layer "F.Cu")
		(at 14.605 -203.073 90)
		(property "Reference" "R5699"
			(at 0 0 90)
			(layer "F.SilkS")
			(hide yes)
			(effects
				(font
					(size 1.27 1.27)
				)
			)
		)
		(property "Value" ""
			(at 0 0 90)
			(layer "F.Fab")
			(effects
				(font
					(size 1.27 1.27)
				)
			)
		)
		(duplicate_pad_numbers_are_jumpers no)
		(fp_line
			(start 0.7874 -0.4064)
			(end 0.7874 0.4064)
			(stroke
				(width 0.1524)
				(type default)
			)
			(layer "F.SilkS")
		)
		(fp_line
			(start -0.7874 -0.4064)
			(end 0.7874 -0.4064)
			(stroke
				(width 0.1524)
				(type default)
			)
			(layer "F.SilkS")
		)
		(fp_line
			(start 0.7874 0.4064)
			(end -0.7874 0.4064)
			(stroke
				(width 0.1524)
				(type default)
			)
			(layer "F.SilkS")
		)
		(fp_line
			(start -0.7874 0.4064)
			(end -0.7874 -0.4064)
			(stroke
				(width 0.1524)
				(type default)
			)
			(layer "F.SilkS")
		)
		(fp_line
			(start -0.12065 -0.305054)
			(end -0.12065 -0.2794)
			(stroke
				(width 0.1)
				(type default)
			)
			(layer "F.Fab")
		)
		(fp_line
			(start -0.67945 -0.305054)
			(end -0.12065 -0.305054)
			(stroke
				(width 0.1)
				(type default)
			)
			(layer "F.Fab")
		)
		(fp_line
			(start 0.67945 -0.3048)
			(end 0.67945 0.3048)
			(stroke
				(width 0.1)
				(type default)
			)
			(layer "F.Fab")
		)
		(fp_line
			(start 0.12065 -0.3048)
			(end 0.67945 -0.3048)
			(stroke
				(width 0.1)
				(type default)
			)
			(layer "F.Fab")
		)
		(fp_line
			(start 0.12065 -0.2794)
			(end 0.12065 -0.3048)
			(stroke
				(width 0.1)
				(type default)
			)
			(layer "F.Fab")
		)
		(fp_line
			(start -0.12065 -0.2794)
			(end 0.12065 -0.2794)
			(stroke
				(width 0.1)
				(type default)
			)
			(layer "F.Fab")
		)
		(fp_line
			(start 0.120396 0.2794)
			(end -0.12065 0.2794)
			(stroke
				(width 0.1)
				(type default)
			)
			(layer "F.Fab")
		)
		(fp_line
			(start -0.12065 0.2794)
			(end -0.12065 0.3048)
			(stroke
				(width 0.1)
				(type default)
			)
			(layer "F.Fab")
		)
		(fp_line
			(start 0.67945 0.3048)
			(end 0.120396 0.3048)
			(stroke
				(width 0.1)
				(type default)
			)
			(layer "F.Fab")
		)
		(fp_line
			(start 0.120396 0.3048)
			(end 0.120396 0.2794)
			(stroke
				(width 0.1)
				(type default)
			)
			(layer "F.Fab")
		)
		(fp_line
			(start -0.12065 0.3048)
			(end -0.67945 0.3048)
			(stroke
				(width 0.1)
				(type default)
			)
			(layer "F.Fab")
		)
		(fp_line
			(start -0.67945 0.3048)
			(end -0.67945 -0.305054)
			(stroke
				(width 0.1)
				(type default)
			)
			(layer "F.Fab")
		)
		(pad "1" smd rect
			(at -0.40005 0 270)
			(size 0.4572 0.508)
			(layers "F.Cu" "F.Mask" "F.Paste")
			(net "P12V_LED_FAN6")
		)
		(pad "2" smd rect
			(at 0.40005 0 270)
			(size 0.4572 0.508)
			(layers "F.Cu" "F.Mask" "F.Paste")
			(net "P12V_LED_R_FAN6")
		)
	)
	(footprint ""
		(layer "F.Cu")
		(at 11.938 -98.552 180)
		(property "Reference" "U410"
			(at 1.17602 1.82499 0)
			(unlocked yes)
			(layer "F.SilkS")
			(effects
				(font
					(size 0.7874 0.5842)
					(thickness 0.1524)
				)
				(justify left)
			)
		)
		(property "Value" ""
			(at 0 0 180)
			(layer "F.Fab")
			(effects
				(font
					(size 1.27 1.27)
				)
			)
		)
		(duplicate_pad_numbers_are_jumpers no)
		(fp_line
			(start 1.335278 1.100074)
			(end 1.335278 -1.100074)
			(stroke
				(width 0.1524)
				(type default)
			)
			(layer "F.SilkS")
		)
		(fp_line
			(start 1.335278 -1.100074)
			(end -1.335278 -1.100074)
			(stroke
				(width 0.1524)
				(type default)
			)
			(layer "F.SilkS")
		)
		(fp_line
			(start -1.335278 1.100074)
			(end 1.335278 1.100074)
			(stroke
				(width 0.1524)
				(type default)
			)
			(layer "F.SilkS")
		)
		(fp_line
			(start -1.335278 -1.100074)
			(end -1.335278 1.100074)
			(stroke
				(width 0.1524)
				(type default)
			)
			(layer "F.SilkS")
		)
		(fp_line
			(start 0.674878 1.100074)
			(end 0.674878 -1.100074)
			(stroke
				(width 0.1)
				(type default)
			)
			(layer "F.Fab")
		)
		(fp_line
			(start 0.674878 -1.100074)
			(end -0.674878 -1.100074)
			(stroke
				(width 0.1)
				(type default)
			)
			(layer "F.Fab")
		)
		(fp_line
			(start -0.674878 1.100074)
			(end 0.674878 1.100074)
			(stroke
				(width 0.1)
				(type default)
			)
			(layer "F.Fab")
		)
		(fp_line
			(start -0.674878 -1.100074)
			(end -0.674878 1.100074)
			(stroke
				(width 0.1)
				(type default)
			)
			(layer "F.Fab")
		)
		(pad "D" smd rect
			(at 0.8001 0 90)
			(size 0.6096 0.8128)
			(layers "F.Cu" "F.Mask" "F.Paste")
			(net "U410_D1")
		)
		(pad "G" smd rect
			(at -0.8001 -0.649986 90)
			(size 0.6096 0.8128)
			(layers "F.Cu" "F.Mask" "F.Paste")
			(net "FAN_5_PRESENT")
		)
		(pad "S" smd rect
			(at -0.8001 0.649986 90)
			(size 0.6096 0.8128)
			(layers "F.Cu" "F.Mask" "F.Paste")
			(net "GND")
		)
	)
	(footprint ""
		(layer "F.Cu")
		(at 37.338 -207.038956 180)
		(property "Reference" "R5200"
			(at 0 0 180)
			(layer "F.SilkS")
			(hide yes)
			(effects
				(font
					(size 1.27 1.27)
				)
			)
		)
		(property "Value" ""
			(at 0 0 180)
			(layer "F.Fab")
			(effects
				(font
					(size 1.27 1.27)
				)
			)
		)
		(duplicate_pad_numbers_are_jumpers no)
		(fp_line
			(start 0.7874 0.4064)
			(end -0.7874 0.4064)
			(stroke
				(width 0.1524)
				(type default)
			)
			(layer "F.SilkS")
		)
		(fp_line
			(start 0.7874 -0.4064)
			(end 0.7874 0.4064)
			(stroke
				(width 0.1524)
				(type default)
			)
			(layer "F.SilkS")
		)
		(fp_line
			(start -0.7874 0.4064)
			(end -0.7874 -0.4064)
			(stroke
				(width 0.1524)
				(type default)
			)
			(layer "F.SilkS")
		)
		(fp_line
			(start -0.7874 -0.4064)
			(end 0.7874 -0.4064)
			(stroke
				(width 0.1524)
				(type default)
			)
			(layer "F.SilkS")
		)
		(fp_line
			(start 0.67945 0.3048)
			(end 0.120396 0.3048)
			(stroke
				(width 0.1)
				(type default)
			)
			(layer "F.Fab")
		)
		(fp_line
			(start 0.67945 -0.3048)
			(end 0.67945 0.3048)
			(stroke
				(width 0.1)
				(type default)
			)
			(layer "F.Fab")
		)
		(fp_line
			(start 0.12065 -0.2794)
			(end 0.12065 -0.3048)
			(stroke
				(width 0.1)
				(type default)
			)
			(layer "F.Fab")
		)
		(fp_line
			(start 0.12065 -0.3048)
			(end 0.67945 -0.3048)
			(stroke
				(width 0.1)
				(type default)
			)
			(layer "F.Fab")
		)
		(fp_line
			(start 0.120396 0.3048)
			(end 0.120396 0.2794)
			(stroke
				(width 0.1)
				(type default)
			)
			(layer "F.Fab")
		)
		(fp_line
			(start 0.120396 0.2794)
			(end -0.12065 0.2794)
			(stroke
				(width 0.1)
				(type default)
			)
			(layer "F.Fab")
		)
		(fp_line
			(start -0.12065 0.3048)
			(end -0.67945 0.3048)
			(stroke
				(width 0.1)
				(type default)
			)
			(layer "F.Fab")
		)
		(fp_line
			(start -0.12065 0.2794)
			(end -0.12065 0.3048)
			(stroke
				(width 0.1)
				(type default)
			)
			(layer "F.Fab")
		)
		(fp_line
			(start -0.12065 -0.2794)
			(end 0.12065 -0.2794)
			(stroke
				(width 0.1)
				(type default)
			)
			(layer "F.Fab")
		)
		(fp_line
			(start -0.12065 -0.305054)
			(end -0.12065 -0.2794)
			(stroke
				(width 0.1)
				(type default)
			)
			(layer "F.Fab")
		)
		(fp_line
			(start -0.67945 0.3048)
			(end -0.67945 -0.305054)
			(stroke
				(width 0.1)
				(type default)
			)
			(layer "F.Fab")
		)
		(fp_line
			(start -0.67945 -0.305054)
			(end -0.12065 -0.305054)
			(stroke
				(width 0.1)
				(type default)
			)
			(layer "F.Fab")
		)
		(pad "1" smd circle
			(at -0.40005 0 180)
			(size 0 0)
			(layers "F.Cu" "F.Mask" "F.Paste")
			(net "FAN_1_PWM_IL_R")
		)
		(pad "2" smd circle
			(at 0.40005 0 180)
			(size 0 0)
			(layers "F.Cu" "F.Mask" "F.Paste")
			(net "FAN_1_PWM_IL")
		)
	)
	(footprint ""
		(layer "F.Cu")
		(at 12.94892 -313.74588)
		(property "Reference" "ME3"
			(at 0 0 0)
			(layer "F.SilkS")
			(hide yes)
			(effects
				(font
					(size 1.27 1.27)
				)
			)
		)
		(property "Value" ""
			(at 0 0 0)
			(layer "F.Fab")
			(effects
				(font
					(size 1.27 1.27)
				)
			)
		)
		(duplicate_pad_numbers_are_jumpers no)
		(fp_line
			(start 0.089408 -2.660396)
			(end 1.561846 -4.072636)
			(stroke
				(width 0.1)
				(type default)
			)
			(layer "F.SilkS")
		)
		(fp_line
			(start 0.089408 -2.660396)
			(end 1.561846 -4.072636)
			(stroke
				(width 0.1)
				(type default)
			)
			(layer "F.SilkS")
		)
		(fp_line
			(start 0.098806 -2.611628)
			(end 1.482344 -3.938778)
			(stroke
				(width 0.1)
				(type default)
			)
			(layer "F.SilkS")
		)
		(fp_line
			(start 0.098806 -2.611628)
			(end 1.482344 -3.938778)
			(stroke
				(width 0.1)
				(type default)
			)
			(layer "F.SilkS")
		)
		(fp_line
			(start 0.108204 -2.563114)
			(end 1.4224 -3.823716)
			(stroke
				(width 0.1)
				(type default)
			)
			(layer "F.SilkS")
		)
		(fp_line
			(start 0.108204 -2.563114)
			(end 1.4224 -3.823716)
			(stroke
				(width 0.1)
				(type default)
			)
			(layer "F.SilkS")
		)
		(fp_line
			(start 0.117602 -2.514346)
			(end 1.38557 -3.730498)
			(stroke
				(width 0.1)
				(type default)
			)
			(layer "F.SilkS")
		)
		(fp_line
			(start 0.117602 -2.514346)
			(end 1.38557 -3.730498)
			(stroke
				(width 0.1)
				(type default)
			)
			(layer "F.SilkS")
		)
		(fp_line
			(start 0.127254 -2.465832)
			(end 1.360932 -3.649218)
			(stroke
				(width 0.1)
				(type default)
			)
			(layer "F.SilkS")
		)
		(fp_line
			(start 0.127254 -2.465832)
			(end 1.360932 -3.649218)
			(stroke
				(width 0.1)
				(type default)
			)
			(layer "F.SilkS")
		)
		(fp_line
			(start 0.139954 -2.420366)
			(end 1.336548 -3.568192)
			(stroke
				(width 0.1)
				(type default)
			)
			(layer "F.SilkS")
		)
		(fp_line
			(start 0.139954 -2.420366)
			(end 1.336548 -3.568192)
			(stroke
				(width 0.1)
				(type default)
			)
			(layer "F.SilkS")
		)
		(fp_line
			(start 0.152908 -2.3749)
			(end 1.31445 -3.489198)
			(stroke
				(width 0.1)
				(type default)
			)
			(layer "F.SilkS")
		)
		(fp_line
			(start 0.152908 -2.3749)
			(end 1.31445 -3.489198)
			(stroke
				(width 0.1)
				(type default)
			)
			(layer "F.SilkS")
		)
		(fp_line
			(start 0.165608 -2.329434)
			(end 1.307592 -3.424936)
			(stroke
				(width 0.1)
				(type default)
			)
			(layer "F.SilkS")
		)
		(fp_line
			(start 0.165608 -2.329434)
			(end 1.307592 -3.424936)
			(stroke
				(width 0.1)
				(type default)
			)
			(layer "F.SilkS")
		)
		(fp_line
			(start 0.178562 -2.284222)
			(end 1.300988 -3.360674)
			(stroke
				(width 0.1)
				(type default)
			)
			(layer "F.SilkS")
		)
		(fp_line
			(start 0.178562 -2.284222)
			(end 1.300988 -3.360674)
			(stroke
				(width 0.1)
				(type default)
			)
			(layer "F.SilkS")
		)
		(fp_line
			(start 0.191516 -2.238756)
			(end 1.29413 -3.296412)
			(stroke
				(width 0.1)
				(type default)
			)
			(layer "F.SilkS")
		)
		(fp_line
			(start 0.191516 -2.238756)
			(end 1.29413 -3.296412)
			(stroke
				(width 0.1)
				(type default)
			)
			(layer "F.SilkS")
		)
		(fp_line
			(start 0.205994 -2.195068)
			(end 1.287526 -3.232404)
			(stroke
				(width 0.1)
				(type default)
			)
			(layer "F.SilkS")
		)
		(fp_line
			(start 0.205994 -2.195068)
			(end 1.287526 -3.232404)
			(stroke
				(width 0.1)
				(type default)
			)
			(layer "F.SilkS")
		)
		(fp_line
			(start 0.222504 -2.153158)
			(end 1.2827 -3.170174)
			(stroke
				(width 0.1)
				(type default)
			)
			(layer "F.SilkS")
		)
		(fp_line
			(start 0.222504 -2.153158)
			(end 1.2827 -3.170174)
			(stroke
				(width 0.1)
				(type default)
			)
			(layer "F.SilkS")
		)
		(fp_line
			(start 0.239268 -2.111502)
			(end 1.287018 -3.11658)
			(stroke
				(width 0.1)
				(type default)
			)
			(layer "F.SilkS")
		)
		(fp_line
			(start 0.239268 -2.111502)
			(end 1.287018 -3.11658)
			(stroke
				(width 0.1)
				(type default)
			)
			(layer "F.SilkS")
		)
		(fp_line
			(start 0.256032 -2.069846)
			(end 1.291082 -3.062732)
			(stroke
				(width 0.1)
				(type default)
			)
			(layer "F.SilkS")
		)
		(fp_line
			(start 0.256032 -2.069846)
			(end 1.291082 -3.062732)
			(stroke
				(width 0.1)
				(type default)
			)
			(layer "F.SilkS")
		)
		(fp_line
			(start 0.272796 -2.02819)
			(end 1.295146 -3.009138)
			(stroke
				(width 0.1)
				(type default)
			)
			(layer "F.SilkS")
		)
		(fp_line
			(start 0.272796 -2.02819)
			(end 1.295146 -3.009138)
			(stroke
				(width 0.1)
				(type default)
			)
			(layer "F.SilkS")
		)
		(fp_line
			(start 0.289306 -1.986534)
			(end 1.299464 -2.955544)
			(stroke
				(width 0.1)
				(type default)
			)
			(layer "F.SilkS")
		)
		(fp_line
			(start 0.289306 -1.986534)
			(end 1.299464 -2.955544)
			(stroke
				(width 0.1)
				(type default)
			)
			(layer "F.SilkS")
		)
		(fp_line
			(start 0.307086 -1.94564)
			(end 1.303528 -2.901696)
			(stroke
				(width 0.1)
				(type default)
			)
			(layer "F.SilkS")
		)
		(fp_line
			(start 0.307086 -1.94564)
			(end 1.303528 -2.901696)
			(stroke
				(width 0.1)
				(type default)
			)
			(layer "F.SilkS")
		)
		(fp_line
			(start 0.327914 -1.908048)
			(end 1.31318 -2.853182)
			(stroke
				(width 0.1)
				(type default)
			)
			(layer "F.SilkS")
		)
		(fp_line
			(start 0.327914 -1.908048)
			(end 1.31318 -2.853182)
			(stroke
				(width 0.1)
				(type default)
			)
			(layer "F.SilkS")
		)
		(fp_line
			(start 0.348996 -1.870456)
			(end 1.325118 -2.8067)
			(stroke
				(width 0.1)
				(type default)
			)
			(layer "F.SilkS")
		)
		(fp_line
			(start 0.348996 -1.870456)
			(end 1.325118 -2.8067)
			(stroke
				(width 0.1)
				(type default)
			)
			(layer "F.SilkS")
		)
		(fp_line
			(start 0.369824 -1.832864)
			(end 1.336802 -2.760472)
			(stroke
				(width 0.1)
				(type default)
			)
			(layer "F.SilkS")
		)
		(fp_line
			(start 0.369824 -1.832864)
			(end 1.336802 -2.760472)
			(stroke
				(width 0.1)
				(type default)
			)
			(layer "F.SilkS")
		)
		(fp_line
			(start 0.390906 -1.795272)
			(end 1.348486 -2.714244)
			(stroke
				(width 0.1)
				(type default)
			)
			(layer "F.SilkS")
		)
		(fp_line
			(start 0.390906 -1.795272)
			(end 1.348486 -2.714244)
			(stroke
				(width 0.1)
				(type default)
			)
			(layer "F.SilkS")
		)
		(fp_line
			(start 0.411988 -1.75768)
			(end 1.360424 -2.667508)
			(stroke
				(width 0.1)
				(type default)
			)
			(layer "F.SilkS")
		)
		(fp_line
			(start 0.411988 -1.75768)
			(end 1.360424 -2.667508)
			(stroke
				(width 0.1)
				(type default)
			)
			(layer "F.SilkS")
		)
		(fp_line
			(start 0.432816 -1.720088)
			(end 1.372362 -2.62128)
			(stroke
				(width 0.1)
				(type default)
			)
			(layer "F.SilkS")
		)
		(fp_line
			(start 0.432816 -1.720088)
			(end 1.372362 -2.62128)
			(stroke
				(width 0.1)
				(type default)
			)
			(layer "F.SilkS")
		)
		(fp_line
			(start 0.456184 -1.684782)
			(end 1.387856 -2.578608)
			(stroke
				(width 0.1)
				(type default)
			)
			(layer "F.SilkS")
		)
		(fp_line
			(start 0.456184 -1.684782)
			(end 1.387856 -2.578608)
			(stroke
				(width 0.1)
				(type default)
			)
			(layer "F.SilkS")
		)
		(fp_line
			(start 0.481838 -1.651762)
			(end 1.40589 -2.538222)
			(stroke
				(width 0.1)
				(type default)
			)
			(layer "F.SilkS")
		)
		(fp_line
			(start 0.481838 -1.651762)
			(end 1.40589 -2.538222)
			(stroke
				(width 0.1)
				(type default)
			)
			(layer "F.SilkS")
		)
		(fp_line
			(start 0.507746 -1.618742)
			(end 1.423924 -2.497836)
			(stroke
				(width 0.1)
				(type default)
			)
			(layer "F.SilkS")
		)
		(fp_line
			(start 0.507746 -1.618742)
			(end 1.423924 -2.497836)
			(stroke
				(width 0.1)
				(type default)
			)
			(layer "F.SilkS")
		)
		(fp_line
			(start 0.5334 -1.585722)
			(end 1.441958 -2.457196)
			(stroke
				(width 0.1)
				(type default)
			)
			(layer "F.SilkS")
		)
		(fp_line
			(start 0.5334 -1.585722)
			(end 1.441958 -2.457196)
			(stroke
				(width 0.1)
				(type default)
			)
			(layer "F.SilkS")
		)
		(fp_line
			(start 0.559054 -1.552702)
			(end 1.459992 -2.41681)
			(stroke
				(width 0.1)
				(type default)
			)
			(layer "F.SilkS")
		)
		(fp_line
			(start 0.559054 -1.552702)
			(end 1.459992 -2.41681)
			(stroke
				(width 0.1)
				(type default)
			)
			(layer "F.SilkS")
		)
		(fp_line
			(start 0.584962 -1.519682)
			(end 1.477772 -2.376424)
			(stroke
				(width 0.1)
				(type default)
			)
			(layer "F.SilkS")
		)
		(fp_line
			(start 0.584962 -1.519682)
			(end 1.477772 -2.376424)
			(stroke
				(width 0.1)
				(type default)
			)
			(layer "F.SilkS")
		)
		(fp_line
			(start 0.610616 -1.486916)
			(end 1.496568 -2.336546)
			(stroke
				(width 0.1)
				(type default)
			)
			(layer "F.SilkS")
		)
		(fp_line
			(start 0.610616 -1.486916)
			(end 1.496568 -2.336546)
			(stroke
				(width 0.1)
				(type default)
			)
			(layer "F.SilkS")
		)
		(fp_line
			(start 0.637794 -1.455166)
			(end 1.52019 -2.301494)
			(stroke
				(width 0.1)
				(type default)
			)
			(layer "F.SilkS")
		)
		(fp_line
			(start 0.637794 -1.455166)
			(end 1.52019 -2.301494)
			(stroke
				(width 0.1)
				(type default)
			)
			(layer "F.SilkS")
		)
		(fp_line
			(start 0.668274 -1.426464)
			(end 1.543558 -2.266188)
			(stroke
				(width 0.1)
				(type default)
			)
			(layer "F.SilkS")
		)
		(fp_line
			(start 0.668274 -1.426464)
			(end 1.543558 -2.266188)
			(stroke
				(width 0.1)
				(type default)
			)
			(layer "F.SilkS")
		)
		(fp_line
			(start 0.6985 -1.397762)
			(end 1.56718 -2.231136)
			(stroke
				(width 0.1)
				(type default)
			)
			(layer "F.SilkS")
		)
		(fp_line
			(start 0.6985 -1.397762)
			(end 1.56718 -2.231136)
			(stroke
				(width 0.1)
				(type default)
			)
			(layer "F.SilkS")
		)
		(fp_line
			(start 0.728726 -1.36906)
			(end 1.590802 -2.196084)
			(stroke
				(width 0.1)
				(type default)
			)
			(layer "F.SilkS")
		)
		(fp_line
			(start 0.728726 -1.36906)
			(end 1.590802 -2.196084)
			(stroke
				(width 0.1)
				(type default)
			)
			(layer "F.SilkS")
		)
		(fp_line
			(start 0.758952 -1.340358)
			(end 1.61417 -2.160778)
			(stroke
				(width 0.1)
				(type default)
			)
			(layer "F.SilkS")
		)
		(fp_line
			(start 0.758952 -1.340358)
			(end 1.61417 -2.160778)
			(stroke
				(width 0.1)
				(type default)
			)
			(layer "F.SilkS")
		)
		(fp_line
			(start 0.789178 -1.31191)
			(end 1.637792 -2.125726)
			(stroke
				(width 0.1)
				(type default)
			)
			(layer "F.SilkS")
		)
		(fp_line
			(start 0.789178 -1.31191)
			(end 1.637792 -2.125726)
			(stroke
				(width 0.1)
				(type default)
			)
			(layer "F.SilkS")
		)
		(fp_line
			(start 0.819404 -1.282954)
			(end 1.663954 -2.09296)
			(stroke
				(width 0.1)
				(type default)
			)
			(layer "F.SilkS")
		)
		(fp_line
			(start 0.819404 -1.282954)
			(end 1.663954 -2.09296)
			(stroke
				(width 0.1)
				(type default)
			)
			(layer "F.SilkS")
		)
		(fp_line
			(start 0.851408 -1.25603)
			(end 1.69291 -2.063242)
			(stroke
				(width 0.1)
				(type default)
			)
			(layer "F.SilkS")
		)
		(fp_line
			(start 0.851408 -1.25603)
			(end 1.69291 -2.063242)
			(stroke
				(width 0.1)
				(type default)
			)
			(layer "F.SilkS")
		)
		(fp_line
			(start 0.885698 -1.230884)
			(end 1.72212 -2.03327)
			(stroke
				(width 0.1)
				(type default)
			)
			(layer "F.SilkS")
		)
		(fp_line
			(start 0.885698 -1.230884)
			(end 1.72212 -2.03327)
			(stroke
				(width 0.1)
				(type default)
			)
			(layer "F.SilkS")
		)
		(fp_line
			(start 0.919734 -1.206246)
			(end 1.751076 -2.003552)
			(stroke
				(width 0.1)
				(type default)
			)
			(layer "F.SilkS")
		)
		(fp_line
			(start 0.919734 -1.206246)
			(end 1.751076 -2.003552)
			(stroke
				(width 0.1)
				(type default)
			)
			(layer "F.SilkS")
		)
		(fp_line
			(start 0.954024 -1.1811)
			(end 1.780032 -1.973834)
			(stroke
				(width 0.1)
				(type default)
			)
			(layer "F.SilkS")
		)
		(fp_line
			(start 0.954024 -1.1811)
			(end 1.780032 -1.973834)
			(stroke
				(width 0.1)
				(type default)
			)
			(layer "F.SilkS")
		)
		(fp_line
			(start 0.988314 -1.156462)
			(end 1.809242 -1.943862)
			(stroke
				(width 0.1)
				(type default)
			)
			(layer "F.SilkS")
		)
		(fp_line
			(start 0.988314 -1.156462)
			(end 1.809242 -1.943862)
			(stroke
				(width 0.1)
				(type default)
			)
			(layer "F.SilkS")
		)
		(fp_line
			(start 1.02235 -1.13157)
			(end 1.838452 -1.914144)
			(stroke
				(width 0.1)
				(type default)
			)
			(layer "F.SilkS")
		)
		(fp_line
			(start 1.02235 -1.13157)
			(end 1.838452 -1.914144)
			(stroke
				(width 0.1)
				(type default)
			)
			(layer "F.SilkS")
		)
		(fp_line
			(start 1.05664 -1.106678)
			(end 1.872488 -1.889252)
			(stroke
				(width 0.1)
				(type default)
			)
			(layer "F.SilkS")
		)
		(fp_line
			(start 1.05664 -1.106678)
			(end 1.872488 -1.889252)
			(stroke
				(width 0.1)
				(type default)
			)
			(layer "F.SilkS")
		)
		(fp_line
			(start 1.09347 -1.084326)
			(end 1.907794 -1.865376)
			(stroke
				(width 0.1)
				(type default)
			)
			(layer "F.SilkS")
		)
		(fp_line
			(start 1.09347 -1.084326)
			(end 1.907794 -1.865376)
			(stroke
				(width 0.1)
				(type default)
			)
			(layer "F.SilkS")
		)
		(fp_line
			(start 1.131824 -1.063498)
			(end 1.9431 -1.8415)
			(stroke
				(width 0.1)
				(type default)
			)
			(layer "F.SilkS")
		)
		(fp_line
			(start 1.131824 -1.063498)
			(end 1.9431 -1.8415)
			(stroke
				(width 0.1)
				(type default)
			)
			(layer "F.SilkS")
		)
		(fp_line
			(start 1.133856 -5.220462)
			(end 0.47117 -4.5847)
			(stroke
				(width 0.1)
				(type default)
			)
			(layer "F.SilkS")
		)
		(fp_line
			(start 1.133856 -5.220462)
			(end 0.47117 -4.5847)
			(stroke
				(width 0.1)
				(type default)
			)
			(layer "F.SilkS")
		)
		(fp_line
			(start 1.170178 -1.042416)
			(end 1.978406 -1.817624)
			(stroke
				(width 0.1)
				(type default)
			)
			(layer "F.SilkS")
		)
		(fp_line
			(start 1.170178 -1.042416)
			(end 1.978406 -1.817624)
			(stroke
				(width 0.1)
				(type default)
			)
			(layer "F.SilkS")
		)
		(fp_line
			(start 1.208532 -1.021334)
			(end 2.013458 -1.793748)
			(stroke
				(width 0.1)
				(type default)
			)
			(layer "F.SilkS")
		)
		(fp_line
			(start 1.208532 -1.021334)
			(end 2.013458 -1.793748)
			(stroke
				(width 0.1)
				(type default)
			)
			(layer "F.SilkS")
		)
		(fp_line
			(start 1.246886 -1.000506)
			(end 2.048764 -1.769872)
			(stroke
				(width 0.1)
				(type default)
			)
			(layer "F.SilkS")
		)
		(fp_line
			(start 1.246886 -1.000506)
			(end 2.048764 -1.769872)
			(stroke
				(width 0.1)
				(type default)
			)
			(layer "F.SilkS")
		)
		(fp_line
			(start 1.28524 -0.979424)
			(end 2.087626 -1.749298)
			(stroke
				(width 0.1)
				(type default)
			)
			(layer "F.SilkS")
		)
		(fp_line
			(start 1.28524 -0.979424)
			(end 2.087626 -1.749298)
			(stroke
				(width 0.1)
				(type default)
			)
			(layer "F.SilkS")
		)
		(fp_line
			(start 1.293368 -5.315966)
			(end 0.37465 -4.434332)
			(stroke
				(width 0.1)
				(type default)
			)
			(layer "F.SilkS")
		)
		(fp_line
			(start 1.293368 -5.315966)
			(end 0.37465 -4.434332)
			(stroke
				(width 0.1)
				(type default)
			)
			(layer "F.SilkS")
		)
		(fp_line
			(start 1.323594 -0.958596)
			(end 2.130552 -1.732788)
			(stroke
				(width 0.1)
				(type default)
			)
			(layer "F.SilkS")
		)
		(fp_line
			(start 1.323594 -0.958596)
			(end 2.130552 -1.732788)
			(stroke
				(width 0.1)
				(type default)
			)
			(layer "F.SilkS")
		)
		(fp_line
			(start 1.366266 -0.941832)
			(end 2.173478 -1.716024)
			(stroke
				(width 0.1)
				(type default)
			)
			(layer "F.SilkS")
		)
		(fp_line
			(start 1.366266 -0.941832)
			(end 2.173478 -1.716024)
			(stroke
				(width 0.1)
				(type default)
			)
			(layer "F.SilkS")
		)
		(fp_line
			(start 1.408684 -0.924814)
			(end 2.21615 -1.699514)
			(stroke
				(width 0.1)
				(type default)
			)
			(layer "F.SilkS")
		)
		(fp_line
			(start 1.408684 -0.924814)
			(end 2.21615 -1.699514)
			(stroke
				(width 0.1)
				(type default)
			)
			(layer "F.SilkS")
		)
		(fp_line
			(start 1.41224 -5.3721)
			(end 0.302768 -4.307586)
			(stroke
				(width 0.1)
				(type default)
			)
			(layer "F.SilkS")
		)
		(fp_line
			(start 1.41224 -5.3721)
			(end 0.302768 -4.307586)
			(stroke
				(width 0.1)
				(type default)
			)
			(layer "F.SilkS")
		)
		(fp_line
			(start 1.451356 -0.90805)
			(end 2.259076 -1.68275)
			(stroke
				(width 0.1)
				(type default)
			)
			(layer "F.SilkS")
		)
		(fp_line
			(start 1.451356 -0.90805)
			(end 2.259076 -1.68275)
			(stroke
				(width 0.1)
				(type default)
			)
			(layer "F.SilkS")
		)
		(fp_line
			(start 1.493774 -0.891032)
			(end 2.301748 -1.66624)
			(stroke
				(width 0.1)
				(type default)
			)
			(layer "F.SilkS")
		)
		(fp_line
			(start 1.493774 -0.891032)
			(end 2.301748 -1.66624)
			(stroke
				(width 0.1)
				(type default)
			)
			(layer "F.SilkS")
		)
		(fp_line
			(start 1.52781 -5.425186)
			(end 0.256794 -4.205732)
			(stroke
				(width 0.1)
				(type default)
			)
			(layer "F.SilkS")
		)
		(fp_line
			(start 1.52781 -5.425186)
			(end 0.256794 -4.205732)
			(stroke
				(width 0.1)
				(type default)
			)
			(layer "F.SilkS")
		)
		(fp_line
			(start 1.536446 -0.874268)
			(end 2.351024 -1.655826)
			(stroke
				(width 0.1)
				(type default)
			)
			(layer "F.SilkS")
		)
		(fp_line
			(start 1.536446 -0.874268)
			(end 2.351024 -1.655826)
			(stroke
				(width 0.1)
				(type default)
			)
			(layer "F.SilkS")
		)
		(fp_line
			(start 1.578864 -0.857504)
			(end 2.404364 -1.649222)
			(stroke
				(width 0.1)
				(type default)
			)
			(layer "F.SilkS")
		)
		(fp_line
			(start 1.578864 -0.857504)
			(end 2.404364 -1.649222)
			(stroke
				(width 0.1)
				(type default)
			)
			(layer "F.SilkS")
		)
		(fp_line
			(start 1.62306 -5.458714)
			(end 0.211328 -4.10464)
			(stroke
				(width 0.1)
				(type default)
			)
			(layer "F.SilkS")
		)
		(fp_line
			(start 1.62306 -5.458714)
			(end 0.211328 -4.10464)
			(stroke
				(width 0.1)
				(type default)
			)
			(layer "F.SilkS")
		)
		(fp_line
			(start 1.623314 -0.842264)
			(end 2.457704 -1.642618)
			(stroke
				(width 0.1)
				(type default)
			)
			(layer "F.SilkS")
		)
		(fp_line
			(start 1.623314 -0.842264)
			(end 2.457704 -1.642618)
			(stroke
				(width 0.1)
				(type default)
			)
			(layer "F.SilkS")
		)
		(fp_line
			(start 1.67005 -0.829564)
			(end 2.511044 -1.636014)
			(stroke
				(width 0.1)
				(type default)
			)
			(layer "F.SilkS")
		)
		(fp_line
			(start 1.67005 -0.829564)
			(end 2.511044 -1.636014)
			(stroke
				(width 0.1)
				(type default)
			)
			(layer "F.SilkS")
		)
		(fp_line
			(start 1.716786 -0.816356)
			(end 2.56413 -1.62941)
			(stroke
				(width 0.1)
				(type default)
			)
			(layer "F.SilkS")
		)
		(fp_line
			(start 1.716786 -0.816356)
			(end 2.56413 -1.62941)
			(stroke
				(width 0.1)
				(type default)
			)
			(layer "F.SilkS")
		)
		(fp_line
			(start 1.717802 -5.492242)
			(end 0.181356 -4.018026)
			(stroke
				(width 0.1)
				(type default)
			)
			(layer "F.SilkS")
		)
		(fp_line
			(start 1.717802 -5.492242)
			(end 0.181356 -4.018026)
			(stroke
				(width 0.1)
				(type default)
			)
			(layer "F.SilkS")
		)
		(fp_line
			(start 1.763522 -0.803656)
			(end 2.624582 -1.629664)
			(stroke
				(width 0.1)
				(type default)
			)
			(layer "F.SilkS")
		)
		(fp_line
			(start 1.763522 -0.803656)
			(end 2.624582 -1.629664)
			(stroke
				(width 0.1)
				(type default)
			)
			(layer "F.SilkS")
		)
		(fp_line
			(start 1.805686 -5.518658)
			(end 0.1524 -3.932682)
			(stroke
				(width 0.1)
				(type default)
			)
			(layer "F.SilkS")
		)
		(fp_line
			(start 1.805686 -5.518658)
			(end 0.1524 -3.932682)
			(stroke
				(width 0.1)
				(type default)
			)
			(layer "F.SilkS")
		)
		(fp_line
			(start 1.810512 -0.790956)
			(end 2.692654 -1.637284)
			(stroke
				(width 0.1)
				(type default)
			)
			(layer "F.SilkS")
		)
		(fp_line
			(start 1.810512 -0.790956)
			(end 2.692654 -1.637284)
			(stroke
				(width 0.1)
				(type default)
			)
			(layer "F.SilkS")
		)
		(fp_line
			(start 1.856994 -0.777748)
			(end 2.760726 -1.64465)
			(stroke
				(width 0.1)
				(type default)
			)
			(layer "F.SilkS")
		)
		(fp_line
			(start 1.856994 -0.777748)
			(end 2.760726 -1.64465)
			(stroke
				(width 0.1)
				(type default)
			)
			(layer "F.SilkS")
		)
		(fp_line
			(start 1.886458 -5.538216)
			(end 0.128016 -3.851402)
			(stroke
				(width 0.1)
				(type default)
			)
			(layer "F.SilkS")
		)
		(fp_line
			(start 1.886458 -5.538216)
			(end 0.128016 -3.851402)
			(stroke
				(width 0.1)
				(type default)
			)
			(layer "F.SilkS")
		)
		(fp_line
			(start 1.90373 -0.765048)
			(end 2.828544 -1.65227)
			(stroke
				(width 0.1)
				(type default)
			)
			(layer "F.SilkS")
		)
		(fp_line
			(start 1.90373 -0.765048)
			(end 2.828544 -1.65227)
			(stroke
				(width 0.1)
				(type default)
			)
			(layer "F.SilkS")
		)
		(fp_line
			(start 1.954276 -0.75565)
			(end 2.906014 -1.66878)
			(stroke
				(width 0.1)
				(type default)
			)
			(layer "F.SilkS")
		)
		(fp_line
			(start 1.954276 -0.75565)
			(end 2.906014 -1.66878)
			(stroke
				(width 0.1)
				(type default)
			)
			(layer "F.SilkS")
		)
		(fp_line
			(start 1.966722 -5.557774)
			(end 0.110236 -3.776726)
			(stroke
				(width 0.1)
				(type default)
			)
			(layer "F.SilkS")
		)
		(fp_line
			(start 1.966722 -5.557774)
			(end 0.110236 -3.776726)
			(stroke
				(width 0.1)
				(type default)
			)
			(layer "F.SilkS")
		)
		(fp_line
			(start 2.00533 -0.74676)
			(end 3.000248 -1.701546)
			(stroke
				(width 0.1)
				(type default)
			)
			(layer "F.SilkS")
		)
		(fp_line
			(start 2.00533 -0.74676)
			(end 3.000248 -1.701546)
			(stroke
				(width 0.1)
				(type default)
			)
			(layer "F.SilkS")
		)
		(fp_line
			(start 2.04597 -5.576062)
			(end 0.092456 -3.70205)
			(stroke
				(width 0.1)
				(type default)
			)
			(layer "F.SilkS")
		)
		(fp_line
			(start 2.04597 -5.576062)
			(end 0.092456 -3.70205)
			(stroke
				(width 0.1)
				(type default)
			)
			(layer "F.SilkS")
		)
		(fp_line
			(start 2.05613 -0.73787)
			(end 3.094228 -1.733804)
			(stroke
				(width 0.1)
				(type default)
			)
			(layer "F.SilkS")
		)
		(fp_line
			(start 2.05613 -0.73787)
			(end 3.094228 -1.733804)
			(stroke
				(width 0.1)
				(type default)
			)
			(layer "F.SilkS")
		)
		(fp_line
			(start 2.10693 -0.72898)
			(end 3.238246 -1.814322)
			(stroke
				(width 0.1)
				(type default)
			)
			(layer "F.SilkS")
		)
		(fp_line
			(start 2.10693 -0.72898)
			(end 3.238246 -1.814322)
			(stroke
				(width 0.1)
				(type default)
			)
			(layer "F.SilkS")
		)
		(fp_line
			(start 2.116328 -5.585968)
			(end 0.07874 -3.631184)
			(stroke
				(width 0.1)
				(type default)
			)
			(layer "F.SilkS")
		)
		(fp_line
			(start 2.116328 -5.585968)
			(end 0.07874 -3.631184)
			(stroke
				(width 0.1)
				(type default)
			)
			(layer "F.SilkS")
		)
		(fp_line
			(start 2.18694 -5.595874)
			(end 0.069342 -3.564382)
			(stroke
				(width 0.1)
				(type default)
			)
			(layer "F.SilkS")
		)
		(fp_line
			(start 2.18694 -5.595874)
			(end 0.069342 -3.564382)
			(stroke
				(width 0.1)
				(type default)
			)
			(layer "F.SilkS")
		)
		(fp_line
			(start 2.208784 -0.710946)
			(end 5.142484 -3.52552)
			(stroke
				(width 0.1)
				(type default)
			)
			(layer "F.SilkS")
		)
		(fp_line
			(start 2.208784 -0.710946)
			(end 5.142484 -3.52552)
			(stroke
				(width 0.1)
				(type default)
			)
			(layer "F.SilkS")
		)
		(fp_line
			(start 2.257552 -5.60578)
			(end 0.059944 -3.49758)
			(stroke
				(width 0.1)
				(type default)
			)
			(layer "F.SilkS")
		)
		(fp_line
			(start 2.257552 -5.60578)
			(end 0.059944 -3.49758)
			(stroke
				(width 0.1)
				(type default)
			)
			(layer "F.SilkS")
		)
		(fp_line
			(start 2.2606 -0.703326)
			(end 5.147564 -3.472942)
			(stroke
				(width 0.1)
				(type default)
			)
			(layer "F.SilkS")
		)
		(fp_line
			(start 2.2606 -0.703326)
			(end 5.147564 -3.472942)
			(stroke
				(width 0.1)
				(type default)
			)
			(layer "F.SilkS")
		)
		(fp_line
			(start 2.315464 -0.698246)
			(end 5.152898 -3.42011)
			(stroke
				(width 0.1)
				(type default)
			)
			(layer "F.SilkS")
		)
		(fp_line
			(start 2.315464 -0.698246)
			(end 5.152898 -3.42011)
			(stroke
				(width 0.1)
				(type default)
			)
			(layer "F.SilkS")
		)
		(fp_line
			(start 2.32791 -5.615686)
			(end 0.051308 -3.431794)
			(stroke
				(width 0.1)
				(type default)
			)
			(layer "F.SilkS")
		)
		(fp_line
			(start 2.32791 -5.615686)
			(end 0.051308 -3.431794)
			(stroke
				(width 0.1)
				(type default)
			)
			(layer "F.SilkS")
		)
		(fp_line
			(start 2.370328 -0.693166)
			(end 5.156708 -3.366262)
			(stroke
				(width 0.1)
				(type default)
			)
			(layer "F.SilkS")
		)
		(fp_line
			(start 2.370328 -0.693166)
			(end 5.156708 -3.366262)
			(stroke
				(width 0.1)
				(type default)
			)
			(layer "F.SilkS")
		)
		(fp_line
			(start 2.390902 -5.61848)
			(end 0.048514 -3.371342)
			(stroke
				(width 0.1)
				(type default)
			)
			(layer "F.SilkS")
		)
		(fp_line
			(start 2.390902 -5.61848)
			(end 0.048514 -3.371342)
			(stroke
				(width 0.1)
				(type default)
			)
			(layer "F.SilkS")
		)
		(fp_line
			(start 2.424938 -0.687832)
			(end 5.158994 -3.310382)
			(stroke
				(width 0.1)
				(type default)
			)
			(layer "F.SilkS")
		)
		(fp_line
			(start 2.424938 -0.687832)
			(end 5.158994 -3.310382)
			(stroke
				(width 0.1)
				(type default)
			)
			(layer "F.SilkS")
		)
		(fp_line
			(start 2.454148 -5.621274)
			(end 0.04572 -3.31089)
			(stroke
				(width 0.1)
				(type default)
			)
			(layer "F.SilkS")
		)
		(fp_line
			(start 2.454148 -5.621274)
			(end 0.04572 -3.31089)
			(stroke
				(width 0.1)
				(type default)
			)
			(layer "F.SilkS")
		)
		(fp_line
			(start 2.479802 -0.682752)
			(end 5.16001 -3.25374)
			(stroke
				(width 0.1)
				(type default)
			)
			(layer "F.SilkS")
		)
		(fp_line
			(start 2.479802 -0.682752)
			(end 5.16001 -3.25374)
			(stroke
				(width 0.1)
				(type default)
			)
			(layer "F.SilkS")
		)
		(fp_line
			(start 2.517394 -5.624322)
			(end 0.042926 -3.250438)
			(stroke
				(width 0.1)
				(type default)
			)
			(layer "F.SilkS")
		)
		(fp_line
			(start 2.517394 -5.624322)
			(end 0.042926 -3.250438)
			(stroke
				(width 0.1)
				(type default)
			)
			(layer "F.SilkS")
		)
		(fp_line
			(start 2.534666 -0.677672)
			(end 5.15747 -3.193796)
			(stroke
				(width 0.1)
				(type default)
			)
			(layer "F.SilkS")
		)
		(fp_line
			(start 2.534666 -0.677672)
			(end 5.15747 -3.193796)
			(stroke
				(width 0.1)
				(type default)
			)
			(layer "F.SilkS")
		)
		(fp_line
			(start 2.580386 -5.626862)
			(end 0.041656 -3.19151)
			(stroke
				(width 0.1)
				(type default)
			)
			(layer "F.SilkS")
		)
		(fp_line
			(start 2.580386 -5.626862)
			(end 0.041656 -3.19151)
			(stroke
				(width 0.1)
				(type default)
			)
			(layer "F.SilkS")
		)
		(fp_line
			(start 2.589276 -0.672338)
			(end 5.15493 -3.133598)
			(stroke
				(width 0.1)
				(type default)
			)
			(layer "F.SilkS")
		)
		(fp_line
			(start 2.589276 -0.672338)
			(end 5.15493 -3.133598)
			(stroke
				(width 0.1)
				(type default)
			)
			(layer "F.SilkS")
		)
		(fp_line
			(start 2.64287 -5.629148)
			(end 0.042672 -3.135122)
			(stroke
				(width 0.1)
				(type default)
			)
			(layer "F.SilkS")
		)
		(fp_line
			(start 2.64287 -5.629148)
			(end 0.042672 -3.135122)
			(stroke
				(width 0.1)
				(type default)
			)
			(layer "F.SilkS")
		)
		(fp_line
			(start 2.646426 -0.669544)
			(end 5.15239 -3.073146)
			(stroke
				(width 0.1)
				(type default)
			)
			(layer "F.SilkS")
		)
		(fp_line
			(start 2.646426 -0.669544)
			(end 5.15239 -3.073146)
			(stroke
				(width 0.1)
				(type default)
			)
			(layer "F.SilkS")
		)
		(fp_line
			(start 2.700528 -5.626862)
			(end 0.04445 -3.078734)
			(stroke
				(width 0.1)
				(type default)
			)
			(layer "F.SilkS")
		)
		(fp_line
			(start 2.700528 -5.626862)
			(end 0.04445 -3.078734)
			(stroke
				(width 0.1)
				(type default)
			)
			(layer "F.SilkS")
		)
		(fp_line
			(start 2.704846 -0.66802)
			(end 5.14985 -3.013202)
			(stroke
				(width 0.1)
				(type default)
			)
			(layer "F.SilkS")
		)
		(fp_line
			(start 2.704846 -0.66802)
			(end 5.14985 -3.013202)
			(stroke
				(width 0.1)
				(type default)
			)
			(layer "F.SilkS")
		)
		(fp_line
			(start 2.75844 -5.62483)
			(end 0.048006 -3.024632)
			(stroke
				(width 0.1)
				(type default)
			)
			(layer "F.SilkS")
		)
		(fp_line
			(start 2.75844 -5.62483)
			(end 0.048006 -3.024632)
			(stroke
				(width 0.1)
				(type default)
			)
			(layer "F.SilkS")
		)
		(fp_line
			(start 2.76352 -0.666242)
			(end 5.14731 -2.953258)
			(stroke
				(width 0.1)
				(type default)
			)
			(layer "F.SilkS")
		)
		(fp_line
			(start 2.76352 -0.666242)
			(end 5.14731 -2.953258)
			(stroke
				(width 0.1)
				(type default)
			)
			(layer "F.SilkS")
		)
		(fp_line
			(start 2.816098 -5.622544)
			(end 0.051562 -2.970276)
			(stroke
				(width 0.1)
				(type default)
			)
			(layer "F.SilkS")
		)
		(fp_line
			(start 2.816098 -5.622544)
			(end 0.051562 -2.970276)
			(stroke
				(width 0.1)
				(type default)
			)
			(layer "F.SilkS")
		)
		(fp_line
			(start 2.82194 -0.664718)
			(end 5.145024 -2.89306)
			(stroke
				(width 0.1)
				(type default)
			)
			(layer "F.SilkS")
		)
		(fp_line
			(start 2.82194 -0.664718)
			(end 5.145024 -2.89306)
			(stroke
				(width 0.1)
				(type default)
			)
			(layer "F.SilkS")
		)
		(fp_line
			(start 2.87401 -5.620258)
			(end 0.054864 -2.91592)
			(stroke
				(width 0.1)
				(type default)
			)
			(layer "F.SilkS")
		)
		(fp_line
			(start 2.87401 -5.620258)
			(end 0.054864 -2.91592)
			(stroke
				(width 0.1)
				(type default)
			)
			(layer "F.SilkS")
		)
		(fp_line
			(start 2.88036 -0.662686)
			(end 5.13588 -2.826512)
			(stroke
				(width 0.1)
				(type default)
			)
			(layer "F.SilkS")
		)
		(fp_line
			(start 2.88036 -0.662686)
			(end 5.13588 -2.826512)
			(stroke
				(width 0.1)
				(type default)
			)
			(layer "F.SilkS")
		)
		(fp_line
			(start 2.92989 -5.616194)
			(end 0.061468 -2.864358)
			(stroke
				(width 0.1)
				(type default)
			)
			(layer "F.SilkS")
		)
		(fp_line
			(start 2.92989 -5.616194)
			(end 0.061468 -2.864358)
			(stroke
				(width 0.1)
				(type default)
			)
			(layer "F.SilkS")
		)
		(fp_line
			(start 2.93878 -0.661416)
			(end 5.126736 -2.760218)
			(stroke
				(width 0.1)
				(type default)
			)
			(layer "F.SilkS")
		)
		(fp_line
			(start 2.93878 -0.661416)
			(end 5.126736 -2.760218)
			(stroke
				(width 0.1)
				(type default)
			)
			(layer "F.SilkS")
		)
		(fp_line
			(start 2.98323 -5.609336)
			(end 0.067818 -2.812542)
			(stroke
				(width 0.1)
				(type default)
			)
			(layer "F.SilkS")
		)
		(fp_line
			(start 2.98323 -5.609336)
			(end 0.067818 -2.812542)
			(stroke
				(width 0.1)
				(type default)
			)
			(layer "F.SilkS")
		)
		(fp_line
			(start 2.9972 -0.659638)
			(end 5.117592 -2.69367)
			(stroke
				(width 0.1)
				(type default)
			)
			(layer "F.SilkS")
		)
		(fp_line
			(start 2.9972 -0.659638)
			(end 5.117592 -2.69367)
			(stroke
				(width 0.1)
				(type default)
			)
			(layer "F.SilkS")
		)
		(fp_line
			(start 3.03657 -5.602732)
			(end 0.073914 -2.76098)
			(stroke
				(width 0.1)
				(type default)
			)
			(layer "F.SilkS")
		)
		(fp_line
			(start 3.03657 -5.602732)
			(end 0.073914 -2.76098)
			(stroke
				(width 0.1)
				(type default)
			)
			(layer "F.SilkS")
		)
		(fp_line
			(start 3.048 -0.651002)
			(end 5.108194 -2.627122)
			(stroke
				(width 0.1)
				(type default)
			)
			(layer "F.SilkS")
		)
		(fp_line
			(start 3.048 -0.651002)
			(end 5.108194 -2.627122)
			(stroke
				(width 0.1)
				(type default)
			)
			(layer "F.SilkS")
		)
		(fp_line
			(start 3.089656 -5.596382)
			(end 0.080264 -2.709418)
			(stroke
				(width 0.1)
				(type default)
			)
			(layer "F.SilkS")
		)
		(fp_line
			(start 3.089656 -5.596382)
			(end 0.080264 -2.709418)
			(stroke
				(width 0.1)
				(type default)
			)
			(layer "F.SilkS")
		)
		(fp_line
			(start 3.094482 -0.637286)
			(end 5.09905 -2.560574)
			(stroke
				(width 0.1)
				(type default)
			)
			(layer "F.SilkS")
		)
		(fp_line
			(start 3.094482 -0.637286)
			(end 5.09905 -2.560574)
			(stroke
				(width 0.1)
				(type default)
			)
			(layer "F.SilkS")
		)
		(fp_line
			(start 3.13944 -0.622808)
			(end 5.081524 -2.485898)
			(stroke
				(width 0.1)
				(type default)
			)
			(layer "F.SilkS")
		)
		(fp_line
			(start 3.13944 -0.622808)
			(end 5.081524 -2.485898)
			(stroke
				(width 0.1)
				(type default)
			)
			(layer "F.SilkS")
		)
		(fp_line
			(start 3.14325 -5.589778)
			(end 1.972818 -4.467098)
			(stroke
				(width 0.1)
				(type default)
			)
			(layer "F.SilkS")
		)
		(fp_line
			(start 3.14325 -5.589778)
			(end 1.972818 -4.467098)
			(stroke
				(width 0.1)
				(type default)
			)
			(layer "F.SilkS")
		)
		(fp_line
			(start 3.184144 -0.60833)
			(end 5.061966 -2.409698)
			(stroke
				(width 0.1)
				(type default)
			)
			(layer "F.SilkS")
		)
		(fp_line
			(start 3.184144 -0.60833)
			(end 5.061966 -2.409698)
			(stroke
				(width 0.1)
				(type default)
			)
			(layer "F.SilkS")
		)
		(fp_line
			(start 3.19405 -5.580888)
			(end 2.123694 -4.553966)
			(stroke
				(width 0.1)
				(type default)
			)
			(layer "F.SilkS")
		)
		(fp_line
			(start 3.19405 -5.580888)
			(end 2.123694 -4.553966)
			(stroke
				(width 0.1)
				(type default)
			)
			(layer "F.SilkS")
		)
		(fp_line
			(start 3.22834 -0.592836)
			(end 5.042408 -2.33299)
			(stroke
				(width 0.1)
				(type default)
			)
			(layer "F.SilkS")
		)
		(fp_line
			(start 3.22834 -0.592836)
			(end 5.042408 -2.33299)
			(stroke
				(width 0.1)
				(type default)
			)
			(layer "F.SilkS")
		)
		(fp_line
			(start 3.243072 -5.57022)
			(end 2.217166 -4.586224)
			(stroke
				(width 0.1)
				(type default)
			)
			(layer "F.SilkS")
		)
		(fp_line
			(start 3.243072 -5.57022)
			(end 2.217166 -4.586224)
			(stroke
				(width 0.1)
				(type default)
			)
			(layer "F.SilkS")
		)
		(fp_line
			(start 3.272536 -0.577342)
			(end 5.02285 -2.256536)
			(stroke
				(width 0.1)
				(type default)
			)
			(layer "F.SilkS")
		)
		(fp_line
			(start 3.272536 -0.577342)
			(end 5.02285 -2.256536)
			(stroke
				(width 0.1)
				(type default)
			)
			(layer "F.SilkS")
		)
		(fp_line
			(start 3.292094 -5.559552)
			(end 2.310892 -4.618228)
			(stroke
				(width 0.1)
				(type default)
			)
			(layer "F.SilkS")
		)
		(fp_line
			(start 3.292094 -5.559552)
			(end 2.310892 -4.618228)
			(stroke
				(width 0.1)
				(type default)
			)
			(layer "F.SilkS")
		)
		(fp_line
			(start 3.316224 -0.561848)
			(end 4.990338 -2.167636)
			(stroke
				(width 0.1)
				(type default)
			)
			(layer "F.SilkS")
		)
		(fp_line
			(start 3.316224 -0.561848)
			(end 4.990338 -2.167636)
			(stroke
				(width 0.1)
				(type default)
			)
			(layer "F.SilkS")
		)
		(fp_line
			(start 3.34137 -5.549138)
			(end 2.389632 -4.636262)
			(stroke
				(width 0.1)
				(type default)
			)
			(layer "F.SilkS")
		)
		(fp_line
			(start 3.34137 -5.549138)
			(end 2.389632 -4.636262)
			(stroke
				(width 0.1)
				(type default)
			)
			(layer "F.SilkS")
		)
		(fp_line
			(start 3.359912 -0.545846)
			(end 4.953254 -2.074418)
			(stroke
				(width 0.1)
				(type default)
			)
			(layer "F.SilkS")
		)
		(fp_line
			(start 3.359912 -0.545846)
			(end 4.953254 -2.074418)
			(stroke
				(width 0.1)
				(type default)
			)
			(layer "F.SilkS")
		)
		(fp_line
			(start 3.390392 -5.53847)
			(end 2.458212 -4.644136)
			(stroke
				(width 0.1)
				(type default)
			)
			(layer "F.SilkS")
		)
		(fp_line
			(start 3.390392 -5.53847)
			(end 2.458212 -4.644136)
			(stroke
				(width 0.1)
				(type default)
			)
			(layer "F.SilkS")
		)
		(fp_line
			(start 3.4036 -0.530098)
			(end 4.915916 -1.980946)
			(stroke
				(width 0.1)
				(type default)
			)
			(layer "F.SilkS")
		)
		(fp_line
			(start 3.4036 -0.530098)
			(end 4.915916 -1.980946)
			(stroke
				(width 0.1)
				(type default)
			)
			(layer "F.SilkS")
		)
		(fp_line
			(start 3.437382 -5.52577)
			(end 2.526538 -4.65201)
			(stroke
				(width 0.1)
				(type default)
			)
			(layer "F.SilkS")
		)
		(fp_line
			(start 3.437382 -5.52577)
			(end 2.526538 -4.65201)
			(stroke
				(width 0.1)
				(type default)
			)
			(layer "F.SilkS")
		)
		(fp_line
			(start 3.447034 -0.513842)
			(end 4.85267 -1.862582)
			(stroke
				(width 0.1)
				(type default)
			)
			(layer "F.SilkS")
		)
		(fp_line
			(start 3.447034 -0.513842)
			(end 4.85267 -1.862582)
			(stroke
				(width 0.1)
				(type default)
			)
			(layer "F.SilkS")
		)
		(fp_line
			(start 3.482594 -5.511292)
			(end 2.593086 -4.658106)
			(stroke
				(width 0.1)
				(type default)
			)
			(layer "F.SilkS")
		)
		(fp_line
			(start 3.482594 -5.511292)
			(end 2.593086 -4.658106)
			(stroke
				(width 0.1)
				(type default)
			)
			(layer "F.SilkS")
		)
		(fp_line
			(start 3.490468 -0.498094)
			(end 4.77901 -1.734058)
			(stroke
				(width 0.1)
				(type default)
			)
			(layer "F.SilkS")
		)
		(fp_line
			(start 3.490468 -0.498094)
			(end 4.77901 -1.734058)
			(stroke
				(width 0.1)
				(type default)
			)
			(layer "F.SilkS")
		)
		(fp_line
			(start 3.527806 -5.497068)
			(end 2.647188 -4.652264)
			(stroke
				(width 0.1)
				(type default)
			)
			(layer "F.SilkS")
		)
		(fp_line
			(start 3.527806 -5.497068)
			(end 2.647188 -4.652264)
			(stroke
				(width 0.1)
				(type default)
			)
			(layer "F.SilkS")
		)
		(fp_line
			(start 3.533648 -0.481838)
			(end 4.147312 -1.070356)
			(stroke
				(width 0.1)
				(type default)
			)
			(layer "F.SilkS")
		)
		(fp_line
			(start 3.533648 -0.481838)
			(end 4.147312 -1.070356)
			(stroke
				(width 0.1)
				(type default)
			)
			(layer "F.SilkS")
		)
		(fp_line
			(start 3.573018 -5.482844)
			(end 2.700782 -4.645914)
			(stroke
				(width 0.1)
				(type default)
			)
			(layer "F.SilkS")
		)
		(fp_line
			(start 3.573018 -5.482844)
			(end 2.700782 -4.645914)
			(stroke
				(width 0.1)
				(type default)
			)
			(layer "F.SilkS")
		)
		(fp_line
			(start 3.61823 -5.468366)
			(end 2.75463 -4.639818)
			(stroke
				(width 0.1)
				(type default)
			)
			(layer "F.SilkS")
		)
		(fp_line
			(start 3.61823 -5.468366)
			(end 2.75463 -4.639818)
			(stroke
				(width 0.1)
				(type default)
			)
			(layer "F.SilkS")
		)
		(fp_line
			(start 3.620008 -0.449072)
			(end 4.2164 -1.02108)
			(stroke
				(width 0.1)
				(type default)
			)
			(layer "F.SilkS")
		)
		(fp_line
			(start 3.620008 -0.449072)
			(end 4.2164 -1.02108)
			(stroke
				(width 0.1)
				(type default)
			)
			(layer "F.SilkS")
		)
		(fp_line
			(start 3.662426 -5.452872)
			(end 2.808478 -4.633976)
			(stroke
				(width 0.1)
				(type default)
			)
			(layer "F.SilkS")
		)
		(fp_line
			(start 3.662426 -5.452872)
			(end 2.808478 -4.633976)
			(stroke
				(width 0.1)
				(type default)
			)
			(layer "F.SilkS")
		)
		(fp_line
			(start 3.663442 -0.43307)
			(end 4.250944 -0.996696)
			(stroke
				(width 0.1)
				(type default)
			)
			(layer "F.SilkS")
		)
		(fp_line
			(start 3.663442 -0.43307)
			(end 4.250944 -0.996696)
			(stroke
				(width 0.1)
				(type default)
			)
			(layer "F.SilkS")
		)
		(fp_line
			(start 3.703828 -5.435092)
			(end 2.860548 -4.626102)
			(stroke
				(width 0.1)
				(type default)
			)
			(layer "F.SilkS")
		)
		(fp_line
			(start 3.703828 -5.435092)
			(end 2.860548 -4.626102)
			(stroke
				(width 0.1)
				(type default)
			)
			(layer "F.SilkS")
		)
		(fp_line
			(start 3.706368 -0.416814)
			(end 4.285488 -0.972058)
			(stroke
				(width 0.1)
				(type default)
			)
			(layer "F.SilkS")
		)
		(fp_line
			(start 3.706368 -0.416814)
			(end 4.285488 -0.972058)
			(stroke
				(width 0.1)
				(type default)
			)
			(layer "F.SilkS")
		)
		(fp_line
			(start 3.745484 -5.417058)
			(end 2.90449 -4.610354)
			(stroke
				(width 0.1)
				(type default)
			)
			(layer "F.SilkS")
		)
		(fp_line
			(start 3.745484 -5.417058)
			(end 2.90449 -4.610354)
			(stroke
				(width 0.1)
				(type default)
			)
			(layer "F.SilkS")
		)
		(fp_line
			(start 3.749548 -0.400304)
			(end 4.320286 -0.947674)
			(stroke
				(width 0.1)
				(type default)
			)
			(layer "F.SilkS")
		)
		(fp_line
			(start 3.749548 -0.400304)
			(end 4.320286 -0.947674)
			(stroke
				(width 0.1)
				(type default)
			)
			(layer "F.SilkS")
		)
		(fp_line
			(start 3.786886 -5.399278)
			(end 2.948432 -4.595114)
			(stroke
				(width 0.1)
				(type default)
			)
			(layer "F.SilkS")
		)
		(fp_line
			(start 3.786886 -5.399278)
			(end 2.948432 -4.595114)
			(stroke
				(width 0.1)
				(type default)
			)
			(layer "F.SilkS")
		)
		(fp_line
			(start 3.792474 -0.383794)
			(end 4.35483 -0.923036)
			(stroke
				(width 0.1)
				(type default)
			)
			(layer "F.SilkS")
		)
		(fp_line
			(start 3.792474 -0.383794)
			(end 4.35483 -0.923036)
			(stroke
				(width 0.1)
				(type default)
			)
			(layer "F.SilkS")
		)
		(fp_line
			(start 3.828288 -5.381498)
			(end 2.992628 -4.57962)
			(stroke
				(width 0.1)
				(type default)
			)
			(layer "F.SilkS")
		)
		(fp_line
			(start 3.828288 -5.381498)
			(end 2.992628 -4.57962)
			(stroke
				(width 0.1)
				(type default)
			)
			(layer "F.SilkS")
		)
		(fp_line
			(start 3.8354 -0.36703)
			(end 4.389374 -0.898398)
			(stroke
				(width 0.1)
				(type default)
			)
			(layer "F.SilkS")
		)
		(fp_line
			(start 3.8354 -0.36703)
			(end 4.389374 -0.898398)
			(stroke
				(width 0.1)
				(type default)
			)
			(layer "F.SilkS")
		)
		(fp_line
			(start 3.870198 -5.363464)
			(end 3.036824 -4.56438)
			(stroke
				(width 0.1)
				(type default)
			)
			(layer "F.SilkS")
		)
		(fp_line
			(start 3.870198 -5.363464)
			(end 3.036824 -4.56438)
			(stroke
				(width 0.1)
				(type default)
			)
			(layer "F.SilkS")
		)
		(fp_line
			(start 3.878326 -0.35052)
			(end 4.423918 -0.874014)
			(stroke
				(width 0.1)
				(type default)
			)
			(layer "F.SilkS")
		)
		(fp_line
			(start 3.878326 -0.35052)
			(end 4.423918 -0.874014)
			(stroke
				(width 0.1)
				(type default)
			)
			(layer "F.SilkS")
		)
		(fp_line
			(start 3.908552 -5.34289)
			(end 3.080766 -4.548886)
			(stroke
				(width 0.1)
				(type default)
			)
			(layer "F.SilkS")
		)
		(fp_line
			(start 3.908552 -5.34289)
			(end 3.080766 -4.548886)
			(stroke
				(width 0.1)
				(type default)
			)
			(layer "F.SilkS")
		)
		(fp_line
			(start 3.921252 -0.33401)
			(end 4.458462 -0.849376)
			(stroke
				(width 0.1)
				(type default)
			)
			(layer "F.SilkS")
		)
		(fp_line
			(start 3.921252 -0.33401)
			(end 4.458462 -0.849376)
			(stroke
				(width 0.1)
				(type default)
			)
			(layer "F.SilkS")
		)
		(fp_line
			(start 3.946652 -5.321808)
			(end 3.12039 -4.529074)
			(stroke
				(width 0.1)
				(type default)
			)
			(layer "F.SilkS")
		)
		(fp_line
			(start 3.946652 -5.321808)
			(end 3.12039 -4.529074)
			(stroke
				(width 0.1)
				(type default)
			)
			(layer "F.SilkS")
		)
		(fp_line
			(start 3.964178 -0.3175)
			(end 4.493006 -0.824738)
			(stroke
				(width 0.1)
				(type default)
			)
			(layer "F.SilkS")
		)
		(fp_line
			(start 3.964178 -0.3175)
			(end 4.493006 -0.824738)
			(stroke
				(width 0.1)
				(type default)
			)
			(layer "F.SilkS")
		)
		(fp_line
			(start 3.984752 -5.300472)
			(end 3.15722 -4.506722)
			(stroke
				(width 0.1)
				(type default)
			)
			(layer "F.SilkS")
		)
		(fp_line
			(start 3.984752 -5.300472)
			(end 3.15722 -4.506722)
			(stroke
				(width 0.1)
				(type default)
			)
			(layer "F.SilkS")
		)
		(fp_line
			(start 4.00685 -0.30099)
			(end 4.52755 -0.800608)
			(stroke
				(width 0.1)
				(type default)
			)
			(layer "F.SilkS")
		)
		(fp_line
			(start 4.00685 -0.30099)
			(end 4.52755 -0.800608)
			(stroke
				(width 0.1)
				(type default)
			)
			(layer "F.SilkS")
		)
		(fp_line
			(start 4.022852 -5.27939)
			(end 3.193796 -4.484116)
			(stroke
				(width 0.1)
				(type default)
			)
			(layer "F.SilkS")
		)
		(fp_line
			(start 4.022852 -5.27939)
			(end 3.193796 -4.484116)
			(stroke
				(width 0.1)
				(type default)
			)
			(layer "F.SilkS")
		)
		(fp_line
			(start 4.049776 -0.284226)
			(end 4.562094 -0.775716)
			(stroke
				(width 0.1)
				(type default)
			)
			(layer "F.SilkS")
		)
		(fp_line
			(start 4.049776 -0.284226)
			(end 4.562094 -0.775716)
			(stroke
				(width 0.1)
				(type default)
			)
			(layer "F.SilkS")
		)
		(fp_line
			(start 4.060952 -5.258054)
			(end 3.230372 -4.461256)
			(stroke
				(width 0.1)
				(type default)
			)
			(layer "F.SilkS")
		)
		(fp_line
			(start 4.060952 -5.258054)
			(end 3.230372 -4.461256)
			(stroke
				(width 0.1)
				(type default)
			)
			(layer "F.SilkS")
		)
		(fp_line
			(start 4.092448 -0.267462)
			(end 4.596892 -0.751332)
			(stroke
				(width 0.1)
				(type default)
			)
			(layer "F.SilkS")
		)
		(fp_line
			(start 4.092448 -0.267462)
			(end 4.596892 -0.751332)
			(stroke
				(width 0.1)
				(type default)
			)
			(layer "F.SilkS")
		)
		(fp_line
			(start 4.09829 -5.23621)
			(end 3.266948 -4.438904)
			(stroke
				(width 0.1)
				(type default)
			)
			(layer "F.SilkS")
		)
		(fp_line
			(start 4.09829 -5.23621)
			(end 3.266948 -4.438904)
			(stroke
				(width 0.1)
				(type default)
			)
			(layer "F.SilkS")
		)
		(fp_line
			(start 4.133088 -5.21208)
			(end 3.303524 -4.416044)
			(stroke
				(width 0.1)
				(type default)
			)
			(layer "F.SilkS")
		)
		(fp_line
			(start 4.133088 -5.21208)
			(end 3.303524 -4.416044)
			(stroke
				(width 0.1)
				(type default)
			)
			(layer "F.SilkS")
		)
		(fp_line
			(start 4.135374 -0.250698)
			(end 4.631436 -0.726694)
			(stroke
				(width 0.1)
				(type default)
			)
			(layer "F.SilkS")
		)
		(fp_line
			(start 4.135374 -0.250698)
			(end 4.631436 -0.726694)
			(stroke
				(width 0.1)
				(type default)
			)
			(layer "F.SilkS")
		)
		(fp_line
			(start 4.16814 -5.187696)
			(end 3.337052 -4.390644)
			(stroke
				(width 0.1)
				(type default)
			)
			(layer "F.SilkS")
		)
		(fp_line
			(start 4.16814 -5.187696)
			(end 3.337052 -4.390644)
			(stroke
				(width 0.1)
				(type default)
			)
			(layer "F.SilkS")
		)
		(fp_line
			(start 4.178046 -0.234188)
			(end 4.66598 -0.702056)
			(stroke
				(width 0.1)
				(type default)
			)
			(layer "F.SilkS")
		)
		(fp_line
			(start 4.178046 -0.234188)
			(end 4.66598 -0.702056)
			(stroke
				(width 0.1)
				(type default)
			)
			(layer "F.SilkS")
		)
		(fp_line
			(start 4.181856 -1.045718)
			(end 3.576828 -0.465582)
			(stroke
				(width 0.1)
				(type default)
			)
			(layer "F.SilkS")
		)
		(fp_line
			(start 4.181856 -1.045718)
			(end 3.576828 -0.465582)
			(stroke
				(width 0.1)
				(type default)
			)
			(layer "F.SilkS")
		)
		(fp_line
			(start 4.202938 -5.163312)
			(end 3.367532 -4.362196)
			(stroke
				(width 0.1)
				(type default)
			)
			(layer "F.SilkS")
		)
		(fp_line
			(start 4.202938 -5.163312)
			(end 3.367532 -4.362196)
			(stroke
				(width 0.1)
				(type default)
			)
			(layer "F.SilkS")
		)
		(fp_line
			(start 4.220718 -0.217678)
			(end 4.700524 -0.677926)
			(stroke
				(width 0.1)
				(type default)
			)
			(layer "F.SilkS")
		)
		(fp_line
			(start 4.220718 -0.217678)
			(end 4.700524 -0.677926)
			(stroke
				(width 0.1)
				(type default)
			)
			(layer "F.SilkS")
		)
		(fp_line
			(start 4.237736 -5.139182)
			(end 3.397504 -4.33324)
			(stroke
				(width 0.1)
				(type default)
			)
			(layer "F.SilkS")
		)
		(fp_line
			(start 4.237736 -5.139182)
			(end 3.397504 -4.33324)
			(stroke
				(width 0.1)
				(type default)
			)
			(layer "F.SilkS")
		)
		(fp_line
			(start 4.26339 -0.200406)
			(end 4.735068 -0.653034)
			(stroke
				(width 0.1)
				(type default)
			)
			(layer "F.SilkS")
		)
		(fp_line
			(start 4.26339 -0.200406)
			(end 4.735068 -0.653034)
			(stroke
				(width 0.1)
				(type default)
			)
			(layer "F.SilkS")
		)
		(fp_line
			(start 4.272534 -5.115052)
			(end 3.427984 -4.304792)
			(stroke
				(width 0.1)
				(type default)
			)
			(layer "F.SilkS")
		)
		(fp_line
			(start 4.272534 -5.115052)
			(end 3.427984 -4.304792)
			(stroke
				(width 0.1)
				(type default)
			)
			(layer "F.SilkS")
		)
		(fp_line
			(start 4.306062 -0.183896)
			(end 4.769866 -0.62865)
			(stroke
				(width 0.1)
				(type default)
			)
			(layer "F.SilkS")
		)
		(fp_line
			(start 4.306062 -0.183896)
			(end 4.769866 -0.62865)
			(stroke
				(width 0.1)
				(type default)
			)
			(layer "F.SilkS")
		)
		(fp_line
			(start 4.306316 -5.089398)
			(end 3.45821 -4.275836)
			(stroke
				(width 0.1)
				(type default)
			)
			(layer "F.SilkS")
		)
		(fp_line
			(start 4.306316 -5.089398)
			(end 3.45821 -4.275836)
			(stroke
				(width 0.1)
				(type default)
			)
			(layer "F.SilkS")
		)
		(fp_line
			(start 4.338066 -5.06222)
			(end 3.488436 -4.247388)
			(stroke
				(width 0.1)
				(type default)
			)
			(layer "F.SilkS")
		)
		(fp_line
			(start 4.338066 -5.06222)
			(end 3.488436 -4.247388)
			(stroke
				(width 0.1)
				(type default)
			)
			(layer "F.SilkS")
		)
		(fp_line
			(start 4.348734 -0.166878)
			(end 4.80441 -0.604266)
			(stroke
				(width 0.1)
				(type default)
			)
			(layer "F.SilkS")
		)
		(fp_line
			(start 4.348734 -0.166878)
			(end 4.80441 -0.604266)
			(stroke
				(width 0.1)
				(type default)
			)
			(layer "F.SilkS")
		)
		(fp_line
			(start 4.37007 -5.035296)
			(end 3.518408 -4.218432)
			(stroke
				(width 0.1)
				(type default)
			)
			(layer "F.SilkS")
		)
		(fp_line
			(start 4.37007 -5.035296)
			(end 3.518408 -4.218432)
			(stroke
				(width 0.1)
				(type default)
			)
			(layer "F.SilkS")
		)
		(fp_line
			(start 4.391406 -0.150114)
			(end 4.838954 -0.579628)
			(stroke
				(width 0.1)
				(type default)
			)
			(layer "F.SilkS")
		)
		(fp_line
			(start 4.391406 -0.150114)
			(end 4.838954 -0.579628)
			(stroke
				(width 0.1)
				(type default)
			)
			(layer "F.SilkS")
		)
		(fp_line
			(start 4.401566 -5.008118)
			(end 3.542792 -4.183888)
			(stroke
				(width 0.1)
				(type default)
			)
			(layer "F.SilkS")
		)
		(fp_line
			(start 4.401566 -5.008118)
			(end 3.542792 -4.183888)
			(stroke
				(width 0.1)
				(type default)
			)
			(layer "F.SilkS")
		)
		(fp_line
			(start 4.43357 -4.98094)
			(end 3.567176 -4.149598)
			(stroke
				(width 0.1)
				(type default)
			)
			(layer "F.SilkS")
		)
		(fp_line
			(start 4.43357 -4.98094)
			(end 3.567176 -4.149598)
			(stroke
				(width 0.1)
				(type default)
			)
			(layer "F.SilkS")
		)
		(fp_line
			(start 4.433824 -0.133604)
			(end 4.873752 -0.555244)
			(stroke
				(width 0.1)
				(type default)
			)
			(layer "F.SilkS")
		)
		(fp_line
			(start 4.433824 -0.133604)
			(end 4.873752 -0.555244)
			(stroke
				(width 0.1)
				(type default)
			)
			(layer "F.SilkS")
		)
		(fp_line
			(start 4.46532 -4.953508)
			(end 3.59156 -4.115308)
			(stroke
				(width 0.1)
				(type default)
			)
			(layer "F.SilkS")
		)
		(fp_line
			(start 4.46532 -4.953508)
			(end 3.59156 -4.115308)
			(stroke
				(width 0.1)
				(type default)
			)
			(layer "F.SilkS")
		)
		(fp_line
			(start 4.476496 -0.116332)
			(end 4.908296 -0.530352)
			(stroke
				(width 0.1)
				(type default)
			)
			(layer "F.SilkS")
		)
		(fp_line
			(start 4.476496 -0.116332)
			(end 4.908296 -0.530352)
			(stroke
				(width 0.1)
				(type default)
			)
			(layer "F.SilkS")
		)
		(fp_line
			(start 4.4958 -4.92506)
			(end 3.615944 -4.081018)
			(stroke
				(width 0.1)
				(type default)
			)
			(layer "F.SilkS")
		)
		(fp_line
			(start 4.4958 -4.92506)
			(end 3.615944 -4.081018)
			(stroke
				(width 0.1)
				(type default)
			)
			(layer "F.SilkS")
		)
		(fp_line
			(start 4.519168 -0.099822)
			(end 4.94284 -0.506222)
			(stroke
				(width 0.1)
				(type default)
			)
			(layer "F.SilkS")
		)
		(fp_line
			(start 4.519168 -0.099822)
			(end 4.94284 -0.506222)
			(stroke
				(width 0.1)
				(type default)
			)
			(layer "F.SilkS")
		)
		(fp_line
			(start 4.52374 -4.894072)
			(end 3.640328 -4.046728)
			(stroke
				(width 0.1)
				(type default)
			)
			(layer "F.SilkS")
		)
		(fp_line
			(start 4.52374 -4.894072)
			(end 3.640328 -4.046728)
			(stroke
				(width 0.1)
				(type default)
			)
			(layer "F.SilkS")
		)
		(fp_line
			(start 4.55168 -4.863338)
			(end 3.664712 -4.012438)
			(stroke
				(width 0.1)
				(type default)
			)
			(layer "F.SilkS")
		)
		(fp_line
			(start 4.55168 -4.863338)
			(end 3.664712 -4.012438)
			(stroke
				(width 0.1)
				(type default)
			)
			(layer "F.SilkS")
		)
		(fp_line
			(start 4.561586 -0.08255)
			(end 4.977384 -0.481584)
			(stroke
				(width 0.1)
				(type default)
			)
			(layer "F.SilkS")
		)
		(fp_line
			(start 4.561586 -0.08255)
			(end 4.977384 -0.481584)
			(stroke
				(width 0.1)
				(type default)
			)
			(layer "F.SilkS")
		)
		(fp_line
			(start 4.57962 -4.83235)
			(end 3.686556 -3.975608)
			(stroke
				(width 0.1)
				(type default)
			)
			(layer "F.SilkS")
		)
		(fp_line
			(start 4.57962 -4.83235)
			(end 3.686556 -3.975608)
			(stroke
				(width 0.1)
				(type default)
			)
			(layer "F.SilkS")
		)
		(fp_line
			(start 4.60756 -4.801362)
			(end 3.704844 -3.935476)
			(stroke
				(width 0.1)
				(type default)
			)
			(layer "F.SilkS")
		)
		(fp_line
			(start 4.60756 -4.801362)
			(end 3.704844 -3.935476)
			(stroke
				(width 0.1)
				(type default)
			)
			(layer "F.SilkS")
		)
		(fp_line
			(start 4.631182 -0.091948)
			(end 4.713478 -0.112776)
			(stroke
				(width 0.1)
				(type default)
			)
			(layer "F.SilkS")
		)
		(fp_line
			(start 4.631182 -0.091948)
			(end 4.713478 -0.112776)
			(stroke
				(width 0.1)
				(type default)
			)
			(layer "F.SilkS")
		)
		(fp_line
			(start 4.631182 -0.091948)
			(end 5.012182 -0.456946)
			(stroke
				(width 0.1)
				(type default)
			)
			(layer "F.SilkS")
		)
		(fp_line
			(start 4.631182 -0.091948)
			(end 5.012182 -0.456946)
			(stroke
				(width 0.1)
				(type default)
			)
			(layer "F.SilkS")
		)
		(fp_line
			(start 4.635246 -4.770374)
			(end 3.723386 -3.895598)
			(stroke
				(width 0.1)
				(type default)
			)
			(layer "F.SilkS")
		)
		(fp_line
			(start 4.635246 -4.770374)
			(end 3.723386 -3.895598)
			(stroke
				(width 0.1)
				(type default)
			)
			(layer "F.SilkS")
		)
		(fp_line
			(start 4.663186 -4.739386)
			(end 3.741928 -3.85572)
			(stroke
				(width 0.1)
				(type default)
			)
			(layer "F.SilkS")
		)
		(fp_line
			(start 4.663186 -4.739386)
			(end 3.741928 -3.85572)
			(stroke
				(width 0.1)
				(type default)
			)
			(layer "F.SilkS")
		)
		(fp_line
			(start 4.690618 -4.70789)
			(end 3.76047 -3.815588)
			(stroke
				(width 0.1)
				(type default)
			)
			(layer "F.SilkS")
		)
		(fp_line
			(start 4.690618 -4.70789)
			(end 3.76047 -3.815588)
			(stroke
				(width 0.1)
				(type default)
			)
			(layer "F.SilkS")
		)
		(fp_line
			(start 4.713478 -0.112776)
			(end 4.795266 -0.133604)
			(stroke
				(width 0.1)
				(type default)
			)
			(layer "F.SilkS")
		)
		(fp_line
			(start 4.713478 -0.112776)
			(end 4.795266 -0.133604)
			(stroke
				(width 0.1)
				(type default)
			)
			(layer "F.SilkS")
		)
		(fp_line
			(start 4.713478 -0.112776)
			(end 5.046726 -0.432562)
			(stroke
				(width 0.1)
				(type default)
			)
			(layer "F.SilkS")
		)
		(fp_line
			(start 4.713478 -0.112776)
			(end 5.046726 -0.432562)
			(stroke
				(width 0.1)
				(type default)
			)
			(layer "F.SilkS")
		)
		(fp_line
			(start 4.713732 -4.672584)
			(end 3.778758 -3.775456)
			(stroke
				(width 0.1)
				(type default)
			)
			(layer "F.SilkS")
		)
		(fp_line
			(start 4.713732 -4.672584)
			(end 3.778758 -3.775456)
			(stroke
				(width 0.1)
				(type default)
			)
			(layer "F.SilkS")
		)
		(fp_line
			(start 4.7371 -4.637278)
			(end 3.7973 -3.735578)
			(stroke
				(width 0.1)
				(type default)
			)
			(layer "F.SilkS")
		)
		(fp_line
			(start 4.7371 -4.637278)
			(end 3.7973 -3.735578)
			(stroke
				(width 0.1)
				(type default)
			)
			(layer "F.SilkS")
		)
		(fp_line
			(start 4.760214 -4.601718)
			(end 3.81 -3.689858)
			(stroke
				(width 0.1)
				(type default)
			)
			(layer "F.SilkS")
		)
		(fp_line
			(start 4.760214 -4.601718)
			(end 3.81 -3.689858)
			(stroke
				(width 0.1)
				(type default)
			)
			(layer "F.SilkS")
		)
		(fp_line
			(start 4.783582 -4.566158)
			(end 3.821938 -3.643884)
			(stroke
				(width 0.1)
				(type default)
			)
			(layer "F.SilkS")
		)
		(fp_line
			(start 4.783582 -4.566158)
			(end 3.821938 -3.643884)
			(stroke
				(width 0.1)
				(type default)
			)
			(layer "F.SilkS")
		)
		(fp_line
			(start 4.795266 -0.133604)
			(end 4.877308 -0.15494)
			(stroke
				(width 0.1)
				(type default)
			)
			(layer "F.SilkS")
		)
		(fp_line
			(start 4.795266 -0.133604)
			(end 4.877308 -0.15494)
			(stroke
				(width 0.1)
				(type default)
			)
			(layer "F.SilkS")
		)
		(fp_line
			(start 4.795266 -0.133604)
			(end 5.08127 -0.408178)
			(stroke
				(width 0.1)
				(type default)
			)
			(layer "F.SilkS")
		)
		(fp_line
			(start 4.795266 -0.133604)
			(end 5.08127 -0.408178)
			(stroke
				(width 0.1)
				(type default)
			)
			(layer "F.SilkS")
		)
		(fp_line
			(start 4.806696 -4.530852)
			(end 3.83413 -3.59791)
			(stroke
				(width 0.1)
				(type default)
			)
			(layer "F.SilkS")
		)
		(fp_line
			(start 4.806696 -4.530852)
			(end 3.83413 -3.59791)
			(stroke
				(width 0.1)
				(type default)
			)
			(layer "F.SilkS")
		)
		(fp_line
			(start 4.82981 -4.495292)
			(end 3.846068 -3.551682)
			(stroke
				(width 0.1)
				(type default)
			)
			(layer "F.SilkS")
		)
		(fp_line
			(start 4.82981 -4.495292)
			(end 3.846068 -3.551682)
			(stroke
				(width 0.1)
				(type default)
			)
			(layer "F.SilkS")
		)
		(fp_line
			(start 4.851654 -4.458462)
			(end 3.858006 -3.505454)
			(stroke
				(width 0.1)
				(type default)
			)
			(layer "F.SilkS")
		)
		(fp_line
			(start 4.851654 -4.458462)
			(end 3.858006 -3.505454)
			(stroke
				(width 0.1)
				(type default)
			)
			(layer "F.SilkS")
		)
		(fp_line
			(start 4.870958 -4.419092)
			(end 3.870198 -3.459226)
			(stroke
				(width 0.1)
				(type default)
			)
			(layer "F.SilkS")
		)
		(fp_line
			(start 4.870958 -4.419092)
			(end 3.870198 -3.459226)
			(stroke
				(width 0.1)
				(type default)
			)
			(layer "F.SilkS")
		)
		(fp_line
			(start 4.877308 -0.15494)
			(end 4.95935 -0.175514)
			(stroke
				(width 0.1)
				(type default)
			)
			(layer "F.SilkS")
		)
		(fp_line
			(start 4.877308 -0.15494)
			(end 4.95935 -0.175514)
			(stroke
				(width 0.1)
				(type default)
			)
			(layer "F.SilkS")
		)
		(fp_line
			(start 4.877308 -0.15494)
			(end 5.115814 -0.383794)
			(stroke
				(width 0.1)
				(type default)
			)
			(layer "F.SilkS")
		)
		(fp_line
			(start 4.877308 -0.15494)
			(end 5.115814 -0.383794)
			(stroke
				(width 0.1)
				(type default)
			)
			(layer "F.SilkS")
		)
		(fp_line
			(start 4.889754 -4.379722)
			(end 3.878072 -3.409188)
			(stroke
				(width 0.1)
				(type default)
			)
			(layer "F.SilkS")
		)
		(fp_line
			(start 4.889754 -4.379722)
			(end 3.878072 -3.409188)
			(stroke
				(width 0.1)
				(type default)
			)
			(layer "F.SilkS")
		)
		(fp_line
			(start 4.908804 -4.340098)
			(end 3.88239 -3.355848)
			(stroke
				(width 0.1)
				(type default)
			)
			(layer "F.SilkS")
		)
		(fp_line
			(start 4.908804 -4.340098)
			(end 3.88239 -3.355848)
			(stroke
				(width 0.1)
				(type default)
			)
			(layer "F.SilkS")
		)
		(fp_line
			(start 4.927854 -4.300728)
			(end 3.886962 -3.302254)
			(stroke
				(width 0.1)
				(type default)
			)
			(layer "F.SilkS")
		)
		(fp_line
			(start 4.927854 -4.300728)
			(end 3.886962 -3.302254)
			(stroke
				(width 0.1)
				(type default)
			)
			(layer "F.SilkS")
		)
		(fp_line
			(start 4.946904 -4.261358)
			(end 3.891534 -3.248914)
			(stroke
				(width 0.1)
				(type default)
			)
			(layer "F.SilkS")
		)
		(fp_line
			(start 4.946904 -4.261358)
			(end 3.891534 -3.248914)
			(stroke
				(width 0.1)
				(type default)
			)
			(layer "F.SilkS")
		)
		(fp_line
			(start 4.95935 -0.175514)
			(end 5.041392 -0.196596)
			(stroke
				(width 0.1)
				(type default)
			)
			(layer "F.SilkS")
		)
		(fp_line
			(start 4.95935 -0.175514)
			(end 5.041392 -0.196596)
			(stroke
				(width 0.1)
				(type default)
			)
			(layer "F.SilkS")
		)
		(fp_line
			(start 4.95935 -0.175514)
			(end 5.150612 -0.359156)
			(stroke
				(width 0.1)
				(type default)
			)
			(layer "F.SilkS")
		)
		(fp_line
			(start 4.95935 -0.175514)
			(end 5.150612 -0.359156)
			(stroke
				(width 0.1)
				(type default)
			)
			(layer "F.SilkS")
		)
		(fp_line
			(start 4.965446 -4.221226)
			(end 3.895852 -3.19532)
			(stroke
				(width 0.1)
				(type default)
			)
			(layer "F.SilkS")
		)
		(fp_line
			(start 4.965446 -4.221226)
			(end 3.895852 -3.19532)
			(stroke
				(width 0.1)
				(type default)
			)
			(layer "F.SilkS")
		)
		(fp_line
			(start 4.980686 -4.1783)
			(end 3.900424 -3.14198)
			(stroke
				(width 0.1)
				(type default)
			)
			(layer "F.SilkS")
		)
		(fp_line
			(start 4.980686 -4.1783)
			(end 3.900424 -3.14198)
			(stroke
				(width 0.1)
				(type default)
			)
			(layer "F.SilkS")
		)
		(fp_line
			(start 4.995672 -4.13512)
			(end 3.899408 -3.083306)
			(stroke
				(width 0.1)
				(type default)
			)
			(layer "F.SilkS")
		)
		(fp_line
			(start 4.995672 -4.13512)
			(end 3.899408 -3.083306)
			(stroke
				(width 0.1)
				(type default)
			)
			(layer "F.SilkS")
		)
		(fp_line
			(start 5.011166 -4.09194)
			(end 3.894328 -3.020822)
			(stroke
				(width 0.1)
				(type default)
			)
			(layer "F.SilkS")
		)
		(fp_line
			(start 5.011166 -4.09194)
			(end 3.894328 -3.020822)
			(stroke
				(width 0.1)
				(type default)
			)
			(layer "F.SilkS")
		)
		(fp_line
			(start 5.026152 -4.04876)
			(end 3.889248 -2.958084)
			(stroke
				(width 0.1)
				(type default)
			)
			(layer "F.SilkS")
		)
		(fp_line
			(start 5.026152 -4.04876)
			(end 3.889248 -2.958084)
			(stroke
				(width 0.1)
				(type default)
			)
			(layer "F.SilkS")
		)
		(fp_line
			(start 5.041392 -4.00558)
			(end 3.884168 -2.8956)
			(stroke
				(width 0.1)
				(type default)
			)
			(layer "F.SilkS")
		)
		(fp_line
			(start 5.041392 -4.00558)
			(end 3.884168 -2.8956)
			(stroke
				(width 0.1)
				(type default)
			)
			(layer "F.SilkS")
		)
		(fp_line
			(start 5.041392 -0.196596)
			(end 5.12318 -0.217678)
			(stroke
				(width 0.1)
				(type default)
			)
			(layer "F.SilkS")
		)
		(fp_line
			(start 5.041392 -0.196596)
			(end 5.12318 -0.217678)
			(stroke
				(width 0.1)
				(type default)
			)
			(layer "F.SilkS")
		)
		(fp_line
			(start 5.041392 -0.196596)
			(end 5.185156 -0.334772)
			(stroke
				(width 0.1)
				(type default)
			)
			(layer "F.SilkS")
		)
		(fp_line
			(start 5.041392 -0.196596)
			(end 5.185156 -0.334772)
			(stroke
				(width 0.1)
				(type default)
			)
			(layer "F.SilkS")
		)
		(fp_line
			(start 5.0546 -3.960622)
			(end 3.879088 -2.832862)
			(stroke
				(width 0.1)
				(type default)
			)
			(layer "F.SilkS")
		)
		(fp_line
			(start 5.0546 -3.960622)
			(end 3.879088 -2.832862)
			(stroke
				(width 0.1)
				(type default)
			)
			(layer "F.SilkS")
		)
		(fp_line
			(start 5.066284 -3.91414)
			(end 3.863086 -2.75971)
			(stroke
				(width 0.1)
				(type default)
			)
			(layer "F.SilkS")
		)
		(fp_line
			(start 5.066284 -3.91414)
			(end 3.863086 -2.75971)
			(stroke
				(width 0.1)
				(type default)
			)
			(layer "F.SilkS")
		)
		(fp_line
			(start 5.078222 -3.867658)
			(end 3.843782 -2.68351)
			(stroke
				(width 0.1)
				(type default)
			)
			(layer "F.SilkS")
		)
		(fp_line
			(start 5.078222 -3.867658)
			(end 3.843782 -2.68351)
			(stroke
				(width 0.1)
				(type default)
			)
			(layer "F.SilkS")
		)
		(fp_line
			(start 5.089652 -3.821176)
			(end 3.824478 -2.607564)
			(stroke
				(width 0.1)
				(type default)
			)
			(layer "F.SilkS")
		)
		(fp_line
			(start 5.089652 -3.821176)
			(end 3.824478 -2.607564)
			(stroke
				(width 0.1)
				(type default)
			)
			(layer "F.SilkS")
		)
		(fp_line
			(start 5.101336 -3.774694)
			(end 3.802126 -2.528316)
			(stroke
				(width 0.1)
				(type default)
			)
			(layer "F.SilkS")
		)
		(fp_line
			(start 5.101336 -3.774694)
			(end 3.802126 -2.528316)
			(stroke
				(width 0.1)
				(type default)
			)
			(layer "F.SilkS")
		)
		(fp_line
			(start 5.110734 -3.72618)
			(end 3.756406 -2.426716)
			(stroke
				(width 0.1)
				(type default)
			)
			(layer "F.SilkS")
		)
		(fp_line
			(start 5.110734 -3.72618)
			(end 3.756406 -2.426716)
			(stroke
				(width 0.1)
				(type default)
			)
			(layer "F.SilkS")
		)
		(fp_line
			(start 5.11937 -3.676396)
			(end 3.710686 -2.32537)
			(stroke
				(width 0.1)
				(type default)
			)
			(layer "F.SilkS")
		)
		(fp_line
			(start 5.11937 -3.676396)
			(end 3.710686 -2.32537)
			(stroke
				(width 0.1)
				(type default)
			)
			(layer "F.SilkS")
		)
		(fp_line
			(start 5.12318 -0.217678)
			(end 5.205222 -0.238252)
			(stroke
				(width 0.1)
				(type default)
			)
			(layer "F.SilkS")
		)
		(fp_line
			(start 5.12318 -0.217678)
			(end 5.205222 -0.238252)
			(stroke
				(width 0.1)
				(type default)
			)
			(layer "F.SilkS")
		)
		(fp_line
			(start 5.12318 -0.217678)
			(end 5.219954 -0.310388)
			(stroke
				(width 0.1)
				(type default)
			)
			(layer "F.SilkS")
		)
		(fp_line
			(start 5.12318 -0.217678)
			(end 5.219954 -0.310388)
			(stroke
				(width 0.1)
				(type default)
			)
			(layer "F.SilkS")
		)
		(fp_line
			(start 5.127498 -3.626612)
			(end 3.618992 -2.17932)
			(stroke
				(width 0.1)
				(type default)
			)
			(layer "F.SilkS")
		)
		(fp_line
			(start 5.127498 -3.626612)
			(end 3.618992 -2.17932)
			(stroke
				(width 0.1)
				(type default)
			)
			(layer "F.SilkS")
		)
		(fp_line
			(start 5.13588 -3.576828)
			(end 2.15773 -0.719836)
			(stroke
				(width 0.1)
				(type default)
			)
			(layer "F.SilkS")
		)
		(fp_line
			(start 5.13588 -3.576828)
			(end 2.15773 -0.719836)
			(stroke
				(width 0.1)
				(type default)
			)
			(layer "F.SilkS")
		)
		(fp_line
			(start 5.205222 -0.238252)
			(end 5.254752 -0.28575)
			(stroke
				(width 0.1)
				(type default)
			)
			(layer "F.SilkS")
		)
		(fp_line
			(start 5.205222 -0.238252)
			(end 5.254752 -0.28575)
			(stroke
				(width 0.1)
				(type default)
			)
			(layer "F.SilkS")
		)
		(fp_line
			(start 5.287264 -0.259588)
			(end 5.205222 -0.238252)
			(stroke
				(width 0.1)
				(type default)
			)
			(layer "F.SilkS")
		)
		(fp_line
			(start 5.287264 -0.259588)
			(end 5.205222 -0.238252)
			(stroke
				(width 0.1)
				(type default)
			)
			(layer "F.SilkS")
		)
		(fp_line
			(start 5.287264 -0.259588)
			(end 5.289296 -0.261366)
			(stroke
				(width 0.1)
				(type default)
			)
			(layer "F.SilkS")
		)
		(fp_line
			(start 5.287264 -0.259588)
			(end 5.289296 -0.261366)
			(stroke
				(width 0.1)
				(type default)
			)
			(layer "F.SilkS")
		)
		(fp_line
			(start 5.507482 -2.281682)
			(end 6.825488 -3.54584)
			(stroke
				(width 0.1)
				(type default)
			)
			(layer "F.SilkS")
		)
		(fp_line
			(start 5.507482 -2.281682)
			(end 6.825488 -3.54584)
			(stroke
				(width 0.1)
				(type default)
			)
			(layer "F.SilkS")
		)
		(fp_line
			(start 5.50799 -2.224278)
			(end 6.81355 -3.476498)
			(stroke
				(width 0.1)
				(type default)
			)
			(layer "F.SilkS")
		)
		(fp_line
			(start 5.50799 -2.224278)
			(end 6.81355 -3.476498)
			(stroke
				(width 0.1)
				(type default)
			)
			(layer "F.SilkS")
		)
		(fp_line
			(start 5.508498 -2.167128)
			(end 6.801104 -3.407156)
			(stroke
				(width 0.1)
				(type default)
			)
			(layer "F.SilkS")
		)
		(fp_line
			(start 5.508498 -2.167128)
			(end 6.801104 -3.407156)
			(stroke
				(width 0.1)
				(type default)
			)
			(layer "F.SilkS")
		)
		(fp_line
			(start 5.508752 -2.109724)
			(end 6.788912 -3.337814)
			(stroke
				(width 0.1)
				(type default)
			)
			(layer "F.SilkS")
		)
		(fp_line
			(start 5.508752 -2.109724)
			(end 6.788912 -3.337814)
			(stroke
				(width 0.1)
				(type default)
			)
			(layer "F.SilkS")
		)
		(fp_line
			(start 5.50926 -2.052574)
			(end 6.776974 -3.268472)
			(stroke
				(width 0.1)
				(type default)
			)
			(layer "F.SilkS")
		)
		(fp_line
			(start 5.50926 -2.052574)
			(end 6.776974 -3.268472)
			(stroke
				(width 0.1)
				(type default)
			)
			(layer "F.SilkS")
		)
		(fp_line
			(start 5.509768 -1.99517)
			(end 6.764782 -3.19913)
			(stroke
				(width 0.1)
				(type default)
			)
			(layer "F.SilkS")
		)
		(fp_line
			(start 5.509768 -1.99517)
			(end 6.764782 -3.19913)
			(stroke
				(width 0.1)
				(type default)
			)
			(layer "F.SilkS")
		)
		(fp_line
			(start 5.510276 -1.937766)
			(end 6.75259 -3.129534)
			(stroke
				(width 0.1)
				(type default)
			)
			(layer "F.SilkS")
		)
		(fp_line
			(start 5.510276 -1.937766)
			(end 6.75259 -3.129534)
			(stroke
				(width 0.1)
				(type default)
			)
			(layer "F.SilkS")
		)
		(fp_line
			(start 5.518912 -1.88849)
			(end 6.740144 -3.060192)
			(stroke
				(width 0.1)
				(type default)
			)
			(layer "F.SilkS")
		)
		(fp_line
			(start 5.518912 -1.88849)
			(end 6.740144 -3.060192)
			(stroke
				(width 0.1)
				(type default)
			)
			(layer "F.SilkS")
		)
		(fp_line
			(start 5.527802 -1.839214)
			(end 6.728206 -2.99085)
			(stroke
				(width 0.1)
				(type default)
			)
			(layer "F.SilkS")
		)
		(fp_line
			(start 5.527802 -1.839214)
			(end 6.728206 -2.99085)
			(stroke
				(width 0.1)
				(type default)
			)
			(layer "F.SilkS")
		)
		(fp_line
			(start 5.536438 -1.789938)
			(end 6.716014 -2.921254)
			(stroke
				(width 0.1)
				(type default)
			)
			(layer "F.SilkS")
		)
		(fp_line
			(start 5.536438 -1.789938)
			(end 6.716014 -2.921254)
			(stroke
				(width 0.1)
				(type default)
			)
			(layer "F.SilkS")
		)
		(fp_line
			(start 5.545582 -1.740916)
			(end 6.703822 -2.852166)
			(stroke
				(width 0.1)
				(type default)
			)
			(layer "F.SilkS")
		)
		(fp_line
			(start 5.545582 -1.740916)
			(end 6.703822 -2.852166)
			(stroke
				(width 0.1)
				(type default)
			)
			(layer "F.SilkS")
		)
		(fp_line
			(start 5.554218 -1.69164)
			(end 6.695186 -2.786126)
			(stroke
				(width 0.1)
				(type default)
			)
			(layer "F.SilkS")
		)
		(fp_line
			(start 5.554218 -1.69164)
			(end 6.695186 -2.786126)
			(stroke
				(width 0.1)
				(type default)
			)
			(layer "F.SilkS")
		)
		(fp_line
			(start 5.563108 -1.642364)
			(end 6.68655 -2.720086)
			(stroke
				(width 0.1)
				(type default)
			)
			(layer "F.SilkS")
		)
		(fp_line
			(start 5.563108 -1.642364)
			(end 6.68655 -2.720086)
			(stroke
				(width 0.1)
				(type default)
			)
			(layer "F.SilkS")
		)
		(fp_line
			(start 5.573522 -1.594612)
			(end 6.678168 -2.6543)
			(stroke
				(width 0.1)
				(type default)
			)
			(layer "F.SilkS")
		)
		(fp_line
			(start 5.573522 -1.594612)
			(end 6.678168 -2.6543)
			(stroke
				(width 0.1)
				(type default)
			)
			(layer "F.SilkS")
		)
		(fp_line
			(start 5.58038 -2.870962)
			(end 5.568188 -2.801366)
			(stroke
				(width 0.1)
				(type default)
			)
			(layer "F.SilkS")
		)
		(fp_line
			(start 5.58038 -2.870962)
			(end 5.568188 -2.801366)
			(stroke
				(width 0.1)
				(type default)
			)
			(layer "F.SilkS")
		)
		(fp_line
			(start 5.591048 -1.553718)
			(end 6.669532 -2.58826)
			(stroke
				(width 0.1)
				(type default)
			)
			(layer "F.SilkS")
		)
		(fp_line
			(start 5.591048 -1.553718)
			(end 6.669532 -2.58826)
			(stroke
				(width 0.1)
				(type default)
			)
			(layer "F.SilkS")
		)
		(fp_line
			(start 5.592572 -2.940304)
			(end 5.58038 -2.870962)
			(stroke
				(width 0.1)
				(type default)
			)
			(layer "F.SilkS")
		)
		(fp_line
			(start 5.592572 -2.940304)
			(end 5.58038 -2.870962)
			(stroke
				(width 0.1)
				(type default)
			)
			(layer "F.SilkS")
		)
		(fp_line
			(start 5.604764 -3.009646)
			(end 5.592572 -2.940304)
			(stroke
				(width 0.1)
				(type default)
			)
			(layer "F.SilkS")
		)
		(fp_line
			(start 5.604764 -3.009646)
			(end 5.592572 -2.940304)
			(stroke
				(width 0.1)
				(type default)
			)
			(layer "F.SilkS")
		)
		(fp_line
			(start 5.60832 -1.51257)
			(end 6.669024 -2.530094)
			(stroke
				(width 0.1)
				(type default)
			)
			(layer "F.SilkS")
		)
		(fp_line
			(start 5.60832 -1.51257)
			(end 6.669024 -2.530094)
			(stroke
				(width 0.1)
				(type default)
			)
			(layer "F.SilkS")
		)
		(fp_line
			(start 5.616956 -3.079242)
			(end 5.604764 -3.009646)
			(stroke
				(width 0.1)
				(type default)
			)
			(layer "F.SilkS")
		)
		(fp_line
			(start 5.616956 -3.079242)
			(end 5.604764 -3.009646)
			(stroke
				(width 0.1)
				(type default)
			)
			(layer "F.SilkS")
		)
		(fp_line
			(start 5.625846 -1.471676)
			(end 6.668516 -2.471928)
			(stroke
				(width 0.1)
				(type default)
			)
			(layer "F.SilkS")
		)
		(fp_line
			(start 5.625846 -1.471676)
			(end 6.668516 -2.471928)
			(stroke
				(width 0.1)
				(type default)
			)
			(layer "F.SilkS")
		)
		(fp_line
			(start 5.629148 -3.148584)
			(end 5.616956 -3.079242)
			(stroke
				(width 0.1)
				(type default)
			)
			(layer "F.SilkS")
		)
		(fp_line
			(start 5.629148 -3.148584)
			(end 5.616956 -3.079242)
			(stroke
				(width 0.1)
				(type default)
			)
			(layer "F.SilkS")
		)
		(fp_line
			(start 5.64134 -3.217926)
			(end 5.629148 -3.148584)
			(stroke
				(width 0.1)
				(type default)
			)
			(layer "F.SilkS")
		)
		(fp_line
			(start 5.64134 -3.217926)
			(end 5.629148 -3.148584)
			(stroke
				(width 0.1)
				(type default)
			)
			(layer "F.SilkS")
		)
		(fp_line
			(start 5.643118 -1.430528)
			(end 6.668008 -2.413762)
			(stroke
				(width 0.1)
				(type default)
			)
			(layer "F.SilkS")
		)
		(fp_line
			(start 5.643118 -1.430528)
			(end 6.668008 -2.413762)
			(stroke
				(width 0.1)
				(type default)
			)
			(layer "F.SilkS")
		)
		(fp_line
			(start 5.653532 -3.287268)
			(end 5.64134 -3.217926)
			(stroke
				(width 0.1)
				(type default)
			)
			(layer "F.SilkS")
		)
		(fp_line
			(start 5.653532 -3.287268)
			(end 5.64134 -3.217926)
			(stroke
				(width 0.1)
				(type default)
			)
			(layer "F.SilkS")
		)
		(fp_line
			(start 5.660644 -1.389634)
			(end 6.67004 -2.357882)
			(stroke
				(width 0.1)
				(type default)
			)
			(layer "F.SilkS")
		)
		(fp_line
			(start 5.660644 -1.389634)
			(end 6.67004 -2.357882)
			(stroke
				(width 0.1)
				(type default)
			)
			(layer "F.SilkS")
		)
		(fp_line
			(start 5.665724 -3.35661)
			(end 5.653532 -3.287268)
			(stroke
				(width 0.1)
				(type default)
			)
			(layer "F.SilkS")
		)
		(fp_line
			(start 5.665724 -3.35661)
			(end 5.653532 -3.287268)
			(stroke
				(width 0.1)
				(type default)
			)
			(layer "F.SilkS")
		)
		(fp_line
			(start 5.677662 -3.425952)
			(end 5.665724 -3.35661)
			(stroke
				(width 0.1)
				(type default)
			)
			(layer "F.SilkS")
		)
		(fp_line
			(start 5.677662 -3.425952)
			(end 5.665724 -3.35661)
			(stroke
				(width 0.1)
				(type default)
			)
			(layer "F.SilkS")
		)
		(fp_line
			(start 5.677916 -1.34874)
			(end 6.678168 -2.308352)
			(stroke
				(width 0.1)
				(type default)
			)
			(layer "F.SilkS")
		)
		(fp_line
			(start 5.677916 -1.34874)
			(end 6.678168 -2.308352)
			(stroke
				(width 0.1)
				(type default)
			)
			(layer "F.SilkS")
		)
		(fp_line
			(start 5.690108 -3.495548)
			(end 5.677662 -3.425952)
			(stroke
				(width 0.1)
				(type default)
			)
			(layer "F.SilkS")
		)
		(fp_line
			(start 5.690108 -3.495548)
			(end 5.677662 -3.425952)
			(stroke
				(width 0.1)
				(type default)
			)
			(layer "F.SilkS")
		)
		(fp_line
			(start 5.697982 -1.310132)
			(end 6.68655 -2.258568)
			(stroke
				(width 0.1)
				(type default)
			)
			(layer "F.SilkS")
		)
		(fp_line
			(start 5.697982 -1.310132)
			(end 6.68655 -2.258568)
			(stroke
				(width 0.1)
				(type default)
			)
			(layer "F.SilkS")
		)
		(fp_line
			(start 5.7023 -3.56489)
			(end 5.690108 -3.495548)
			(stroke
				(width 0.1)
				(type default)
			)
			(layer "F.SilkS")
		)
		(fp_line
			(start 5.7023 -3.56489)
			(end 5.690108 -3.495548)
			(stroke
				(width 0.1)
				(type default)
			)
			(layer "F.SilkS")
		)
		(fp_line
			(start 5.714238 -3.634232)
			(end 5.7023 -3.56489)
			(stroke
				(width 0.1)
				(type default)
			)
			(layer "F.SilkS")
		)
		(fp_line
			(start 5.714238 -3.634232)
			(end 5.7023 -3.56489)
			(stroke
				(width 0.1)
				(type default)
			)
			(layer "F.SilkS")
		)
		(fp_line
			(start 5.724398 -1.27762)
			(end 6.694932 -2.20853)
			(stroke
				(width 0.1)
				(type default)
			)
			(layer "F.SilkS")
		)
		(fp_line
			(start 5.724398 -1.27762)
			(end 6.694932 -2.20853)
			(stroke
				(width 0.1)
				(type default)
			)
			(layer "F.SilkS")
		)
		(fp_line
			(start 5.72643 -3.703828)
			(end 5.714238 -3.634232)
			(stroke
				(width 0.1)
				(type default)
			)
			(layer "F.SilkS")
		)
		(fp_line
			(start 5.72643 -3.703828)
			(end 5.714238 -3.634232)
			(stroke
				(width 0.1)
				(type default)
			)
			(layer "F.SilkS")
		)
		(fp_line
			(start 5.738876 -3.772916)
			(end 5.72643 -3.703828)
			(stroke
				(width 0.1)
				(type default)
			)
			(layer "F.SilkS")
		)
		(fp_line
			(start 5.738876 -3.772916)
			(end 5.72643 -3.703828)
			(stroke
				(width 0.1)
				(type default)
			)
			(layer "F.SilkS")
		)
		(fp_line
			(start 5.750306 -1.244854)
			(end 6.710934 -2.166366)
			(stroke
				(width 0.1)
				(type default)
			)
			(layer "F.SilkS")
		)
		(fp_line
			(start 5.750306 -1.244854)
			(end 6.710934 -2.166366)
			(stroke
				(width 0.1)
				(type default)
			)
			(layer "F.SilkS")
		)
		(fp_line
			(start 5.751068 -3.842512)
			(end 5.738876 -3.772916)
			(stroke
				(width 0.1)
				(type default)
			)
			(layer "F.SilkS")
		)
		(fp_line
			(start 5.751068 -3.842512)
			(end 5.738876 -3.772916)
			(stroke
				(width 0.1)
				(type default)
			)
			(layer "F.SilkS")
		)
		(fp_line
			(start 5.763006 -3.911854)
			(end 5.751068 -3.842512)
			(stroke
				(width 0.1)
				(type default)
			)
			(layer "F.SilkS")
		)
		(fp_line
			(start 5.763006 -3.911854)
			(end 5.751068 -3.842512)
			(stroke
				(width 0.1)
				(type default)
			)
			(layer "F.SilkS")
		)
		(fp_line
			(start 5.775198 -3.98145)
			(end 5.763006 -3.911854)
			(stroke
				(width 0.1)
				(type default)
			)
			(layer "F.SilkS")
		)
		(fp_line
			(start 5.775198 -3.98145)
			(end 5.763006 -3.911854)
			(stroke
				(width 0.1)
				(type default)
			)
			(layer "F.SilkS")
		)
		(fp_line
			(start 5.776468 -1.212342)
			(end 6.728714 -2.125726)
			(stroke
				(width 0.1)
				(type default)
			)
			(layer "F.SilkS")
		)
		(fp_line
			(start 5.776468 -1.212342)
			(end 6.728714 -2.125726)
			(stroke
				(width 0.1)
				(type default)
			)
			(layer "F.SilkS")
		)
		(fp_line
			(start 5.78739 -4.050538)
			(end 5.775198 -3.98145)
			(stroke
				(width 0.1)
				(type default)
			)
			(layer "F.SilkS")
		)
		(fp_line
			(start 5.78739 -4.050538)
			(end 5.775198 -3.98145)
			(stroke
				(width 0.1)
				(type default)
			)
			(layer "F.SilkS")
		)
		(fp_line
			(start 5.799582 -4.11988)
			(end 5.78739 -4.050538)
			(stroke
				(width 0.1)
				(type default)
			)
			(layer "F.SilkS")
		)
		(fp_line
			(start 5.799582 -4.11988)
			(end 5.78739 -4.050538)
			(stroke
				(width 0.1)
				(type default)
			)
			(layer "F.SilkS")
		)
		(fp_line
			(start 5.80263 -1.179576)
			(end 6.746494 -2.084832)
			(stroke
				(width 0.1)
				(type default)
			)
			(layer "F.SilkS")
		)
		(fp_line
			(start 5.80263 -1.179576)
			(end 6.746494 -2.084832)
			(stroke
				(width 0.1)
				(type default)
			)
			(layer "F.SilkS")
		)
		(fp_line
			(start 5.811774 -4.189476)
			(end 5.799582 -4.11988)
			(stroke
				(width 0.1)
				(type default)
			)
			(layer "F.SilkS")
		)
		(fp_line
			(start 5.811774 -4.189476)
			(end 5.799582 -4.11988)
			(stroke
				(width 0.1)
				(type default)
			)
			(layer "F.SilkS")
		)
		(fp_line
			(start 5.823966 -4.258818)
			(end 5.811774 -4.189476)
			(stroke
				(width 0.1)
				(type default)
			)
			(layer "F.SilkS")
		)
		(fp_line
			(start 5.823966 -4.258818)
			(end 5.811774 -4.189476)
			(stroke
				(width 0.1)
				(type default)
			)
			(layer "F.SilkS")
		)
		(fp_line
			(start 5.828792 -1.147064)
			(end 6.769608 -2.049272)
			(stroke
				(width 0.1)
				(type default)
			)
			(layer "F.SilkS")
		)
		(fp_line
			(start 5.828792 -1.147064)
			(end 6.769608 -2.049272)
			(stroke
				(width 0.1)
				(type default)
			)
			(layer "F.SilkS")
		)
		(fp_line
			(start 5.836158 -4.328414)
			(end 5.823966 -4.258818)
			(stroke
				(width 0.1)
				(type default)
			)
			(layer "F.SilkS")
		)
		(fp_line
			(start 5.836158 -4.328414)
			(end 5.823966 -4.258818)
			(stroke
				(width 0.1)
				(type default)
			)
			(layer "F.SilkS")
		)
		(fp_line
			(start 5.84835 -4.397502)
			(end 5.836158 -4.328414)
			(stroke
				(width 0.1)
				(type default)
			)
			(layer "F.SilkS")
		)
		(fp_line
			(start 5.84835 -4.397502)
			(end 5.836158 -4.328414)
			(stroke
				(width 0.1)
				(type default)
			)
			(layer "F.SilkS")
		)
		(fp_line
			(start 5.854954 -1.114298)
			(end 6.79704 -2.018284)
			(stroke
				(width 0.1)
				(type default)
			)
			(layer "F.SilkS")
		)
		(fp_line
			(start 5.854954 -1.114298)
			(end 6.79704 -2.018284)
			(stroke
				(width 0.1)
				(type default)
			)
			(layer "F.SilkS")
		)
		(fp_line
			(start 5.860542 -4.467098)
			(end 5.84835 -4.397502)
			(stroke
				(width 0.1)
				(type default)
			)
			(layer "F.SilkS")
		)
		(fp_line
			(start 5.860542 -4.467098)
			(end 5.84835 -4.397502)
			(stroke
				(width 0.1)
				(type default)
			)
			(layer "F.SilkS")
		)
		(fp_line
			(start 5.872734 -4.53644)
			(end 5.860542 -4.467098)
			(stroke
				(width 0.1)
				(type default)
			)
			(layer "F.SilkS")
		)
		(fp_line
			(start 5.872734 -4.53644)
			(end 5.860542 -4.467098)
			(stroke
				(width 0.1)
				(type default)
			)
			(layer "F.SilkS")
		)
		(fp_line
			(start 5.872734 -4.53644)
			(end 5.884926 -4.605782)
			(stroke
				(width 0.1)
				(type default)
			)
			(layer "F.SilkS")
		)
		(fp_line
			(start 5.872734 -4.53644)
			(end 5.884926 -4.605782)
			(stroke
				(width 0.1)
				(type default)
			)
			(layer "F.SilkS")
		)
		(fp_line
			(start 5.884926 -4.605782)
			(end 5.897118 -4.675124)
			(stroke
				(width 0.1)
				(type default)
			)
			(layer "F.SilkS")
		)
		(fp_line
			(start 5.884926 -4.605782)
			(end 5.897118 -4.675124)
			(stroke
				(width 0.1)
				(type default)
			)
			(layer "F.SilkS")
		)
		(fp_line
			(start 5.884926 -1.085342)
			(end 6.824726 -1.987042)
			(stroke
				(width 0.1)
				(type default)
			)
			(layer "F.SilkS")
		)
		(fp_line
			(start 5.884926 -1.085342)
			(end 6.824726 -1.987042)
			(stroke
				(width 0.1)
				(type default)
			)
			(layer "F.SilkS")
		)
		(fp_line
			(start 5.897118 -4.675124)
			(end 5.90931 -4.74472)
			(stroke
				(width 0.1)
				(type default)
			)
			(layer "F.SilkS")
		)
		(fp_line
			(start 5.897118 -4.675124)
			(end 5.90931 -4.74472)
			(stroke
				(width 0.1)
				(type default)
			)
			(layer "F.SilkS")
		)
		(fp_line
			(start 5.90931 -4.74472)
			(end 5.921502 -4.814062)
			(stroke
				(width 0.1)
				(type default)
			)
			(layer "F.SilkS")
		)
		(fp_line
			(start 5.90931 -4.74472)
			(end 5.921502 -4.814062)
			(stroke
				(width 0.1)
				(type default)
			)
			(layer "F.SilkS")
		)
		(fp_line
			(start 5.919978 -1.061212)
			(end 6.856222 -1.95961)
			(stroke
				(width 0.1)
				(type default)
			)
			(layer "F.SilkS")
		)
		(fp_line
			(start 5.919978 -1.061212)
			(end 6.856222 -1.95961)
			(stroke
				(width 0.1)
				(type default)
			)
			(layer "F.SilkS")
		)
		(fp_line
			(start 5.921502 -4.814062)
			(end 5.933694 -4.883404)
			(stroke
				(width 0.1)
				(type default)
			)
			(layer "F.SilkS")
		)
		(fp_line
			(start 5.921502 -4.814062)
			(end 5.933694 -4.883404)
			(stroke
				(width 0.1)
				(type default)
			)
			(layer "F.SilkS")
		)
		(fp_line
			(start 5.933694 -4.883404)
			(end 5.945886 -4.952746)
			(stroke
				(width 0.1)
				(type default)
			)
			(layer "F.SilkS")
		)
		(fp_line
			(start 5.933694 -4.883404)
			(end 5.945886 -4.952746)
			(stroke
				(width 0.1)
				(type default)
			)
			(layer "F.SilkS")
		)
		(fp_line
			(start 5.945886 -4.952746)
			(end 5.958078 -5.022088)
			(stroke
				(width 0.1)
				(type default)
			)
			(layer "F.SilkS")
		)
		(fp_line
			(start 5.945886 -4.952746)
			(end 5.958078 -5.022088)
			(stroke
				(width 0.1)
				(type default)
			)
			(layer "F.SilkS")
		)
		(fp_line
			(start 5.955284 -1.03759)
			(end 6.894068 -1.93802)
			(stroke
				(width 0.1)
				(type default)
			)
			(layer "F.SilkS")
		)
		(fp_line
			(start 5.955284 -1.03759)
			(end 6.894068 -1.93802)
			(stroke
				(width 0.1)
				(type default)
			)
			(layer "F.SilkS")
		)
		(fp_line
			(start 5.958078 -5.022088)
			(end 5.97027 -5.091684)
			(stroke
				(width 0.1)
				(type default)
			)
			(layer "F.SilkS")
		)
		(fp_line
			(start 5.958078 -5.022088)
			(end 5.97027 -5.091684)
			(stroke
				(width 0.1)
				(type default)
			)
			(layer "F.SilkS")
		)
		(fp_line
			(start 5.97027 -5.091684)
			(end 5.982208 -5.161026)
			(stroke
				(width 0.1)
				(type default)
			)
			(layer "F.SilkS")
		)
		(fp_line
			(start 5.97027 -5.091684)
			(end 5.982208 -5.161026)
			(stroke
				(width 0.1)
				(type default)
			)
			(layer "F.SilkS")
		)
		(fp_line
			(start 5.98424 -5.171694)
			(end 5.982208 -5.161026)
			(stroke
				(width 0.1)
				(type default)
			)
			(layer "F.SilkS")
		)
		(fp_line
			(start 5.98424 -5.171694)
			(end 5.982208 -5.161026)
			(stroke
				(width 0.1)
				(type default)
			)
			(layer "F.SilkS")
		)
		(fp_line
			(start 5.99059 -1.013714)
			(end 6.93166 -1.91643)
			(stroke
				(width 0.1)
				(type default)
			)
			(layer "F.SilkS")
		)
		(fp_line
			(start 5.99059 -1.013714)
			(end 6.93166 -1.91643)
			(stroke
				(width 0.1)
				(type default)
			)
			(layer "F.SilkS")
		)
		(fp_line
			(start 5.993638 -5.171694)
			(end 5.982208 -5.161026)
			(stroke
				(width 0.1)
				(type default)
			)
			(layer "F.SilkS")
		)
		(fp_line
			(start 5.993638 -5.171694)
			(end 5.982208 -5.161026)
			(stroke
				(width 0.1)
				(type default)
			)
			(layer "F.SilkS")
		)
		(fp_line
			(start 5.993638 -5.171694)
			(end 5.98424 -5.171694)
			(stroke
				(width 0.1)
				(type default)
			)
			(layer "F.SilkS")
		)
		(fp_line
			(start 5.993638 -5.171694)
			(end 5.98424 -5.171694)
			(stroke
				(width 0.1)
				(type default)
			)
			(layer "F.SilkS")
		)
		(fp_line
			(start 6.025642 -0.989584)
			(end 6.973062 -1.898396)
			(stroke
				(width 0.1)
				(type default)
			)
			(layer "F.SilkS")
		)
		(fp_line
			(start 6.025642 -0.989584)
			(end 6.973062 -1.898396)
			(stroke
				(width 0.1)
				(type default)
			)
			(layer "F.SilkS")
		)
		(fp_line
			(start 6.053582 -5.171694)
			(end 5.97027 -5.091684)
			(stroke
				(width 0.1)
				(type default)
			)
			(layer "F.SilkS")
		)
		(fp_line
			(start 6.053582 -5.171694)
			(end 5.97027 -5.091684)
			(stroke
				(width 0.1)
				(type default)
			)
			(layer "F.SilkS")
		)
		(fp_line
			(start 6.053582 -5.171694)
			(end 5.993638 -5.171694)
			(stroke
				(width 0.1)
				(type default)
			)
			(layer "F.SilkS")
		)
		(fp_line
			(start 6.053582 -5.171694)
			(end 5.993638 -5.171694)
			(stroke
				(width 0.1)
				(type default)
			)
			(layer "F.SilkS")
		)
		(fp_line
			(start 6.060948 -0.965962)
			(end 7.020306 -1.88595)
			(stroke
				(width 0.1)
				(type default)
			)
			(layer "F.SilkS")
		)
		(fp_line
			(start 6.060948 -0.965962)
			(end 7.020306 -1.88595)
			(stroke
				(width 0.1)
				(type default)
			)
			(layer "F.SilkS")
		)
		(fp_line
			(start 6.096254 -0.942086)
			(end 7.06755 -1.873504)
			(stroke
				(width 0.1)
				(type default)
			)
			(layer "F.SilkS")
		)
		(fp_line
			(start 6.096254 -0.942086)
			(end 7.06755 -1.873504)
			(stroke
				(width 0.1)
				(type default)
			)
			(layer "F.SilkS")
		)
		(fp_line
			(start 6.11378 -5.171694)
			(end 5.958078 -5.022088)
			(stroke
				(width 0.1)
				(type default)
			)
			(layer "F.SilkS")
		)
		(fp_line
			(start 6.11378 -5.171694)
			(end 5.958078 -5.022088)
			(stroke
				(width 0.1)
				(type default)
			)
			(layer "F.SilkS")
		)
		(fp_line
			(start 6.11378 -5.171694)
			(end 6.053582 -5.171694)
			(stroke
				(width 0.1)
				(type default)
			)
			(layer "F.SilkS")
		)
		(fp_line
			(start 6.11378 -5.171694)
			(end 6.053582 -5.171694)
			(stroke
				(width 0.1)
				(type default)
			)
			(layer "F.SilkS")
		)
		(fp_line
			(start 6.136132 -0.922528)
			(end 7.118604 -1.865122)
			(stroke
				(width 0.1)
				(type default)
			)
			(layer "F.SilkS")
		)
		(fp_line
			(start 6.136132 -0.922528)
			(end 7.118604 -1.865122)
			(stroke
				(width 0.1)
				(type default)
			)
			(layer "F.SilkS")
		)
		(fp_line
			(start 6.173978 -5.171694)
			(end 5.945886 -4.952746)
			(stroke
				(width 0.1)
				(type default)
			)
			(layer "F.SilkS")
		)
		(fp_line
			(start 6.173978 -5.171694)
			(end 5.945886 -4.952746)
			(stroke
				(width 0.1)
				(type default)
			)
			(layer "F.SilkS")
		)
		(fp_line
			(start 6.173978 -5.171694)
			(end 6.11378 -5.171694)
			(stroke
				(width 0.1)
				(type default)
			)
			(layer "F.SilkS")
		)
		(fp_line
			(start 6.173978 -5.171694)
			(end 6.11378 -5.171694)
			(stroke
				(width 0.1)
				(type default)
			)
			(layer "F.SilkS")
		)
		(fp_line
			(start 6.180836 -0.907796)
			(end 7.174738 -1.861058)
			(stroke
				(width 0.1)
				(type default)
			)
			(layer "F.SilkS")
		)
		(fp_line
			(start 6.180836 -0.907796)
			(end 7.174738 -1.861058)
			(stroke
				(width 0.1)
				(type default)
			)
			(layer "F.SilkS")
		)
		(fp_line
			(start 6.225794 -0.89281)
			(end 7.231126 -1.857248)
			(stroke
				(width 0.1)
				(type default)
			)
			(layer "F.SilkS")
		)
		(fp_line
			(start 6.225794 -0.89281)
			(end 7.231126 -1.857248)
			(stroke
				(width 0.1)
				(type default)
			)
			(layer "F.SilkS")
		)
		(fp_line
			(start 6.234176 -5.171694)
			(end 5.933694 -4.883404)
			(stroke
				(width 0.1)
				(type default)
			)
			(layer "F.SilkS")
		)
		(fp_line
			(start 6.234176 -5.171694)
			(end 5.933694 -4.883404)
			(stroke
				(width 0.1)
				(type default)
			)
			(layer "F.SilkS")
		)
		(fp_line
			(start 6.234176 -5.171694)
			(end 6.173978 -5.171694)
			(stroke
				(width 0.1)
				(type default)
			)
			(layer "F.SilkS")
		)
		(fp_line
			(start 6.234176 -5.171694)
			(end 6.173978 -5.171694)
			(stroke
				(width 0.1)
				(type default)
			)
			(layer "F.SilkS")
		)
		(fp_line
			(start 6.270752 -0.878332)
			(end 7.291832 -1.857756)
			(stroke
				(width 0.1)
				(type default)
			)
			(layer "F.SilkS")
		)
		(fp_line
			(start 6.270752 -0.878332)
			(end 7.291832 -1.857756)
			(stroke
				(width 0.1)
				(type default)
			)
			(layer "F.SilkS")
		)
		(fp_line
			(start 6.294374 -5.171694)
			(end 5.921502 -4.814062)
			(stroke
				(width 0.1)
				(type default)
			)
			(layer "F.SilkS")
		)
		(fp_line
			(start 6.294374 -5.171694)
			(end 5.921502 -4.814062)
			(stroke
				(width 0.1)
				(type default)
			)
			(layer "F.SilkS")
		)
		(fp_line
			(start 6.294374 -5.171694)
			(end 6.234176 -5.171694)
			(stroke
				(width 0.1)
				(type default)
			)
			(layer "F.SilkS")
		)
		(fp_line
			(start 6.294374 -5.171694)
			(end 6.234176 -5.171694)
			(stroke
				(width 0.1)
				(type default)
			)
			(layer "F.SilkS")
		)
		(fp_line
			(start 6.315456 -0.8636)
			(end 7.356348 -1.862074)
			(stroke
				(width 0.1)
				(type default)
			)
			(layer "F.SilkS")
		)
		(fp_line
			(start 6.315456 -0.8636)
			(end 7.356348 -1.862074)
			(stroke
				(width 0.1)
				(type default)
			)
			(layer "F.SilkS")
		)
		(fp_line
			(start 6.354318 -5.171694)
			(end 5.90931 -4.74472)
			(stroke
				(width 0.1)
				(type default)
			)
			(layer "F.SilkS")
		)
		(fp_line
			(start 6.354318 -5.171694)
			(end 5.90931 -4.74472)
			(stroke
				(width 0.1)
				(type default)
			)
			(layer "F.SilkS")
		)
		(fp_line
			(start 6.354318 -5.171694)
			(end 6.294374 -5.171694)
			(stroke
				(width 0.1)
				(type default)
			)
			(layer "F.SilkS")
		)
		(fp_line
			(start 6.354318 -5.171694)
			(end 6.294374 -5.171694)
			(stroke
				(width 0.1)
				(type default)
			)
			(layer "F.SilkS")
		)
		(fp_line
			(start 6.36016 -0.848868)
			(end 7.421118 -1.866392)
			(stroke
				(width 0.1)
				(type default)
			)
			(layer "F.SilkS")
		)
		(fp_line
			(start 6.36016 -0.848868)
			(end 7.421118 -1.866392)
			(stroke
				(width 0.1)
				(type default)
			)
			(layer "F.SilkS")
		)
		(fp_line
			(start 6.405118 -0.833882)
			(end 7.500366 -1.884934)
			(stroke
				(width 0.1)
				(type default)
			)
			(layer "F.SilkS")
		)
		(fp_line
			(start 6.405118 -0.833882)
			(end 7.500366 -1.884934)
			(stroke
				(width 0.1)
				(type default)
			)
			(layer "F.SilkS")
		)
		(fp_line
			(start 6.41477 -5.171694)
			(end 5.897118 -4.675124)
			(stroke
				(width 0.1)
				(type default)
			)
			(layer "F.SilkS")
		)
		(fp_line
			(start 6.41477 -5.171694)
			(end 5.897118 -4.675124)
			(stroke
				(width 0.1)
				(type default)
			)
			(layer "F.SilkS")
		)
		(fp_line
			(start 6.41477 -5.171694)
			(end 6.354318 -5.171694)
			(stroke
				(width 0.1)
				(type default)
			)
			(layer "F.SilkS")
		)
		(fp_line
			(start 6.41477 -5.171694)
			(end 6.354318 -5.171694)
			(stroke
				(width 0.1)
				(type default)
			)
			(layer "F.SilkS")
		)
		(fp_line
			(start 6.455664 -0.824738)
			(end 7.582662 -1.906016)
			(stroke
				(width 0.1)
				(type default)
			)
			(layer "F.SilkS")
		)
		(fp_line
			(start 6.455664 -0.824738)
			(end 7.582662 -1.906016)
			(stroke
				(width 0.1)
				(type default)
			)
			(layer "F.SilkS")
		)
		(fp_line
			(start 6.474714 -5.171694)
			(end 5.884926 -4.605782)
			(stroke
				(width 0.1)
				(type default)
			)
			(layer "F.SilkS")
		)
		(fp_line
			(start 6.474714 -5.171694)
			(end 5.884926 -4.605782)
			(stroke
				(width 0.1)
				(type default)
			)
			(layer "F.SilkS")
		)
		(fp_line
			(start 6.474714 -5.171694)
			(end 6.41477 -5.171694)
			(stroke
				(width 0.1)
				(type default)
			)
			(layer "F.SilkS")
		)
		(fp_line
			(start 6.474714 -5.171694)
			(end 6.41477 -5.171694)
			(stroke
				(width 0.1)
				(type default)
			)
			(layer "F.SilkS")
		)
		(fp_line
			(start 6.510528 -0.819912)
			(end 7.699756 -1.96088)
			(stroke
				(width 0.1)
				(type default)
			)
			(layer "F.SilkS")
		)
		(fp_line
			(start 6.510528 -0.819912)
			(end 7.699756 -1.96088)
			(stroke
				(width 0.1)
				(type default)
			)
			(layer "F.SilkS")
		)
		(fp_line
			(start 6.534912 -5.171694)
			(end 5.872734 -4.53644)
			(stroke
				(width 0.1)
				(type default)
			)
			(layer "F.SilkS")
		)
		(fp_line
			(start 6.534912 -5.171694)
			(end 5.872734 -4.53644)
			(stroke
				(width 0.1)
				(type default)
			)
			(layer "F.SilkS")
		)
		(fp_line
			(start 6.534912 -5.171694)
			(end 6.474714 -5.171694)
			(stroke
				(width 0.1)
				(type default)
			)
			(layer "F.SilkS")
		)
		(fp_line
			(start 6.534912 -5.171694)
			(end 6.474714 -5.171694)
			(stroke
				(width 0.1)
				(type default)
			)
			(layer "F.SilkS")
		)
		(fp_line
			(start 6.59511 -5.171694)
			(end 5.860542 -4.467098)
			(stroke
				(width 0.1)
				(type default)
			)
			(layer "F.SilkS")
		)
		(fp_line
			(start 6.59511 -5.171694)
			(end 5.860542 -4.467098)
			(stroke
				(width 0.1)
				(type default)
			)
			(layer "F.SilkS")
		)
		(fp_line
			(start 6.59511 -5.171694)
			(end 6.534912 -5.171694)
			(stroke
				(width 0.1)
				(type default)
			)
			(layer "F.SilkS")
		)
		(fp_line
			(start 6.59511 -5.171694)
			(end 6.534912 -5.171694)
			(stroke
				(width 0.1)
				(type default)
			)
			(layer "F.SilkS")
		)
		(fp_line
			(start 6.620256 -0.809498)
			(end 9.404096 -3.480054)
			(stroke
				(width 0.1)
				(type default)
			)
			(layer "F.SilkS")
		)
		(fp_line
			(start 6.620256 -0.809498)
			(end 9.404096 -3.480054)
			(stroke
				(width 0.1)
				(type default)
			)
			(layer "F.SilkS")
		)
		(fp_line
			(start 6.655308 -5.171694)
			(end 5.84835 -4.397502)
			(stroke
				(width 0.1)
				(type default)
			)
			(layer "F.SilkS")
		)
		(fp_line
			(start 6.655308 -5.171694)
			(end 5.84835 -4.397502)
			(stroke
				(width 0.1)
				(type default)
			)
			(layer "F.SilkS")
		)
		(fp_line
			(start 6.655308 -5.171694)
			(end 6.59511 -5.171694)
			(stroke
				(width 0.1)
				(type default)
			)
			(layer "F.SilkS")
		)
		(fp_line
			(start 6.655308 -5.171694)
			(end 6.59511 -5.171694)
			(stroke
				(width 0.1)
				(type default)
			)
			(layer "F.SilkS")
		)
		(fp_line
			(start 6.67512 -0.804672)
			(end 9.391904 -3.410712)
			(stroke
				(width 0.1)
				(type default)
			)
			(layer "F.SilkS")
		)
		(fp_line
			(start 6.67512 -0.804672)
			(end 9.391904 -3.410712)
			(stroke
				(width 0.1)
				(type default)
			)
			(layer "F.SilkS")
		)
		(fp_line
			(start 6.703822 -2.852166)
			(end 6.716014 -2.921254)
			(stroke
				(width 0.1)
				(type default)
			)
			(layer "F.SilkS")
		)
		(fp_line
			(start 6.703822 -2.852166)
			(end 6.716014 -2.921254)
			(stroke
				(width 0.1)
				(type default)
			)
			(layer "F.SilkS")
		)
		(fp_line
			(start 6.715506 -5.171694)
			(end 5.836158 -4.328414)
			(stroke
				(width 0.1)
				(type default)
			)
			(layer "F.SilkS")
		)
		(fp_line
			(start 6.715506 -5.171694)
			(end 5.836158 -4.328414)
			(stroke
				(width 0.1)
				(type default)
			)
			(layer "F.SilkS")
		)
		(fp_line
			(start 6.715506 -5.171694)
			(end 6.655308 -5.171694)
			(stroke
				(width 0.1)
				(type default)
			)
			(layer "F.SilkS")
		)
		(fp_line
			(start 6.715506 -5.171694)
			(end 6.655308 -5.171694)
			(stroke
				(width 0.1)
				(type default)
			)
			(layer "F.SilkS")
		)
		(fp_line
			(start 6.716014 -2.921254)
			(end 6.728206 -2.99085)
			(stroke
				(width 0.1)
				(type default)
			)
			(layer "F.SilkS")
		)
		(fp_line
			(start 6.716014 -2.921254)
			(end 6.728206 -2.99085)
			(stroke
				(width 0.1)
				(type default)
			)
			(layer "F.SilkS")
		)
		(fp_line
			(start 6.728206 -2.99085)
			(end 6.740144 -3.060192)
			(stroke
				(width 0.1)
				(type default)
			)
			(layer "F.SilkS")
		)
		(fp_line
			(start 6.728206 -2.99085)
			(end 6.740144 -3.060192)
			(stroke
				(width 0.1)
				(type default)
			)
			(layer "F.SilkS")
		)
		(fp_line
			(start 6.729984 -0.799592)
			(end 9.379712 -3.34137)
			(stroke
				(width 0.1)
				(type default)
			)
			(layer "F.SilkS")
		)
		(fp_line
			(start 6.729984 -0.799592)
			(end 9.379712 -3.34137)
			(stroke
				(width 0.1)
				(type default)
			)
			(layer "F.SilkS")
		)
		(fp_line
			(start 6.740144 -3.060192)
			(end 6.75259 -3.129534)
			(stroke
				(width 0.1)
				(type default)
			)
			(layer "F.SilkS")
		)
		(fp_line
			(start 6.740144 -3.060192)
			(end 6.75259 -3.129534)
			(stroke
				(width 0.1)
				(type default)
			)
			(layer "F.SilkS")
		)
		(fp_line
			(start 6.75259 -3.129534)
			(end 6.764782 -3.19913)
			(stroke
				(width 0.1)
				(type default)
			)
			(layer "F.SilkS")
		)
		(fp_line
			(start 6.75259 -3.129534)
			(end 6.764782 -3.19913)
			(stroke
				(width 0.1)
				(type default)
			)
			(layer "F.SilkS")
		)
		(fp_line
			(start 6.764782 -3.19913)
			(end 6.776974 -3.268472)
			(stroke
				(width 0.1)
				(type default)
			)
			(layer "F.SilkS")
		)
		(fp_line
			(start 6.764782 -3.19913)
			(end 6.776974 -3.268472)
			(stroke
				(width 0.1)
				(type default)
			)
			(layer "F.SilkS")
		)
		(fp_line
			(start 6.77545 -5.171694)
			(end 5.823966 -4.258818)
			(stroke
				(width 0.1)
				(type default)
			)
			(layer "F.SilkS")
		)
		(fp_line
			(start 6.77545 -5.171694)
			(end 5.823966 -4.258818)
			(stroke
				(width 0.1)
				(type default)
			)
			(layer "F.SilkS")
		)
		(fp_line
			(start 6.77545 -5.171694)
			(end 6.715506 -5.171694)
			(stroke
				(width 0.1)
				(type default)
			)
			(layer "F.SilkS")
		)
		(fp_line
			(start 6.77545 -5.171694)
			(end 6.715506 -5.171694)
			(stroke
				(width 0.1)
				(type default)
			)
			(layer "F.SilkS")
		)
		(fp_line
			(start 6.776974 -3.268472)
			(end 6.788912 -3.337814)
			(stroke
				(width 0.1)
				(type default)
			)
			(layer "F.SilkS")
		)
		(fp_line
			(start 6.776974 -3.268472)
			(end 6.788912 -3.337814)
			(stroke
				(width 0.1)
				(type default)
			)
			(layer "F.SilkS")
		)
		(fp_line
			(start 6.784848 -0.794258)
			(end 9.36752 -3.272028)
			(stroke
				(width 0.1)
				(type default)
			)
			(layer "F.SilkS")
		)
		(fp_line
			(start 6.784848 -0.794258)
			(end 9.36752 -3.272028)
			(stroke
				(width 0.1)
				(type default)
			)
			(layer "F.SilkS")
		)
		(fp_line
			(start 6.788912 -3.337814)
			(end 6.801104 -3.407156)
			(stroke
				(width 0.1)
				(type default)
			)
			(layer "F.SilkS")
		)
		(fp_line
			(start 6.788912 -3.337814)
			(end 6.801104 -3.407156)
			(stroke
				(width 0.1)
				(type default)
			)
			(layer "F.SilkS")
		)
		(fp_line
			(start 6.801104 -3.407156)
			(end 6.81355 -3.476498)
			(stroke
				(width 0.1)
				(type default)
			)
			(layer "F.SilkS")
		)
		(fp_line
			(start 6.801104 -3.407156)
			(end 6.81355 -3.476498)
			(stroke
				(width 0.1)
				(type default)
			)
			(layer "F.SilkS")
		)
		(fp_line
			(start 6.825488 -3.54584)
			(end 6.81355 -3.476498)
			(stroke
				(width 0.1)
				(type default)
			)
			(layer "F.SilkS")
		)
		(fp_line
			(start 6.825488 -3.54584)
			(end 6.81355 -3.476498)
			(stroke
				(width 0.1)
				(type default)
			)
			(layer "F.SilkS")
		)
		(fp_line
			(start 6.825488 -3.54584)
			(end 6.83768 -3.615436)
			(stroke
				(width 0.1)
				(type default)
			)
			(layer "F.SilkS")
		)
		(fp_line
			(start 6.825488 -3.54584)
			(end 6.83768 -3.615436)
			(stroke
				(width 0.1)
				(type default)
			)
			(layer "F.SilkS")
		)
		(fp_line
			(start 6.835648 -5.171694)
			(end 5.811774 -4.189476)
			(stroke
				(width 0.1)
				(type default)
			)
			(layer "F.SilkS")
		)
		(fp_line
			(start 6.835648 -5.171694)
			(end 5.811774 -4.189476)
			(stroke
				(width 0.1)
				(type default)
			)
			(layer "F.SilkS")
		)
		(fp_line
			(start 6.835648 -5.171694)
			(end 6.77545 -5.171694)
			(stroke
				(width 0.1)
				(type default)
			)
			(layer "F.SilkS")
		)
		(fp_line
			(start 6.835648 -5.171694)
			(end 6.77545 -5.171694)
			(stroke
				(width 0.1)
				(type default)
			)
			(layer "F.SilkS")
		)
		(fp_line
			(start 6.83768 -3.615436)
			(end 5.509514 -2.341372)
			(stroke
				(width 0.1)
				(type default)
			)
			(layer "F.SilkS")
		)
		(fp_line
			(start 6.83768 -3.615436)
			(end 5.509514 -2.341372)
			(stroke
				(width 0.1)
				(type default)
			)
			(layer "F.SilkS")
		)
		(fp_line
			(start 6.83768 -3.615436)
			(end 6.849872 -3.684778)
			(stroke
				(width 0.1)
				(type default)
			)
			(layer "F.SilkS")
		)
		(fp_line
			(start 6.83768 -3.615436)
			(end 6.849872 -3.684778)
			(stroke
				(width 0.1)
				(type default)
			)
			(layer "F.SilkS")
		)
		(fp_line
			(start 6.848348 -0.797814)
			(end 9.355328 -3.202432)
			(stroke
				(width 0.1)
				(type default)
			)
			(layer "F.SilkS")
		)
		(fp_line
			(start 6.848348 -0.797814)
			(end 9.355328 -3.202432)
			(stroke
				(width 0.1)
				(type default)
			)
			(layer "F.SilkS")
		)
		(fp_line
			(start 6.849872 -3.684778)
			(end 5.517642 -2.40665)
			(stroke
				(width 0.1)
				(type default)
			)
			(layer "F.SilkS")
		)
		(fp_line
			(start 6.849872 -3.684778)
			(end 5.517642 -2.40665)
			(stroke
				(width 0.1)
				(type default)
			)
			(layer "F.SilkS")
		)
		(fp_line
			(start 6.849872 -3.684778)
			(end 6.862318 -3.75412)
			(stroke
				(width 0.1)
				(type default)
			)
			(layer "F.SilkS")
		)
		(fp_line
			(start 6.849872 -3.684778)
			(end 6.862318 -3.75412)
			(stroke
				(width 0.1)
				(type default)
			)
			(layer "F.SilkS")
		)
		(fp_line
			(start 6.862318 -3.75412)
			(end 5.525516 -2.471928)
			(stroke
				(width 0.1)
				(type default)
			)
			(layer "F.SilkS")
		)
		(fp_line
			(start 6.862318 -3.75412)
			(end 5.525516 -2.471928)
			(stroke
				(width 0.1)
				(type default)
			)
			(layer "F.SilkS")
		)
		(fp_line
			(start 6.862318 -3.75412)
			(end 6.874256 -3.823716)
			(stroke
				(width 0.1)
				(type default)
			)
			(layer "F.SilkS")
		)
		(fp_line
			(start 6.862318 -3.75412)
			(end 6.874256 -3.823716)
			(stroke
				(width 0.1)
				(type default)
			)
			(layer "F.SilkS")
		)
		(fp_line
			(start 6.874256 -3.823716)
			(end 5.53339 -2.537206)
			(stroke
				(width 0.1)
				(type default)
			)
			(layer "F.SilkS")
		)
		(fp_line
			(start 6.874256 -3.823716)
			(end 5.53339 -2.537206)
			(stroke
				(width 0.1)
				(type default)
			)
			(layer "F.SilkS")
		)
		(fp_line
			(start 6.874256 -3.823716)
			(end 6.886448 -3.893058)
			(stroke
				(width 0.1)
				(type default)
			)
			(layer "F.SilkS")
		)
		(fp_line
			(start 6.874256 -3.823716)
			(end 6.886448 -3.893058)
			(stroke
				(width 0.1)
				(type default)
			)
			(layer "F.SilkS")
		)
		(fp_line
			(start 6.886448 -3.893058)
			(end 5.541264 -2.602738)
			(stroke
				(width 0.1)
				(type default)
			)
			(layer "F.SilkS")
		)
		(fp_line
			(start 6.886448 -3.893058)
			(end 5.541264 -2.602738)
			(stroke
				(width 0.1)
				(type default)
			)
			(layer "F.SilkS")
		)
		(fp_line
			(start 6.886448 -3.893058)
			(end 6.89864 -3.9624)
			(stroke
				(width 0.1)
				(type default)
			)
			(layer "F.SilkS")
		)
		(fp_line
			(start 6.886448 -3.893058)
			(end 6.89864 -3.9624)
			(stroke
				(width 0.1)
				(type default)
			)
			(layer "F.SilkS")
		)
		(fp_line
			(start 6.895846 -5.171694)
			(end 5.799582 -4.11988)
			(stroke
				(width 0.1)
				(type default)
			)
			(layer "F.SilkS")
		)
		(fp_line
			(start 6.895846 -5.171694)
			(end 5.799582 -4.11988)
			(stroke
				(width 0.1)
				(type default)
			)
			(layer "F.SilkS")
		)
		(fp_line
			(start 6.895846 -5.171694)
			(end 6.835648 -5.171694)
			(stroke
				(width 0.1)
				(type default)
			)
			(layer "F.SilkS")
		)
		(fp_line
			(start 6.895846 -5.171694)
			(end 6.835648 -5.171694)
			(stroke
				(width 0.1)
				(type default)
			)
			(layer "F.SilkS")
		)
		(fp_line
			(start 6.89864 -3.9624)
			(end 5.549392 -2.668016)
			(stroke
				(width 0.1)
				(type default)
			)
			(layer "F.SilkS")
		)
		(fp_line
			(start 6.89864 -3.9624)
			(end 5.549392 -2.668016)
			(stroke
				(width 0.1)
				(type default)
			)
			(layer "F.SilkS")
		)
		(fp_line
			(start 6.89864 -3.9624)
			(end 6.910832 -4.031742)
			(stroke
				(width 0.1)
				(type default)
			)
			(layer "F.SilkS")
		)
		(fp_line
			(start 6.89864 -3.9624)
			(end 6.910832 -4.031742)
			(stroke
				(width 0.1)
				(type default)
			)
			(layer "F.SilkS")
		)
		(fp_line
			(start 6.910832 -4.031742)
			(end 5.557266 -2.733294)
			(stroke
				(width 0.1)
				(type default)
			)
			(layer "F.SilkS")
		)
		(fp_line
			(start 6.910832 -4.031742)
			(end 5.557266 -2.733294)
			(stroke
				(width 0.1)
				(type default)
			)
			(layer "F.SilkS")
		)
		(fp_line
			(start 6.910832 -4.031742)
			(end 6.923024 -4.101084)
			(stroke
				(width 0.1)
				(type default)
			)
			(layer "F.SilkS")
		)
		(fp_line
			(start 6.910832 -4.031742)
			(end 6.923024 -4.101084)
			(stroke
				(width 0.1)
				(type default)
			)
			(layer "F.SilkS")
		)
		(fp_line
			(start 6.914896 -0.80391)
			(end 9.343136 -3.13309)
			(stroke
				(width 0.1)
				(type default)
			)
			(layer "F.SilkS")
		)
		(fp_line
			(start 6.914896 -0.80391)
			(end 9.343136 -3.13309)
			(stroke
				(width 0.1)
				(type default)
			)
			(layer "F.SilkS")
		)
		(fp_line
			(start 6.923024 -4.101084)
			(end 5.568188 -2.801366)
			(stroke
				(width 0.1)
				(type default)
			)
			(layer "F.SilkS")
		)
		(fp_line
			(start 6.923024 -4.101084)
			(end 5.568188 -2.801366)
			(stroke
				(width 0.1)
				(type default)
			)
			(layer "F.SilkS")
		)
		(fp_line
			(start 6.923024 -4.101084)
			(end 6.935216 -4.170426)
			(stroke
				(width 0.1)
				(type default)
			)
			(layer "F.SilkS")
		)
		(fp_line
			(start 6.923024 -4.101084)
			(end 6.935216 -4.170426)
			(stroke
				(width 0.1)
				(type default)
			)
			(layer "F.SilkS")
		)
		(fp_line
			(start 6.935216 -4.170426)
			(end 5.58038 -2.870962)
			(stroke
				(width 0.1)
				(type default)
			)
			(layer "F.SilkS")
		)
		(fp_line
			(start 6.935216 -4.170426)
			(end 5.58038 -2.870962)
			(stroke
				(width 0.1)
				(type default)
			)
			(layer "F.SilkS")
		)
		(fp_line
			(start 6.935216 -4.170426)
			(end 6.947408 -4.240022)
			(stroke
				(width 0.1)
				(type default)
			)
			(layer "F.SilkS")
		)
		(fp_line
			(start 6.935216 -4.170426)
			(end 6.947408 -4.240022)
			(stroke
				(width 0.1)
				(type default)
			)
			(layer "F.SilkS")
		)
		(fp_line
			(start 6.947408 -4.240022)
			(end 5.592572 -2.940304)
			(stroke
				(width 0.1)
				(type default)
			)
			(layer "F.SilkS")
		)
		(fp_line
			(start 6.947408 -4.240022)
			(end 5.592572 -2.940304)
			(stroke
				(width 0.1)
				(type default)
			)
			(layer "F.SilkS")
		)
		(fp_line
			(start 6.947408 -4.240022)
			(end 6.9596 -4.309364)
			(stroke
				(width 0.1)
				(type default)
			)
			(layer "F.SilkS")
		)
		(fp_line
			(start 6.947408 -4.240022)
			(end 6.9596 -4.309364)
			(stroke
				(width 0.1)
				(type default)
			)
			(layer "F.SilkS")
		)
		(fp_line
			(start 6.956044 -5.171694)
			(end 5.78739 -4.050538)
			(stroke
				(width 0.1)
				(type default)
			)
			(layer "F.SilkS")
		)
		(fp_line
			(start 6.956044 -5.171694)
			(end 5.78739 -4.050538)
			(stroke
				(width 0.1)
				(type default)
			)
			(layer "F.SilkS")
		)
		(fp_line
			(start 6.956044 -5.171694)
			(end 6.895846 -5.171694)
			(stroke
				(width 0.1)
				(type default)
			)
			(layer "F.SilkS")
		)
		(fp_line
			(start 6.956044 -5.171694)
			(end 6.895846 -5.171694)
			(stroke
				(width 0.1)
				(type default)
			)
			(layer "F.SilkS")
		)
		(fp_line
			(start 6.9596 -4.309364)
			(end 5.604764 -3.009646)
			(stroke
				(width 0.1)
				(type default)
			)
			(layer "F.SilkS")
		)
		(fp_line
			(start 6.9596 -4.309364)
			(end 5.604764 -3.009646)
			(stroke
				(width 0.1)
				(type default)
			)
			(layer "F.SilkS")
		)
		(fp_line
			(start 6.9596 -4.309364)
			(end 6.971792 -4.378706)
			(stroke
				(width 0.1)
				(type default)
			)
			(layer "F.SilkS")
		)
		(fp_line
			(start 6.9596 -4.309364)
			(end 6.971792 -4.378706)
			(stroke
				(width 0.1)
				(type default)
			)
			(layer "F.SilkS")
		)
		(fp_line
			(start 6.971792 -4.378706)
			(end 5.616956 -3.079242)
			(stroke
				(width 0.1)
				(type default)
			)
			(layer "F.SilkS")
		)
		(fp_line
			(start 6.971792 -4.378706)
			(end 5.616956 -3.079242)
			(stroke
				(width 0.1)
				(type default)
			)
			(layer "F.SilkS")
		)
		(fp_line
			(start 6.971792 -4.378706)
			(end 6.983984 -4.448302)
			(stroke
				(width 0.1)
				(type default)
			)
			(layer "F.SilkS")
		)
		(fp_line
			(start 6.971792 -4.378706)
			(end 6.983984 -4.448302)
			(stroke
				(width 0.1)
				(type default)
			)
			(layer "F.SilkS")
		)
		(fp_line
			(start 6.981444 -0.809752)
			(end 9.330944 -3.063748)
			(stroke
				(width 0.1)
				(type default)
			)
			(layer "F.SilkS")
		)
		(fp_line
			(start 6.981444 -0.809752)
			(end 9.330944 -3.063748)
			(stroke
				(width 0.1)
				(type default)
			)
			(layer "F.SilkS")
		)
		(fp_line
			(start 6.983984 -4.448302)
			(end 5.629148 -3.148584)
			(stroke
				(width 0.1)
				(type default)
			)
			(layer "F.SilkS")
		)
		(fp_line
			(start 6.983984 -4.448302)
			(end 5.629148 -3.148584)
			(stroke
				(width 0.1)
				(type default)
			)
			(layer "F.SilkS")
		)
		(fp_line
			(start 6.983984 -4.448302)
			(end 6.996176 -4.51739)
			(stroke
				(width 0.1)
				(type default)
			)
			(layer "F.SilkS")
		)
		(fp_line
			(start 6.983984 -4.448302)
			(end 6.996176 -4.51739)
			(stroke
				(width 0.1)
				(type default)
			)
			(layer "F.SilkS")
		)
		(fp_line
			(start 6.996176 -4.51739)
			(end 5.64134 -3.217926)
			(stroke
				(width 0.1)
				(type default)
			)
			(layer "F.SilkS")
		)
		(fp_line
			(start 6.996176 -4.51739)
			(end 5.64134 -3.217926)
			(stroke
				(width 0.1)
				(type default)
			)
			(layer "F.SilkS")
		)
		(fp_line
			(start 6.996176 -4.51739)
			(end 7.008368 -4.586986)
			(stroke
				(width 0.1)
				(type default)
			)
			(layer "F.SilkS")
		)
		(fp_line
			(start 6.996176 -4.51739)
			(end 7.008368 -4.586986)
			(stroke
				(width 0.1)
				(type default)
			)
			(layer "F.SilkS")
		)
		(fp_line
			(start 7.008368 -4.586986)
			(end 5.653532 -3.287268)
			(stroke
				(width 0.1)
				(type default)
			)
			(layer "F.SilkS")
		)
		(fp_line
			(start 7.008368 -4.586986)
			(end 5.653532 -3.287268)
			(stroke
				(width 0.1)
				(type default)
			)
			(layer "F.SilkS")
		)
		(fp_line
			(start 7.008368 -4.586986)
			(end 7.02056 -4.656328)
			(stroke
				(width 0.1)
				(type default)
			)
			(layer "F.SilkS")
		)
		(fp_line
			(start 7.008368 -4.586986)
			(end 7.02056 -4.656328)
			(stroke
				(width 0.1)
				(type default)
			)
			(layer "F.SilkS")
		)
		(fp_line
			(start 7.016242 -5.171694)
			(end 5.775198 -3.98145)
			(stroke
				(width 0.1)
				(type default)
			)
			(layer "F.SilkS")
		)
		(fp_line
			(start 7.016242 -5.171694)
			(end 5.775198 -3.98145)
			(stroke
				(width 0.1)
				(type default)
			)
			(layer "F.SilkS")
		)
		(fp_line
			(start 7.016242 -5.171694)
			(end 6.956044 -5.171694)
			(stroke
				(width 0.1)
				(type default)
			)
			(layer "F.SilkS")
		)
		(fp_line
			(start 7.016242 -5.171694)
			(end 6.956044 -5.171694)
			(stroke
				(width 0.1)
				(type default)
			)
			(layer "F.SilkS")
		)
		(fp_line
			(start 7.02056 -4.656328)
			(end 5.665724 -3.35661)
			(stroke
				(width 0.1)
				(type default)
			)
			(layer "F.SilkS")
		)
		(fp_line
			(start 7.02056 -4.656328)
			(end 5.665724 -3.35661)
			(stroke
				(width 0.1)
				(type default)
			)
			(layer "F.SilkS")
		)
		(fp_line
			(start 7.02056 -4.656328)
			(end 7.032752 -4.725924)
			(stroke
				(width 0.1)
				(type default)
			)
			(layer "F.SilkS")
		)
		(fp_line
			(start 7.02056 -4.656328)
			(end 7.032752 -4.725924)
			(stroke
				(width 0.1)
				(type default)
			)
			(layer "F.SilkS")
		)
		(fp_line
			(start 7.032752 -4.725924)
			(end 5.677662 -3.425952)
			(stroke
				(width 0.1)
				(type default)
			)
			(layer "F.SilkS")
		)
		(fp_line
			(start 7.032752 -4.725924)
			(end 5.677662 -3.425952)
			(stroke
				(width 0.1)
				(type default)
			)
			(layer "F.SilkS")
		)
		(fp_line
			(start 7.032752 -4.725924)
			(end 7.04469 -4.795012)
			(stroke
				(width 0.1)
				(type default)
			)
			(layer "F.SilkS")
		)
		(fp_line
			(start 7.032752 -4.725924)
			(end 7.04469 -4.795012)
			(stroke
				(width 0.1)
				(type default)
			)
			(layer "F.SilkS")
		)
		(fp_line
			(start 7.04469 -4.795012)
			(end 5.690108 -3.495548)
			(stroke
				(width 0.1)
				(type default)
			)
			(layer "F.SilkS")
		)
		(fp_line
			(start 7.04469 -4.795012)
			(end 5.690108 -3.495548)
			(stroke
				(width 0.1)
				(type default)
			)
			(layer "F.SilkS")
		)
		(fp_line
			(start 7.04469 -4.795012)
			(end 7.057136 -4.864354)
			(stroke
				(width 0.1)
				(type default)
			)
			(layer "F.SilkS")
		)
		(fp_line
			(start 7.04469 -4.795012)
			(end 7.057136 -4.864354)
			(stroke
				(width 0.1)
				(type default)
			)
			(layer "F.SilkS")
		)
		(fp_line
			(start 7.047992 -0.816102)
			(end 9.318752 -2.994406)
			(stroke
				(width 0.1)
				(type default)
			)
			(layer "F.SilkS")
		)
		(fp_line
			(start 7.047992 -0.816102)
			(end 9.318752 -2.994406)
			(stroke
				(width 0.1)
				(type default)
			)
			(layer "F.SilkS")
		)
		(fp_line
			(start 7.057136 -4.864354)
			(end 5.7023 -3.56489)
			(stroke
				(width 0.1)
				(type default)
			)
			(layer "F.SilkS")
		)
		(fp_line
			(start 7.057136 -4.864354)
			(end 5.7023 -3.56489)
			(stroke
				(width 0.1)
				(type default)
			)
			(layer "F.SilkS")
		)
		(fp_line
			(start 7.057136 -4.864354)
			(end 7.069328 -4.93395)
			(stroke
				(width 0.1)
				(type default)
			)
			(layer "F.SilkS")
		)
		(fp_line
			(start 7.057136 -4.864354)
			(end 7.069328 -4.93395)
			(stroke
				(width 0.1)
				(type default)
			)
			(layer "F.SilkS")
		)
		(fp_line
			(start 7.069328 -4.93395)
			(end 5.714238 -3.634232)
			(stroke
				(width 0.1)
				(type default)
			)
			(layer "F.SilkS")
		)
		(fp_line
			(start 7.069328 -4.93395)
			(end 5.714238 -3.634232)
			(stroke
				(width 0.1)
				(type default)
			)
			(layer "F.SilkS")
		)
		(fp_line
			(start 7.069328 -4.93395)
			(end 7.081266 -5.003292)
			(stroke
				(width 0.1)
				(type default)
			)
			(layer "F.SilkS")
		)
		(fp_line
			(start 7.069328 -4.93395)
			(end 7.081266 -5.003292)
			(stroke
				(width 0.1)
				(type default)
			)
			(layer "F.SilkS")
		)
		(fp_line
			(start 7.07644 -5.171694)
			(end 5.763006 -3.911854)
			(stroke
				(width 0.1)
				(type default)
			)
			(layer "F.SilkS")
		)
		(fp_line
			(start 7.07644 -5.171694)
			(end 5.763006 -3.911854)
			(stroke
				(width 0.1)
				(type default)
			)
			(layer "F.SilkS")
		)
		(fp_line
			(start 7.07644 -5.171694)
			(end 7.016242 -5.171694)
			(stroke
				(width 0.1)
				(type default)
			)
			(layer "F.SilkS")
		)
		(fp_line
			(start 7.07644 -5.171694)
			(end 7.016242 -5.171694)
			(stroke
				(width 0.1)
				(type default)
			)
			(layer "F.SilkS")
		)
		(fp_line
			(start 7.081266 -5.003292)
			(end 5.72643 -3.703828)
			(stroke
				(width 0.1)
				(type default)
			)
			(layer "F.SilkS")
		)
		(fp_line
			(start 7.081266 -5.003292)
			(end 5.72643 -3.703828)
			(stroke
				(width 0.1)
				(type default)
			)
			(layer "F.SilkS")
		)
		(fp_line
			(start 7.081266 -5.003292)
			(end 7.093458 -5.072888)
			(stroke
				(width 0.1)
				(type default)
			)
			(layer "F.SilkS")
		)
		(fp_line
			(start 7.081266 -5.003292)
			(end 7.093458 -5.072888)
			(stroke
				(width 0.1)
				(type default)
			)
			(layer "F.SilkS")
		)
		(fp_line
			(start 7.093458 -5.072888)
			(end 5.738876 -3.772916)
			(stroke
				(width 0.1)
				(type default)
			)
			(layer "F.SilkS")
		)
		(fp_line
			(start 7.093458 -5.072888)
			(end 5.738876 -3.772916)
			(stroke
				(width 0.1)
				(type default)
			)
			(layer "F.SilkS")
		)
		(fp_line
			(start 7.093458 -5.072888)
			(end 7.10565 -5.141976)
			(stroke
				(width 0.1)
				(type default)
			)
			(layer "F.SilkS")
		)
		(fp_line
			(start 7.093458 -5.072888)
			(end 7.10565 -5.141976)
			(stroke
				(width 0.1)
				(type default)
			)
			(layer "F.SilkS")
		)
		(fp_line
			(start 7.10565 -5.141976)
			(end 5.751068 -3.842512)
			(stroke
				(width 0.1)
				(type default)
			)
			(layer "F.SilkS")
		)
		(fp_line
			(start 7.10565 -5.141976)
			(end 5.751068 -3.842512)
			(stroke
				(width 0.1)
				(type default)
			)
			(layer "F.SilkS")
		)
		(fp_line
			(start 7.10565 -5.141976)
			(end 7.110984 -5.171694)
			(stroke
				(width 0.1)
				(type default)
			)
			(layer "F.SilkS")
		)
		(fp_line
			(start 7.10565 -5.141976)
			(end 7.110984 -5.171694)
			(stroke
				(width 0.1)
				(type default)
			)
			(layer "F.SilkS")
		)
		(fp_line
			(start 7.110984 -5.171694)
			(end 7.07644 -5.171694)
			(stroke
				(width 0.1)
				(type default)
			)
			(layer "F.SilkS")
		)
		(fp_line
			(start 7.110984 -5.171694)
			(end 7.07644 -5.171694)
			(stroke
				(width 0.1)
				(type default)
			)
			(layer "F.SilkS")
		)
		(fp_line
			(start 7.11454 -0.822198)
			(end 9.30656 -2.925064)
			(stroke
				(width 0.1)
				(type default)
			)
			(layer "F.SilkS")
		)
		(fp_line
			(start 7.11454 -0.822198)
			(end 9.30656 -2.925064)
			(stroke
				(width 0.1)
				(type default)
			)
			(layer "F.SilkS")
		)
		(fp_line
			(start 7.196582 -0.84328)
			(end 9.294368 -2.855468)
			(stroke
				(width 0.1)
				(type default)
			)
			(layer "F.SilkS")
		)
		(fp_line
			(start 7.196582 -0.84328)
			(end 9.294368 -2.855468)
			(stroke
				(width 0.1)
				(type default)
			)
			(layer "F.SilkS")
		)
		(fp_line
			(start 7.281418 -0.866648)
			(end 9.281922 -2.786126)
			(stroke
				(width 0.1)
				(type default)
			)
			(layer "F.SilkS")
		)
		(fp_line
			(start 7.281418 -0.866648)
			(end 9.281922 -2.786126)
			(stroke
				(width 0.1)
				(type default)
			)
			(layer "F.SilkS")
		)
		(fp_line
			(start 7.366 -0.890016)
			(end 9.269984 -2.716784)
			(stroke
				(width 0.1)
				(type default)
			)
			(layer "F.SilkS")
		)
		(fp_line
			(start 7.366 -0.890016)
			(end 9.269984 -2.716784)
			(stroke
				(width 0.1)
				(type default)
			)
			(layer "F.SilkS")
		)
		(fp_line
			(start 7.464298 -0.926846)
			(end 9.257792 -2.647188)
			(stroke
				(width 0.1)
				(type default)
			)
			(layer "F.SilkS")
		)
		(fp_line
			(start 7.464298 -0.926846)
			(end 9.257792 -2.647188)
			(stroke
				(width 0.1)
				(type default)
			)
			(layer "F.SilkS")
		)
		(fp_line
			(start 7.583678 -0.983488)
			(end 9.2456 -2.577592)
			(stroke
				(width 0.1)
				(type default)
			)
			(layer "F.SilkS")
		)
		(fp_line
			(start 7.583678 -0.983488)
			(end 9.2456 -2.577592)
			(stroke
				(width 0.1)
				(type default)
			)
			(layer "F.SilkS")
		)
		(fp_line
			(start 7.737348 -1.07315)
			(end 9.233408 -2.508504)
			(stroke
				(width 0.1)
				(type default)
			)
			(layer "F.SilkS")
		)
		(fp_line
			(start 7.737348 -1.07315)
			(end 9.233408 -2.508504)
			(stroke
				(width 0.1)
				(type default)
			)
			(layer "F.SilkS")
		)
		(fp_line
			(start 7.82066 -0.882904)
			(end 7.839456 -0.882904)
			(stroke
				(width 0.1)
				(type default)
			)
			(layer "F.SilkS")
		)
		(fp_line
			(start 7.82066 -0.882904)
			(end 7.839456 -0.882904)
			(stroke
				(width 0.1)
				(type default)
			)
			(layer "F.SilkS")
		)
		(fp_line
			(start 7.828788 -0.930148)
			(end 7.82066 -0.882904)
			(stroke
				(width 0.1)
				(type default)
			)
			(layer "F.SilkS")
		)
		(fp_line
			(start 7.828788 -0.930148)
			(end 7.82066 -0.882904)
			(stroke
				(width 0.1)
				(type default)
			)
			(layer "F.SilkS")
		)
		(fp_line
			(start 7.828788 -0.930148)
			(end 9.18464 -2.230882)
			(stroke
				(width 0.1)
				(type default)
			)
			(layer "F.SilkS")
		)
		(fp_line
			(start 7.828788 -0.930148)
			(end 9.18464 -2.230882)
			(stroke
				(width 0.1)
				(type default)
			)
			(layer "F.SilkS")
		)
		(fp_line
			(start 7.839456 -0.882904)
			(end 7.899908 -0.882904)
			(stroke
				(width 0.1)
				(type default)
			)
			(layer "F.SilkS")
		)
		(fp_line
			(start 7.839456 -0.882904)
			(end 7.899908 -0.882904)
			(stroke
				(width 0.1)
				(type default)
			)
			(layer "F.SilkS")
		)
		(fp_line
			(start 7.839456 -0.882904)
			(end 9.172194 -2.161286)
			(stroke
				(width 0.1)
				(type default)
			)
			(layer "F.SilkS")
		)
		(fp_line
			(start 7.839456 -0.882904)
			(end 9.172194 -2.161286)
			(stroke
				(width 0.1)
				(type default)
			)
			(layer "F.SilkS")
		)
		(fp_line
			(start 7.84098 -0.999744)
			(end 7.828788 -0.930148)
			(stroke
				(width 0.1)
				(type default)
			)
			(layer "F.SilkS")
		)
		(fp_line
			(start 7.84098 -0.999744)
			(end 7.828788 -0.930148)
			(stroke
				(width 0.1)
				(type default)
			)
			(layer "F.SilkS")
		)
		(fp_line
			(start 7.84098 -0.999744)
			(end 9.196832 -2.300224)
			(stroke
				(width 0.1)
				(type default)
			)
			(layer "F.SilkS")
		)
		(fp_line
			(start 7.84098 -0.999744)
			(end 9.196832 -2.300224)
			(stroke
				(width 0.1)
				(type default)
			)
			(layer "F.SilkS")
		)
		(fp_line
			(start 7.852918 -1.068832)
			(end 7.84098 -0.999744)
			(stroke
				(width 0.1)
				(type default)
			)
			(layer "F.SilkS")
		)
		(fp_line
			(start 7.852918 -1.068832)
			(end 7.84098 -0.999744)
			(stroke
				(width 0.1)
				(type default)
			)
			(layer "F.SilkS")
		)
		(fp_line
			(start 7.852918 -1.068832)
			(end 9.209024 -2.369566)
			(stroke
				(width 0.1)
				(type default)
			)
			(layer "F.SilkS")
		)
		(fp_line
			(start 7.852918 -1.068832)
			(end 9.209024 -2.369566)
			(stroke
				(width 0.1)
				(type default)
			)
			(layer "F.SilkS")
		)
		(fp_line
			(start 7.865364 -1.138428)
			(end 7.852918 -1.068832)
			(stroke
				(width 0.1)
				(type default)
			)
			(layer "F.SilkS")
		)
		(fp_line
			(start 7.865364 -1.138428)
			(end 7.852918 -1.068832)
			(stroke
				(width 0.1)
				(type default)
			)
			(layer "F.SilkS")
		)
		(fp_line
			(start 7.865364 -1.138428)
			(end 9.220962 -2.438908)
			(stroke
				(width 0.1)
				(type default)
			)
			(layer "F.SilkS")
		)
		(fp_line
			(start 7.865364 -1.138428)
			(end 9.220962 -2.438908)
			(stroke
				(width 0.1)
				(type default)
			)
			(layer "F.SilkS")
		)
		(fp_line
			(start 7.899908 -0.882904)
			(end 7.960106 -0.882904)
			(stroke
				(width 0.1)
				(type default)
			)
			(layer "F.SilkS")
		)
		(fp_line
			(start 7.899908 -0.882904)
			(end 7.960106 -0.882904)
			(stroke
				(width 0.1)
				(type default)
			)
			(layer "F.SilkS")
		)
		(fp_line
			(start 7.899908 -0.882904)
			(end 9.160002 -2.091944)
			(stroke
				(width 0.1)
				(type default)
			)
			(layer "F.SilkS")
		)
		(fp_line
			(start 7.899908 -0.882904)
			(end 9.160002 -2.091944)
			(stroke
				(width 0.1)
				(type default)
			)
			(layer "F.SilkS")
		)
		(fp_line
			(start 7.936484 -2.187702)
			(end 9.42848 -3.618992)
			(stroke
				(width 0.1)
				(type default)
			)
			(layer "F.SilkS")
		)
		(fp_line
			(start 7.936484 -2.187702)
			(end 9.42848 -3.618992)
			(stroke
				(width 0.1)
				(type default)
			)
			(layer "F.SilkS")
		)
		(fp_line
			(start 7.960106 -0.882904)
			(end 8.02005 -0.882904)
			(stroke
				(width 0.1)
				(type default)
			)
			(layer "F.SilkS")
		)
		(fp_line
			(start 7.960106 -0.882904)
			(end 8.02005 -0.882904)
			(stroke
				(width 0.1)
				(type default)
			)
			(layer "F.SilkS")
		)
		(fp_line
			(start 7.960106 -0.882904)
			(end 9.148064 -2.022602)
			(stroke
				(width 0.1)
				(type default)
			)
			(layer "F.SilkS")
		)
		(fp_line
			(start 7.960106 -0.882904)
			(end 9.148064 -2.022602)
			(stroke
				(width 0.1)
				(type default)
			)
			(layer "F.SilkS")
		)
		(fp_line
			(start 8.002778 -2.30886)
			(end 9.440672 -3.688334)
			(stroke
				(width 0.1)
				(type default)
			)
			(layer "F.SilkS")
		)
		(fp_line
			(start 8.002778 -2.30886)
			(end 9.440672 -3.688334)
			(stroke
				(width 0.1)
				(type default)
			)
			(layer "F.SilkS")
		)
		(fp_line
			(start 8.02005 -0.882904)
			(end 8.080248 -0.882904)
			(stroke
				(width 0.1)
				(type default)
			)
			(layer "F.SilkS")
		)
		(fp_line
			(start 8.02005 -0.882904)
			(end 8.080248 -0.882904)
			(stroke
				(width 0.1)
				(type default)
			)
			(layer "F.SilkS")
		)
		(fp_line
			(start 8.02005 -0.882904)
			(end 9.135872 -1.953006)
			(stroke
				(width 0.1)
				(type default)
			)
			(layer "F.SilkS")
		)
		(fp_line
			(start 8.02005 -0.882904)
			(end 9.135872 -1.953006)
			(stroke
				(width 0.1)
				(type default)
			)
			(layer "F.SilkS")
		)
		(fp_line
			(start 8.04799 -2.410206)
			(end 9.452864 -3.75793)
			(stroke
				(width 0.1)
				(type default)
			)
			(layer "F.SilkS")
		)
		(fp_line
			(start 8.04799 -2.410206)
			(end 9.452864 -3.75793)
			(stroke
				(width 0.1)
				(type default)
			)
			(layer "F.SilkS")
		)
		(fp_line
			(start 8.078724 -2.497328)
			(end 9.465056 -3.827526)
			(stroke
				(width 0.1)
				(type default)
			)
			(layer "F.SilkS")
		)
		(fp_line
			(start 8.078724 -2.497328)
			(end 9.465056 -3.827526)
			(stroke
				(width 0.1)
				(type default)
			)
			(layer "F.SilkS")
		)
		(fp_line
			(start 8.080248 -0.882904)
			(end 8.140446 -0.882904)
			(stroke
				(width 0.1)
				(type default)
			)
			(layer "F.SilkS")
		)
		(fp_line
			(start 8.080248 -0.882904)
			(end 8.140446 -0.882904)
			(stroke
				(width 0.1)
				(type default)
			)
			(layer "F.SilkS")
		)
		(fp_line
			(start 8.080248 -0.882904)
			(end 9.12368 -1.883664)
			(stroke
				(width 0.1)
				(type default)
			)
			(layer "F.SilkS")
		)
		(fp_line
			(start 8.080248 -0.882904)
			(end 9.12368 -1.883664)
			(stroke
				(width 0.1)
				(type default)
			)
			(layer "F.SilkS")
		)
		(fp_line
			(start 8.140446 -0.882904)
			(end 8.200644 -0.882904)
			(stroke
				(width 0.1)
				(type default)
			)
			(layer "F.SilkS")
		)
		(fp_line
			(start 8.140446 -0.882904)
			(end 8.200644 -0.882904)
			(stroke
				(width 0.1)
				(type default)
			)
			(layer "F.SilkS")
		)
		(fp_line
			(start 8.140446 -0.882904)
			(end 9.111234 -1.814322)
			(stroke
				(width 0.1)
				(type default)
			)
			(layer "F.SilkS")
		)
		(fp_line
			(start 8.140446 -0.882904)
			(end 9.111234 -1.814322)
			(stroke
				(width 0.1)
				(type default)
			)
			(layer "F.SilkS")
		)
		(fp_line
			(start 8.18261 -2.943352)
			(end 8.170418 -2.87401)
			(stroke
				(width 0.1)
				(type default)
			)
			(layer "F.SilkS")
		)
		(fp_line
			(start 8.18261 -2.943352)
			(end 8.170418 -2.87401)
			(stroke
				(width 0.1)
				(type default)
			)
			(layer "F.SilkS")
		)
		(fp_line
			(start 8.194802 -3.012694)
			(end 8.18261 -2.943352)
			(stroke
				(width 0.1)
				(type default)
			)
			(layer "F.SilkS")
		)
		(fp_line
			(start 8.194802 -3.012694)
			(end 8.18261 -2.943352)
			(stroke
				(width 0.1)
				(type default)
			)
			(layer "F.SilkS")
		)
		(fp_line
			(start 8.200644 -0.882904)
			(end 8.260842 -0.882904)
			(stroke
				(width 0.1)
				(type default)
			)
			(layer "F.SilkS")
		)
		(fp_line
			(start 8.200644 -0.882904)
			(end 8.260842 -0.882904)
			(stroke
				(width 0.1)
				(type default)
			)
			(layer "F.SilkS")
		)
		(fp_line
			(start 8.200644 -0.882904)
			(end 9.099042 -1.744726)
			(stroke
				(width 0.1)
				(type default)
			)
			(layer "F.SilkS")
		)
		(fp_line
			(start 8.200644 -0.882904)
			(end 9.099042 -1.744726)
			(stroke
				(width 0.1)
				(type default)
			)
			(layer "F.SilkS")
		)
		(fp_line
			(start 8.206994 -3.08229)
			(end 8.194802 -3.012694)
			(stroke
				(width 0.1)
				(type default)
			)
			(layer "F.SilkS")
		)
		(fp_line
			(start 8.206994 -3.08229)
			(end 8.194802 -3.012694)
			(stroke
				(width 0.1)
				(type default)
			)
			(layer "F.SilkS")
		)
		(fp_line
			(start 8.219186 -3.151378)
			(end 8.206994 -3.08229)
			(stroke
				(width 0.1)
				(type default)
			)
			(layer "F.SilkS")
		)
		(fp_line
			(start 8.219186 -3.151378)
			(end 8.206994 -3.08229)
			(stroke
				(width 0.1)
				(type default)
			)
			(layer "F.SilkS")
		)
		(fp_line
			(start 8.231378 -3.22072)
			(end 8.219186 -3.151378)
			(stroke
				(width 0.1)
				(type default)
			)
			(layer "F.SilkS")
		)
		(fp_line
			(start 8.231378 -3.22072)
			(end 8.219186 -3.151378)
			(stroke
				(width 0.1)
				(type default)
			)
			(layer "F.SilkS")
		)
		(fp_line
			(start 8.24357 -3.290316)
			(end 8.231378 -3.22072)
			(stroke
				(width 0.1)
				(type default)
			)
			(layer "F.SilkS")
		)
		(fp_line
			(start 8.24357 -3.290316)
			(end 8.231378 -3.22072)
			(stroke
				(width 0.1)
				(type default)
			)
			(layer "F.SilkS")
		)
		(fp_line
			(start 8.255762 -3.359658)
			(end 8.24357 -3.290316)
			(stroke
				(width 0.1)
				(type default)
			)
			(layer "F.SilkS")
		)
		(fp_line
			(start 8.255762 -3.359658)
			(end 8.24357 -3.290316)
			(stroke
				(width 0.1)
				(type default)
			)
			(layer "F.SilkS")
		)
		(fp_line
			(start 8.260842 -0.882904)
			(end 8.320786 -0.882904)
			(stroke
				(width 0.1)
				(type default)
			)
			(layer "F.SilkS")
		)
		(fp_line
			(start 8.260842 -0.882904)
			(end 8.320786 -0.882904)
			(stroke
				(width 0.1)
				(type default)
			)
			(layer "F.SilkS")
		)
		(fp_line
			(start 8.260842 -0.882904)
			(end 9.087104 -1.675384)
			(stroke
				(width 0.1)
				(type default)
			)
			(layer "F.SilkS")
		)
		(fp_line
			(start 8.260842 -0.882904)
			(end 9.087104 -1.675384)
			(stroke
				(width 0.1)
				(type default)
			)
			(layer "F.SilkS")
		)
		(fp_line
			(start 8.2677 -3.429)
			(end 8.255762 -3.359658)
			(stroke
				(width 0.1)
				(type default)
			)
			(layer "F.SilkS")
		)
		(fp_line
			(start 8.2677 -3.429)
			(end 8.255762 -3.359658)
			(stroke
				(width 0.1)
				(type default)
			)
			(layer "F.SilkS")
		)
		(fp_line
			(start 8.279892 -3.498342)
			(end 8.2677 -3.429)
			(stroke
				(width 0.1)
				(type default)
			)
			(layer "F.SilkS")
		)
		(fp_line
			(start 8.279892 -3.498342)
			(end 8.2677 -3.429)
			(stroke
				(width 0.1)
				(type default)
			)
			(layer "F.SilkS")
		)
		(fp_line
			(start 8.292084 -3.567684)
			(end 8.279892 -3.498342)
			(stroke
				(width 0.1)
				(type default)
			)
			(layer "F.SilkS")
		)
		(fp_line
			(start 8.292084 -3.567684)
			(end 8.279892 -3.498342)
			(stroke
				(width 0.1)
				(type default)
			)
			(layer "F.SilkS")
		)
		(fp_line
			(start 8.304276 -3.63728)
			(end 8.292084 -3.567684)
			(stroke
				(width 0.1)
				(type default)
			)
			(layer "F.SilkS")
		)
		(fp_line
			(start 8.304276 -3.63728)
			(end 8.292084 -3.567684)
			(stroke
				(width 0.1)
				(type default)
			)
			(layer "F.SilkS")
		)
		(fp_line
			(start 8.316468 -3.706368)
			(end 8.304276 -3.63728)
			(stroke
				(width 0.1)
				(type default)
			)
			(layer "F.SilkS")
		)
		(fp_line
			(start 8.316468 -3.706368)
			(end 8.304276 -3.63728)
			(stroke
				(width 0.1)
				(type default)
			)
			(layer "F.SilkS")
		)
		(fp_line
			(start 8.320786 -0.882904)
			(end 8.381238 -0.882904)
			(stroke
				(width 0.1)
				(type default)
			)
			(layer "F.SilkS")
		)
		(fp_line
			(start 8.320786 -0.882904)
			(end 8.381238 -0.882904)
			(stroke
				(width 0.1)
				(type default)
			)
			(layer "F.SilkS")
		)
		(fp_line
			(start 8.320786 -0.882904)
			(end 9.074912 -1.606296)
			(stroke
				(width 0.1)
				(type default)
			)
			(layer "F.SilkS")
		)
		(fp_line
			(start 8.320786 -0.882904)
			(end 9.074912 -1.606296)
			(stroke
				(width 0.1)
				(type default)
			)
			(layer "F.SilkS")
		)
		(fp_line
			(start 8.32866 -3.77571)
			(end 8.316468 -3.706368)
			(stroke
				(width 0.1)
				(type default)
			)
			(layer "F.SilkS")
		)
		(fp_line
			(start 8.32866 -3.77571)
			(end 8.316468 -3.706368)
			(stroke
				(width 0.1)
				(type default)
			)
			(layer "F.SilkS")
		)
		(fp_line
			(start 8.340852 -3.845306)
			(end 8.32866 -3.77571)
			(stroke
				(width 0.1)
				(type default)
			)
			(layer "F.SilkS")
		)
		(fp_line
			(start 8.340852 -3.845306)
			(end 8.32866 -3.77571)
			(stroke
				(width 0.1)
				(type default)
			)
			(layer "F.SilkS")
		)
		(fp_line
			(start 8.35279 -3.914648)
			(end 8.340852 -3.845306)
			(stroke
				(width 0.1)
				(type default)
			)
			(layer "F.SilkS")
		)
		(fp_line
			(start 8.35279 -3.914648)
			(end 8.340852 -3.845306)
			(stroke
				(width 0.1)
				(type default)
			)
			(layer "F.SilkS")
		)
		(fp_line
			(start 8.365236 -3.98399)
			(end 8.35279 -3.914648)
			(stroke
				(width 0.1)
				(type default)
			)
			(layer "F.SilkS")
		)
		(fp_line
			(start 8.365236 -3.98399)
			(end 8.35279 -3.914648)
			(stroke
				(width 0.1)
				(type default)
			)
			(layer "F.SilkS")
		)
		(fp_line
			(start 8.377174 -4.053332)
			(end 8.365236 -3.98399)
			(stroke
				(width 0.1)
				(type default)
			)
			(layer "F.SilkS")
		)
		(fp_line
			(start 8.377174 -4.053332)
			(end 8.365236 -3.98399)
			(stroke
				(width 0.1)
				(type default)
			)
			(layer "F.SilkS")
		)
		(fp_line
			(start 8.381238 -0.882904)
			(end 8.441182 -0.882904)
			(stroke
				(width 0.1)
				(type default)
			)
			(layer "F.SilkS")
		)
		(fp_line
			(start 8.381238 -0.882904)
			(end 8.441182 -0.882904)
			(stroke
				(width 0.1)
				(type default)
			)
			(layer "F.SilkS")
		)
		(fp_line
			(start 8.381238 -0.882904)
			(end 9.062466 -1.5367)
			(stroke
				(width 0.1)
				(type default)
			)
			(layer "F.SilkS")
		)
		(fp_line
			(start 8.381238 -0.882904)
			(end 9.062466 -1.5367)
			(stroke
				(width 0.1)
				(type default)
			)
			(layer "F.SilkS")
		)
		(fp_line
			(start 8.389366 -4.122674)
			(end 8.377174 -4.053332)
			(stroke
				(width 0.1)
				(type default)
			)
			(layer "F.SilkS")
		)
		(fp_line
			(start 8.389366 -4.122674)
			(end 8.377174 -4.053332)
			(stroke
				(width 0.1)
				(type default)
			)
			(layer "F.SilkS")
		)
		(fp_line
			(start 8.401558 -4.19227)
			(end 8.389366 -4.122674)
			(stroke
				(width 0.1)
				(type default)
			)
			(layer "F.SilkS")
		)
		(fp_line
			(start 8.401558 -4.19227)
			(end 8.389366 -4.122674)
			(stroke
				(width 0.1)
				(type default)
			)
			(layer "F.SilkS")
		)
		(fp_line
			(start 8.41375 -4.261612)
			(end 8.401558 -4.19227)
			(stroke
				(width 0.1)
				(type default)
			)
			(layer "F.SilkS")
		)
		(fp_line
			(start 8.41375 -4.261612)
			(end 8.401558 -4.19227)
			(stroke
				(width 0.1)
				(type default)
			)
			(layer "F.SilkS")
		)
		(fp_line
			(start 8.425942 -4.3307)
			(end 8.41375 -4.261612)
			(stroke
				(width 0.1)
				(type default)
			)
			(layer "F.SilkS")
		)
		(fp_line
			(start 8.425942 -4.3307)
			(end 8.41375 -4.261612)
			(stroke
				(width 0.1)
				(type default)
			)
			(layer "F.SilkS")
		)
		(fp_line
			(start 8.43788 -4.400296)
			(end 8.425942 -4.3307)
			(stroke
				(width 0.1)
				(type default)
			)
			(layer "F.SilkS")
		)
		(fp_line
			(start 8.43788 -4.400296)
			(end 8.425942 -4.3307)
			(stroke
				(width 0.1)
				(type default)
			)
			(layer "F.SilkS")
		)
		(fp_line
			(start 8.441182 -0.882904)
			(end 8.50138 -0.882904)
			(stroke
				(width 0.1)
				(type default)
			)
			(layer "F.SilkS")
		)
		(fp_line
			(start 8.441182 -0.882904)
			(end 8.50138 -0.882904)
			(stroke
				(width 0.1)
				(type default)
			)
			(layer "F.SilkS")
		)
		(fp_line
			(start 8.441182 -0.882904)
			(end 9.050274 -1.467104)
			(stroke
				(width 0.1)
				(type default)
			)
			(layer "F.SilkS")
		)
		(fp_line
			(start 8.441182 -0.882904)
			(end 9.050274 -1.467104)
			(stroke
				(width 0.1)
				(type default)
			)
			(layer "F.SilkS")
		)
		(fp_line
			(start 8.450326 -4.469638)
			(end 8.43788 -4.400296)
			(stroke
				(width 0.1)
				(type default)
			)
			(layer "F.SilkS")
		)
		(fp_line
			(start 8.450326 -4.469638)
			(end 8.43788 -4.400296)
			(stroke
				(width 0.1)
				(type default)
			)
			(layer "F.SilkS")
		)
		(fp_line
			(start 8.450326 -4.469638)
			(end 8.462264 -4.53898)
			(stroke
				(width 0.1)
				(type default)
			)
			(layer "F.SilkS")
		)
		(fp_line
			(start 8.450326 -4.469638)
			(end 8.462264 -4.53898)
			(stroke
				(width 0.1)
				(type default)
			)
			(layer "F.SilkS")
		)
		(fp_line
			(start 8.462264 -4.53898)
			(end 8.474456 -4.608322)
			(stroke
				(width 0.1)
				(type default)
			)
			(layer "F.SilkS")
		)
		(fp_line
			(start 8.462264 -4.53898)
			(end 8.474456 -4.608322)
			(stroke
				(width 0.1)
				(type default)
			)
			(layer "F.SilkS")
		)
		(fp_line
			(start 8.474456 -4.608322)
			(end 8.486648 -4.677664)
			(stroke
				(width 0.1)
				(type default)
			)
			(layer "F.SilkS")
		)
		(fp_line
			(start 8.474456 -4.608322)
			(end 8.486648 -4.677664)
			(stroke
				(width 0.1)
				(type default)
			)
			(layer "F.SilkS")
		)
		(fp_line
			(start 8.486648 -4.677664)
			(end 8.49884 -4.74726)
			(stroke
				(width 0.1)
				(type default)
			)
			(layer "F.SilkS")
		)
		(fp_line
			(start 8.486648 -4.677664)
			(end 8.49884 -4.74726)
			(stroke
				(width 0.1)
				(type default)
			)
			(layer "F.SilkS")
		)
		(fp_line
			(start 8.49884 -4.74726)
			(end 8.511032 -4.816602)
			(stroke
				(width 0.1)
				(type default)
			)
			(layer "F.SilkS")
		)
		(fp_line
			(start 8.49884 -4.74726)
			(end 8.511032 -4.816602)
			(stroke
				(width 0.1)
				(type default)
			)
			(layer "F.SilkS")
		)
		(fp_line
			(start 8.50138 -0.882904)
			(end 8.561578 -0.882904)
			(stroke
				(width 0.1)
				(type default)
			)
			(layer "F.SilkS")
		)
		(fp_line
			(start 8.50138 -0.882904)
			(end 8.561578 -0.882904)
			(stroke
				(width 0.1)
				(type default)
			)
			(layer "F.SilkS")
		)
		(fp_line
			(start 8.50138 -0.882904)
			(end 9.038082 -1.397762)
			(stroke
				(width 0.1)
				(type default)
			)
			(layer "F.SilkS")
		)
		(fp_line
			(start 8.50138 -0.882904)
			(end 9.038082 -1.397762)
			(stroke
				(width 0.1)
				(type default)
			)
			(layer "F.SilkS")
		)
		(fp_line
			(start 8.511032 -4.816602)
			(end 8.52297 -4.88569)
			(stroke
				(width 0.1)
				(type default)
			)
			(layer "F.SilkS")
		)
		(fp_line
			(start 8.511032 -4.816602)
			(end 8.52297 -4.88569)
			(stroke
				(width 0.1)
				(type default)
			)
			(layer "F.SilkS")
		)
		(fp_line
			(start 8.52297 -4.88569)
			(end 8.535416 -4.955286)
			(stroke
				(width 0.1)
				(type default)
			)
			(layer "F.SilkS")
		)
		(fp_line
			(start 8.52297 -4.88569)
			(end 8.535416 -4.955286)
			(stroke
				(width 0.1)
				(type default)
			)
			(layer "F.SilkS")
		)
		(fp_line
			(start 8.535416 -4.955286)
			(end 8.547608 -5.024628)
			(stroke
				(width 0.1)
				(type default)
			)
			(layer "F.SilkS")
		)
		(fp_line
			(start 8.535416 -4.955286)
			(end 8.547608 -5.024628)
			(stroke
				(width 0.1)
				(type default)
			)
			(layer "F.SilkS")
		)
		(fp_line
			(start 8.547608 -5.024628)
			(end 8.559546 -5.09397)
			(stroke
				(width 0.1)
				(type default)
			)
			(layer "F.SilkS")
		)
		(fp_line
			(start 8.547608 -5.024628)
			(end 8.559546 -5.09397)
			(stroke
				(width 0.1)
				(type default)
			)
			(layer "F.SilkS")
		)
		(fp_line
			(start 8.559546 -5.09397)
			(end 8.571738 -5.163312)
			(stroke
				(width 0.1)
				(type default)
			)
			(layer "F.SilkS")
		)
		(fp_line
			(start 8.559546 -5.09397)
			(end 8.571738 -5.163312)
			(stroke
				(width 0.1)
				(type default)
			)
			(layer "F.SilkS")
		)
		(fp_line
			(start 8.561578 -0.882904)
			(end 8.621522 -0.882904)
			(stroke
				(width 0.1)
				(type default)
			)
			(layer "F.SilkS")
		)
		(fp_line
			(start 8.561578 -0.882904)
			(end 8.621522 -0.882904)
			(stroke
				(width 0.1)
				(type default)
			)
			(layer "F.SilkS")
		)
		(fp_line
			(start 8.561578 -0.882904)
			(end 9.026144 -1.32842)
			(stroke
				(width 0.1)
				(type default)
			)
			(layer "F.SilkS")
		)
		(fp_line
			(start 8.561578 -0.882904)
			(end 9.026144 -1.32842)
			(stroke
				(width 0.1)
				(type default)
			)
			(layer "F.SilkS")
		)
		(fp_line
			(start 8.573262 -5.171694)
			(end 8.571738 -5.163312)
			(stroke
				(width 0.1)
				(type default)
			)
			(layer "F.SilkS")
		)
		(fp_line
			(start 8.573262 -5.171694)
			(end 8.571738 -5.163312)
			(stroke
				(width 0.1)
				(type default)
			)
			(layer "F.SilkS")
		)
		(fp_line
			(start 8.580374 -5.171694)
			(end 8.571738 -5.163312)
			(stroke
				(width 0.1)
				(type default)
			)
			(layer "F.SilkS")
		)
		(fp_line
			(start 8.580374 -5.171694)
			(end 8.571738 -5.163312)
			(stroke
				(width 0.1)
				(type default)
			)
			(layer "F.SilkS")
		)
		(fp_line
			(start 8.580374 -5.171694)
			(end 8.573262 -5.171694)
			(stroke
				(width 0.1)
				(type default)
			)
			(layer "F.SilkS")
		)
		(fp_line
			(start 8.580374 -5.171694)
			(end 8.573262 -5.171694)
			(stroke
				(width 0.1)
				(type default)
			)
			(layer "F.SilkS")
		)
		(fp_line
			(start 8.621522 -0.882904)
			(end 8.681974 -0.882904)
			(stroke
				(width 0.1)
				(type default)
			)
			(layer "F.SilkS")
		)
		(fp_line
			(start 8.621522 -0.882904)
			(end 8.681974 -0.882904)
			(stroke
				(width 0.1)
				(type default)
			)
			(layer "F.SilkS")
		)
		(fp_line
			(start 8.621522 -0.882904)
			(end 9.013952 -1.259078)
			(stroke
				(width 0.1)
				(type default)
			)
			(layer "F.SilkS")
		)
		(fp_line
			(start 8.621522 -0.882904)
			(end 9.013952 -1.259078)
			(stroke
				(width 0.1)
				(type default)
			)
			(layer "F.SilkS")
		)
		(fp_line
			(start 8.640572 -5.171694)
			(end 8.559546 -5.09397)
			(stroke
				(width 0.1)
				(type default)
			)
			(layer "F.SilkS")
		)
		(fp_line
			(start 8.640572 -5.171694)
			(end 8.559546 -5.09397)
			(stroke
				(width 0.1)
				(type default)
			)
			(layer "F.SilkS")
		)
		(fp_line
			(start 8.640572 -5.171694)
			(end 8.580374 -5.171694)
			(stroke
				(width 0.1)
				(type default)
			)
			(layer "F.SilkS")
		)
		(fp_line
			(start 8.640572 -5.171694)
			(end 8.580374 -5.171694)
			(stroke
				(width 0.1)
				(type default)
			)
			(layer "F.SilkS")
		)
		(fp_line
			(start 8.681974 -0.882904)
			(end 8.741918 -0.882904)
			(stroke
				(width 0.1)
				(type default)
			)
			(layer "F.SilkS")
		)
		(fp_line
			(start 8.681974 -0.882904)
			(end 8.741918 -0.882904)
			(stroke
				(width 0.1)
				(type default)
			)
			(layer "F.SilkS")
		)
		(fp_line
			(start 8.681974 -0.882904)
			(end 9.001506 -1.189482)
			(stroke
				(width 0.1)
				(type default)
			)
			(layer "F.SilkS")
		)
		(fp_line
			(start 8.681974 -0.882904)
			(end 9.001506 -1.189482)
			(stroke
				(width 0.1)
				(type default)
			)
			(layer "F.SilkS")
		)
		(fp_line
			(start 8.70077 -5.171694)
			(end 8.547608 -5.024628)
			(stroke
				(width 0.1)
				(type default)
			)
			(layer "F.SilkS")
		)
		(fp_line
			(start 8.70077 -5.171694)
			(end 8.547608 -5.024628)
			(stroke
				(width 0.1)
				(type default)
			)
			(layer "F.SilkS")
		)
		(fp_line
			(start 8.70077 -5.171694)
			(end 8.640572 -5.171694)
			(stroke
				(width 0.1)
				(type default)
			)
			(layer "F.SilkS")
		)
		(fp_line
			(start 8.70077 -5.171694)
			(end 8.640572 -5.171694)
			(stroke
				(width 0.1)
				(type default)
			)
			(layer "F.SilkS")
		)
		(fp_line
			(start 8.741918 -0.882904)
			(end 8.802116 -0.882904)
			(stroke
				(width 0.1)
				(type default)
			)
			(layer "F.SilkS")
		)
		(fp_line
			(start 8.741918 -0.882904)
			(end 8.802116 -0.882904)
			(stroke
				(width 0.1)
				(type default)
			)
			(layer "F.SilkS")
		)
		(fp_line
			(start 8.741918 -0.882904)
			(end 8.989314 -1.12014)
			(stroke
				(width 0.1)
				(type default)
			)
			(layer "F.SilkS")
		)
		(fp_line
			(start 8.741918 -0.882904)
			(end 8.989314 -1.12014)
			(stroke
				(width 0.1)
				(type default)
			)
			(layer "F.SilkS")
		)
		(fp_line
			(start 8.760968 -5.171694)
			(end 8.535416 -4.955286)
			(stroke
				(width 0.1)
				(type default)
			)
			(layer "F.SilkS")
		)
		(fp_line
			(start 8.760968 -5.171694)
			(end 8.535416 -4.955286)
			(stroke
				(width 0.1)
				(type default)
			)
			(layer "F.SilkS")
		)
		(fp_line
			(start 8.760968 -5.171694)
			(end 8.70077 -5.171694)
			(stroke
				(width 0.1)
				(type default)
			)
			(layer "F.SilkS")
		)
		(fp_line
			(start 8.760968 -5.171694)
			(end 8.70077 -5.171694)
			(stroke
				(width 0.1)
				(type default)
			)
			(layer "F.SilkS")
		)
		(fp_line
			(start 8.802116 -0.882904)
			(end 8.862314 -0.882904)
			(stroke
				(width 0.1)
				(type default)
			)
			(layer "F.SilkS")
		)
		(fp_line
			(start 8.802116 -0.882904)
			(end 8.862314 -0.882904)
			(stroke
				(width 0.1)
				(type default)
			)
			(layer "F.SilkS")
		)
		(fp_line
			(start 8.802116 -0.882904)
			(end 8.977122 -1.050798)
			(stroke
				(width 0.1)
				(type default)
			)
			(layer "F.SilkS")
		)
		(fp_line
			(start 8.802116 -0.882904)
			(end 8.977122 -1.050798)
			(stroke
				(width 0.1)
				(type default)
			)
			(layer "F.SilkS")
		)
		(fp_line
			(start 8.821166 -5.171694)
			(end 8.52297 -4.88569)
			(stroke
				(width 0.1)
				(type default)
			)
			(layer "F.SilkS")
		)
		(fp_line
			(start 8.821166 -5.171694)
			(end 8.52297 -4.88569)
			(stroke
				(width 0.1)
				(type default)
			)
			(layer "F.SilkS")
		)
		(fp_line
			(start 8.821166 -5.171694)
			(end 8.760968 -5.171694)
			(stroke
				(width 0.1)
				(type default)
			)
			(layer "F.SilkS")
		)
		(fp_line
			(start 8.821166 -5.171694)
			(end 8.760968 -5.171694)
			(stroke
				(width 0.1)
				(type default)
			)
			(layer "F.SilkS")
		)
		(fp_line
			(start 8.862314 -0.882904)
			(end 8.922512 -0.882904)
			(stroke
				(width 0.1)
				(type default)
			)
			(layer "F.SilkS")
		)
		(fp_line
			(start 8.862314 -0.882904)
			(end 8.922512 -0.882904)
			(stroke
				(width 0.1)
				(type default)
			)
			(layer "F.SilkS")
		)
		(fp_line
			(start 8.862314 -0.882904)
			(end 8.965184 -0.981456)
			(stroke
				(width 0.1)
				(type default)
			)
			(layer "F.SilkS")
		)
		(fp_line
			(start 8.862314 -0.882904)
			(end 8.965184 -0.981456)
			(stroke
				(width 0.1)
				(type default)
			)
			(layer "F.SilkS")
		)
		(fp_line
			(start 8.88111 -5.171694)
			(end 8.511032 -4.816602)
			(stroke
				(width 0.1)
				(type default)
			)
			(layer "F.SilkS")
		)
		(fp_line
			(start 8.88111 -5.171694)
			(end 8.511032 -4.816602)
			(stroke
				(width 0.1)
				(type default)
			)
			(layer "F.SilkS")
		)
		(fp_line
			(start 8.88111 -5.171694)
			(end 8.821166 -5.171694)
			(stroke
				(width 0.1)
				(type default)
			)
			(layer "F.SilkS")
		)
		(fp_line
			(start 8.88111 -5.171694)
			(end 8.821166 -5.171694)
			(stroke
				(width 0.1)
				(type default)
			)
			(layer "F.SilkS")
		)
		(fp_line
			(start 8.922512 -0.882904)
			(end 8.947658 -0.882904)
			(stroke
				(width 0.1)
				(type default)
			)
			(layer "F.SilkS")
		)
		(fp_line
			(start 8.922512 -0.882904)
			(end 8.947658 -0.882904)
			(stroke
				(width 0.1)
				(type default)
			)
			(layer "F.SilkS")
		)
		(fp_line
			(start 8.922512 -0.882904)
			(end 8.952738 -0.91186)
			(stroke
				(width 0.1)
				(type default)
			)
			(layer "F.SilkS")
		)
		(fp_line
			(start 8.922512 -0.882904)
			(end 8.952738 -0.91186)
			(stroke
				(width 0.1)
				(type default)
			)
			(layer "F.SilkS")
		)
		(fp_line
			(start 8.941308 -5.171694)
			(end 8.49884 -4.74726)
			(stroke
				(width 0.1)
				(type default)
			)
			(layer "F.SilkS")
		)
		(fp_line
			(start 8.941308 -5.171694)
			(end 8.49884 -4.74726)
			(stroke
				(width 0.1)
				(type default)
			)
			(layer "F.SilkS")
		)
		(fp_line
			(start 8.941308 -5.171694)
			(end 8.88111 -5.171694)
			(stroke
				(width 0.1)
				(type default)
			)
			(layer "F.SilkS")
		)
		(fp_line
			(start 8.941308 -5.171694)
			(end 8.88111 -5.171694)
			(stroke
				(width 0.1)
				(type default)
			)
			(layer "F.SilkS")
		)
		(fp_line
			(start 8.947658 -0.882904)
			(end 8.952738 -0.91186)
			(stroke
				(width 0.1)
				(type default)
			)
			(layer "F.SilkS")
		)
		(fp_line
			(start 8.947658 -0.882904)
			(end 8.952738 -0.91186)
			(stroke
				(width 0.1)
				(type default)
			)
			(layer "F.SilkS")
		)
		(fp_line
			(start 8.965184 -0.981456)
			(end 8.952738 -0.91186)
			(stroke
				(width 0.1)
				(type default)
			)
			(layer "F.SilkS")
		)
		(fp_line
			(start 8.965184 -0.981456)
			(end 8.952738 -0.91186)
			(stroke
				(width 0.1)
				(type default)
			)
			(layer "F.SilkS")
		)
		(fp_line
			(start 8.977122 -1.050798)
			(end 8.965184 -0.981456)
			(stroke
				(width 0.1)
				(type default)
			)
			(layer "F.SilkS")
		)
		(fp_line
			(start 8.977122 -1.050798)
			(end 8.965184 -0.981456)
			(stroke
				(width 0.1)
				(type default)
			)
			(layer "F.SilkS")
		)
		(fp_line
			(start 8.989314 -1.12014)
			(end 8.977122 -1.050798)
			(stroke
				(width 0.1)
				(type default)
			)
			(layer "F.SilkS")
		)
		(fp_line
			(start 8.989314 -1.12014)
			(end 8.977122 -1.050798)
			(stroke
				(width 0.1)
				(type default)
			)
			(layer "F.SilkS")
		)
		(fp_line
			(start 9.001506 -5.171694)
			(end 8.486648 -4.677664)
			(stroke
				(width 0.1)
				(type default)
			)
			(layer "F.SilkS")
		)
		(fp_line
			(start 9.001506 -5.171694)
			(end 8.486648 -4.677664)
			(stroke
				(width 0.1)
				(type default)
			)
			(layer "F.SilkS")
		)
		(fp_line
			(start 9.001506 -5.171694)
			(end 8.941308 -5.171694)
			(stroke
				(width 0.1)
				(type default)
			)
			(layer "F.SilkS")
		)
		(fp_line
			(start 9.001506 -5.171694)
			(end 8.941308 -5.171694)
			(stroke
				(width 0.1)
				(type default)
			)
			(layer "F.SilkS")
		)
		(fp_line
			(start 9.001506 -1.189482)
			(end 8.989314 -1.12014)
			(stroke
				(width 0.1)
				(type default)
			)
			(layer "F.SilkS")
		)
		(fp_line
			(start 9.001506 -1.189482)
			(end 8.989314 -1.12014)
			(stroke
				(width 0.1)
				(type default)
			)
			(layer "F.SilkS")
		)
		(fp_line
			(start 9.013952 -1.259078)
			(end 9.001506 -1.189482)
			(stroke
				(width 0.1)
				(type default)
			)
			(layer "F.SilkS")
		)
		(fp_line
			(start 9.013952 -1.259078)
			(end 9.001506 -1.189482)
			(stroke
				(width 0.1)
				(type default)
			)
			(layer "F.SilkS")
		)
		(fp_line
			(start 9.026144 -1.32842)
			(end 9.013952 -1.259078)
			(stroke
				(width 0.1)
				(type default)
			)
			(layer "F.SilkS")
		)
		(fp_line
			(start 9.026144 -1.32842)
			(end 9.013952 -1.259078)
			(stroke
				(width 0.1)
				(type default)
			)
			(layer "F.SilkS")
		)
		(fp_line
			(start 9.038082 -1.397762)
			(end 9.026144 -1.32842)
			(stroke
				(width 0.1)
				(type default)
			)
			(layer "F.SilkS")
		)
		(fp_line
			(start 9.038082 -1.397762)
			(end 9.026144 -1.32842)
			(stroke
				(width 0.1)
				(type default)
			)
			(layer "F.SilkS")
		)
		(fp_line
			(start 9.050274 -1.467104)
			(end 9.038082 -1.397762)
			(stroke
				(width 0.1)
				(type default)
			)
			(layer "F.SilkS")
		)
		(fp_line
			(start 9.050274 -1.467104)
			(end 9.038082 -1.397762)
			(stroke
				(width 0.1)
				(type default)
			)
			(layer "F.SilkS")
		)
		(fp_line
			(start 9.061704 -5.171694)
			(end 8.474456 -4.608322)
			(stroke
				(width 0.1)
				(type default)
			)
			(layer "F.SilkS")
		)
		(fp_line
			(start 9.061704 -5.171694)
			(end 8.474456 -4.608322)
			(stroke
				(width 0.1)
				(type default)
			)
			(layer "F.SilkS")
		)
		(fp_line
			(start 9.061704 -5.171694)
			(end 9.001506 -5.171694)
			(stroke
				(width 0.1)
				(type default)
			)
			(layer "F.SilkS")
		)
		(fp_line
			(start 9.061704 -5.171694)
			(end 9.001506 -5.171694)
			(stroke
				(width 0.1)
				(type default)
			)
			(layer "F.SilkS")
		)
		(fp_line
			(start 9.062466 -1.5367)
			(end 9.050274 -1.467104)
			(stroke
				(width 0.1)
				(type default)
			)
			(layer "F.SilkS")
		)
		(fp_line
			(start 9.062466 -1.5367)
			(end 9.050274 -1.467104)
			(stroke
				(width 0.1)
				(type default)
			)
			(layer "F.SilkS")
		)
		(fp_line
			(start 9.074912 -1.606296)
			(end 9.062466 -1.5367)
			(stroke
				(width 0.1)
				(type default)
			)
			(layer "F.SilkS")
		)
		(fp_line
			(start 9.074912 -1.606296)
			(end 9.062466 -1.5367)
			(stroke
				(width 0.1)
				(type default)
			)
			(layer "F.SilkS")
		)
		(fp_line
			(start 9.087104 -1.675384)
			(end 9.074912 -1.606296)
			(stroke
				(width 0.1)
				(type default)
			)
			(layer "F.SilkS")
		)
		(fp_line
			(start 9.087104 -1.675384)
			(end 9.074912 -1.606296)
			(stroke
				(width 0.1)
				(type default)
			)
			(layer "F.SilkS")
		)
		(fp_line
			(start 9.099042 -1.744726)
			(end 9.087104 -1.675384)
			(stroke
				(width 0.1)
				(type default)
			)
			(layer "F.SilkS")
		)
		(fp_line
			(start 9.099042 -1.744726)
			(end 9.087104 -1.675384)
			(stroke
				(width 0.1)
				(type default)
			)
			(layer "F.SilkS")
		)
		(fp_line
			(start 9.111234 -1.814322)
			(end 9.099042 -1.744726)
			(stroke
				(width 0.1)
				(type default)
			)
			(layer "F.SilkS")
		)
		(fp_line
			(start 9.111234 -1.814322)
			(end 9.099042 -1.744726)
			(stroke
				(width 0.1)
				(type default)
			)
			(layer "F.SilkS")
		)
		(fp_line
			(start 9.121902 -5.171694)
			(end 8.462264 -4.53898)
			(stroke
				(width 0.1)
				(type default)
			)
			(layer "F.SilkS")
		)
		(fp_line
			(start 9.121902 -5.171694)
			(end 8.462264 -4.53898)
			(stroke
				(width 0.1)
				(type default)
			)
			(layer "F.SilkS")
		)
		(fp_line
			(start 9.121902 -5.171694)
			(end 9.061704 -5.171694)
			(stroke
				(width 0.1)
				(type default)
			)
			(layer "F.SilkS")
		)
		(fp_line
			(start 9.121902 -5.171694)
			(end 9.061704 -5.171694)
			(stroke
				(width 0.1)
				(type default)
			)
			(layer "F.SilkS")
		)
		(fp_line
			(start 9.12368 -1.883664)
			(end 9.111234 -1.814322)
			(stroke
				(width 0.1)
				(type default)
			)
			(layer "F.SilkS")
		)
		(fp_line
			(start 9.12368 -1.883664)
			(end 9.111234 -1.814322)
			(stroke
				(width 0.1)
				(type default)
			)
			(layer "F.SilkS")
		)
		(fp_line
			(start 9.135872 -1.953006)
			(end 9.12368 -1.883664)
			(stroke
				(width 0.1)
				(type default)
			)
			(layer "F.SilkS")
		)
		(fp_line
			(start 9.135872 -1.953006)
			(end 9.12368 -1.883664)
			(stroke
				(width 0.1)
				(type default)
			)
			(layer "F.SilkS")
		)
		(fp_line
			(start 9.148064 -2.022602)
			(end 9.135872 -1.953006)
			(stroke
				(width 0.1)
				(type default)
			)
			(layer "F.SilkS")
		)
		(fp_line
			(start 9.148064 -2.022602)
			(end 9.135872 -1.953006)
			(stroke
				(width 0.1)
				(type default)
			)
			(layer "F.SilkS")
		)
		(fp_line
			(start 9.160002 -2.091944)
			(end 9.148064 -2.022602)
			(stroke
				(width 0.1)
				(type default)
			)
			(layer "F.SilkS")
		)
		(fp_line
			(start 9.160002 -2.091944)
			(end 9.148064 -2.022602)
			(stroke
				(width 0.1)
				(type default)
			)
			(layer "F.SilkS")
		)
		(fp_line
			(start 9.172194 -2.161286)
			(end 9.160002 -2.091944)
			(stroke
				(width 0.1)
				(type default)
			)
			(layer "F.SilkS")
		)
		(fp_line
			(start 9.172194 -2.161286)
			(end 9.160002 -2.091944)
			(stroke
				(width 0.1)
				(type default)
			)
			(layer "F.SilkS")
		)
		(fp_line
			(start 9.172194 -2.161286)
			(end 9.18464 -2.230882)
			(stroke
				(width 0.1)
				(type default)
			)
			(layer "F.SilkS")
		)
		(fp_line
			(start 9.172194 -2.161286)
			(end 9.18464 -2.230882)
			(stroke
				(width 0.1)
				(type default)
			)
			(layer "F.SilkS")
		)
		(fp_line
			(start 9.181846 -5.171694)
			(end 8.450326 -4.469638)
			(stroke
				(width 0.1)
				(type default)
			)
			(layer "F.SilkS")
		)
		(fp_line
			(start 9.181846 -5.171694)
			(end 8.450326 -4.469638)
			(stroke
				(width 0.1)
				(type default)
			)
			(layer "F.SilkS")
		)
		(fp_line
			(start 9.181846 -5.171694)
			(end 9.121902 -5.171694)
			(stroke
				(width 0.1)
				(type default)
			)
			(layer "F.SilkS")
		)
		(fp_line
			(start 9.181846 -5.171694)
			(end 9.121902 -5.171694)
			(stroke
				(width 0.1)
				(type default)
			)
			(layer "F.SilkS")
		)
		(fp_line
			(start 9.18464 -2.230882)
			(end 9.196832 -2.300224)
			(stroke
				(width 0.1)
				(type default)
			)
			(layer "F.SilkS")
		)
		(fp_line
			(start 9.18464 -2.230882)
			(end 9.196832 -2.300224)
			(stroke
				(width 0.1)
				(type default)
			)
			(layer "F.SilkS")
		)
		(fp_line
			(start 9.196832 -2.300224)
			(end 9.209024 -2.369566)
			(stroke
				(width 0.1)
				(type default)
			)
			(layer "F.SilkS")
		)
		(fp_line
			(start 9.196832 -2.300224)
			(end 9.209024 -2.369566)
			(stroke
				(width 0.1)
				(type default)
			)
			(layer "F.SilkS")
		)
		(fp_line
			(start 9.209024 -2.369566)
			(end 9.220962 -2.438908)
			(stroke
				(width 0.1)
				(type default)
			)
			(layer "F.SilkS")
		)
		(fp_line
			(start 9.209024 -2.369566)
			(end 9.220962 -2.438908)
			(stroke
				(width 0.1)
				(type default)
			)
			(layer "F.SilkS")
		)
		(fp_line
			(start 9.220962 -2.438908)
			(end 9.233408 -2.508504)
			(stroke
				(width 0.1)
				(type default)
			)
			(layer "F.SilkS")
		)
		(fp_line
			(start 9.220962 -2.438908)
			(end 9.233408 -2.508504)
			(stroke
				(width 0.1)
				(type default)
			)
			(layer "F.SilkS")
		)
		(fp_line
			(start 9.233408 -2.508504)
			(end 9.2456 -2.577592)
			(stroke
				(width 0.1)
				(type default)
			)
			(layer "F.SilkS")
		)
		(fp_line
			(start 9.233408 -2.508504)
			(end 9.2456 -2.577592)
			(stroke
				(width 0.1)
				(type default)
			)
			(layer "F.SilkS")
		)
		(fp_line
			(start 9.242298 -5.171694)
			(end 8.43788 -4.400296)
			(stroke
				(width 0.1)
				(type default)
			)
			(layer "F.SilkS")
		)
		(fp_line
			(start 9.242298 -5.171694)
			(end 8.43788 -4.400296)
			(stroke
				(width 0.1)
				(type default)
			)
			(layer "F.SilkS")
		)
		(fp_line
			(start 9.242298 -5.171694)
			(end 9.181846 -5.171694)
			(stroke
				(width 0.1)
				(type default)
			)
			(layer "F.SilkS")
		)
		(fp_line
			(start 9.242298 -5.171694)
			(end 9.181846 -5.171694)
			(stroke
				(width 0.1)
				(type default)
			)
			(layer "F.SilkS")
		)
		(fp_line
			(start 9.2456 -2.577592)
			(end 9.257792 -2.647188)
			(stroke
				(width 0.1)
				(type default)
			)
			(layer "F.SilkS")
		)
		(fp_line
			(start 9.2456 -2.577592)
			(end 9.257792 -2.647188)
			(stroke
				(width 0.1)
				(type default)
			)
			(layer "F.SilkS")
		)
		(fp_line
			(start 9.257792 -2.647188)
			(end 9.269984 -2.716784)
			(stroke
				(width 0.1)
				(type default)
			)
			(layer "F.SilkS")
		)
		(fp_line
			(start 9.257792 -2.647188)
			(end 9.269984 -2.716784)
			(stroke
				(width 0.1)
				(type default)
			)
			(layer "F.SilkS")
		)
		(fp_line
			(start 9.269984 -2.716784)
			(end 9.281922 -2.786126)
			(stroke
				(width 0.1)
				(type default)
			)
			(layer "F.SilkS")
		)
		(fp_line
			(start 9.269984 -2.716784)
			(end 9.281922 -2.786126)
			(stroke
				(width 0.1)
				(type default)
			)
			(layer "F.SilkS")
		)
		(fp_line
			(start 9.281922 -2.786126)
			(end 9.294368 -2.855468)
			(stroke
				(width 0.1)
				(type default)
			)
			(layer "F.SilkS")
		)
		(fp_line
			(start 9.281922 -2.786126)
			(end 9.294368 -2.855468)
			(stroke
				(width 0.1)
				(type default)
			)
			(layer "F.SilkS")
		)
		(fp_line
			(start 9.294368 -2.855468)
			(end 9.30656 -2.925064)
			(stroke
				(width 0.1)
				(type default)
			)
			(layer "F.SilkS")
		)
		(fp_line
			(start 9.294368 -2.855468)
			(end 9.30656 -2.925064)
			(stroke
				(width 0.1)
				(type default)
			)
			(layer "F.SilkS")
		)
		(fp_line
			(start 9.302242 -5.171694)
			(end 8.425942 -4.3307)
			(stroke
				(width 0.1)
				(type default)
			)
			(layer "F.SilkS")
		)
		(fp_line
			(start 9.302242 -5.171694)
			(end 8.425942 -4.3307)
			(stroke
				(width 0.1)
				(type default)
			)
			(layer "F.SilkS")
		)
		(fp_line
			(start 9.302242 -5.171694)
			(end 9.242298 -5.171694)
			(stroke
				(width 0.1)
				(type default)
			)
			(layer "F.SilkS")
		)
		(fp_line
			(start 9.302242 -5.171694)
			(end 9.242298 -5.171694)
			(stroke
				(width 0.1)
				(type default)
			)
			(layer "F.SilkS")
		)
		(fp_line
			(start 9.30656 -2.925064)
			(end 9.318752 -2.994406)
			(stroke
				(width 0.1)
				(type default)
			)
			(layer "F.SilkS")
		)
		(fp_line
			(start 9.30656 -2.925064)
			(end 9.318752 -2.994406)
			(stroke
				(width 0.1)
				(type default)
			)
			(layer "F.SilkS")
		)
		(fp_line
			(start 9.318752 -2.994406)
			(end 9.330944 -3.063748)
			(stroke
				(width 0.1)
				(type default)
			)
			(layer "F.SilkS")
		)
		(fp_line
			(start 9.318752 -2.994406)
			(end 9.330944 -3.063748)
			(stroke
				(width 0.1)
				(type default)
			)
			(layer "F.SilkS")
		)
		(fp_line
			(start 9.330944 -3.063748)
			(end 9.343136 -3.13309)
			(stroke
				(width 0.1)
				(type default)
			)
			(layer "F.SilkS")
		)
		(fp_line
			(start 9.330944 -3.063748)
			(end 9.343136 -3.13309)
			(stroke
				(width 0.1)
				(type default)
			)
			(layer "F.SilkS")
		)
		(fp_line
			(start 9.343136 -3.13309)
			(end 9.355328 -3.202432)
			(stroke
				(width 0.1)
				(type default)
			)
			(layer "F.SilkS")
		)
		(fp_line
			(start 9.343136 -3.13309)
			(end 9.355328 -3.202432)
			(stroke
				(width 0.1)
				(type default)
			)
			(layer "F.SilkS")
		)
		(fp_line
			(start 9.355328 -3.202432)
			(end 9.36752 -3.272028)
			(stroke
				(width 0.1)
				(type default)
			)
			(layer "F.SilkS")
		)
		(fp_line
			(start 9.355328 -3.202432)
			(end 9.36752 -3.272028)
			(stroke
				(width 0.1)
				(type default)
			)
			(layer "F.SilkS")
		)
		(fp_line
			(start 9.36244 -5.171694)
			(end 8.41375 -4.261612)
			(stroke
				(width 0.1)
				(type default)
			)
			(layer "F.SilkS")
		)
		(fp_line
			(start 9.36244 -5.171694)
			(end 8.41375 -4.261612)
			(stroke
				(width 0.1)
				(type default)
			)
			(layer "F.SilkS")
		)
		(fp_line
			(start 9.36244 -5.171694)
			(end 9.302242 -5.171694)
			(stroke
				(width 0.1)
				(type default)
			)
			(layer "F.SilkS")
		)
		(fp_line
			(start 9.36244 -5.171694)
			(end 9.302242 -5.171694)
			(stroke
				(width 0.1)
				(type default)
			)
			(layer "F.SilkS")
		)
		(fp_line
			(start 9.36752 -3.272028)
			(end 9.379712 -3.34137)
			(stroke
				(width 0.1)
				(type default)
			)
			(layer "F.SilkS")
		)
		(fp_line
			(start 9.36752 -3.272028)
			(end 9.379712 -3.34137)
			(stroke
				(width 0.1)
				(type default)
			)
			(layer "F.SilkS")
		)
		(fp_line
			(start 9.379712 -3.34137)
			(end 9.391904 -3.410712)
			(stroke
				(width 0.1)
				(type default)
			)
			(layer "F.SilkS")
		)
		(fp_line
			(start 9.379712 -3.34137)
			(end 9.391904 -3.410712)
			(stroke
				(width 0.1)
				(type default)
			)
			(layer "F.SilkS")
		)
		(fp_line
			(start 9.404096 -3.480054)
			(end 9.391904 -3.410712)
			(stroke
				(width 0.1)
				(type default)
			)
			(layer "F.SilkS")
		)
		(fp_line
			(start 9.404096 -3.480054)
			(end 9.391904 -3.410712)
			(stroke
				(width 0.1)
				(type default)
			)
			(layer "F.SilkS")
		)
		(fp_line
			(start 9.416288 -3.54965)
			(end 6.565392 -0.815086)
			(stroke
				(width 0.1)
				(type default)
			)
			(layer "F.SilkS")
		)
		(fp_line
			(start 9.416288 -3.54965)
			(end 6.565392 -0.815086)
			(stroke
				(width 0.1)
				(type default)
			)
			(layer "F.SilkS")
		)
		(fp_line
			(start 9.416288 -3.54965)
			(end 9.404096 -3.480054)
			(stroke
				(width 0.1)
				(type default)
			)
			(layer "F.SilkS")
		)
		(fp_line
			(start 9.416288 -3.54965)
			(end 9.404096 -3.480054)
			(stroke
				(width 0.1)
				(type default)
			)
			(layer "F.SilkS")
		)
		(fp_line
			(start 9.416288 -3.54965)
			(end 9.42848 -3.618992)
			(stroke
				(width 0.1)
				(type default)
			)
			(layer "F.SilkS")
		)
		(fp_line
			(start 9.416288 -3.54965)
			(end 9.42848 -3.618992)
			(stroke
				(width 0.1)
				(type default)
			)
			(layer "F.SilkS")
		)
		(fp_line
			(start 9.422638 -5.171694)
			(end 8.401558 -4.19227)
			(stroke
				(width 0.1)
				(type default)
			)
			(layer "F.SilkS")
		)
		(fp_line
			(start 9.422638 -5.171694)
			(end 8.401558 -4.19227)
			(stroke
				(width 0.1)
				(type default)
			)
			(layer "F.SilkS")
		)
		(fp_line
			(start 9.422638 -5.171694)
			(end 9.36244 -5.171694)
			(stroke
				(width 0.1)
				(type default)
			)
			(layer "F.SilkS")
		)
		(fp_line
			(start 9.422638 -5.171694)
			(end 9.36244 -5.171694)
			(stroke
				(width 0.1)
				(type default)
			)
			(layer "F.SilkS")
		)
		(fp_line
			(start 9.42848 -3.618992)
			(end 9.440672 -3.688334)
			(stroke
				(width 0.1)
				(type default)
			)
			(layer "F.SilkS")
		)
		(fp_line
			(start 9.42848 -3.618992)
			(end 9.440672 -3.688334)
			(stroke
				(width 0.1)
				(type default)
			)
			(layer "F.SilkS")
		)
		(fp_line
			(start 9.440672 -3.688334)
			(end 9.452864 -3.75793)
			(stroke
				(width 0.1)
				(type default)
			)
			(layer "F.SilkS")
		)
		(fp_line
			(start 9.440672 -3.688334)
			(end 9.452864 -3.75793)
			(stroke
				(width 0.1)
				(type default)
			)
			(layer "F.SilkS")
		)
		(fp_line
			(start 9.465056 -3.827526)
			(end 9.452864 -3.75793)
			(stroke
				(width 0.1)
				(type default)
			)
			(layer "F.SilkS")
		)
		(fp_line
			(start 9.465056 -3.827526)
			(end 9.452864 -3.75793)
			(stroke
				(width 0.1)
				(type default)
			)
			(layer "F.SilkS")
		)
		(fp_line
			(start 9.465056 -3.827526)
			(end 9.477248 -3.896614)
			(stroke
				(width 0.1)
				(type default)
			)
			(layer "F.SilkS")
		)
		(fp_line
			(start 9.465056 -3.827526)
			(end 9.477248 -3.896614)
			(stroke
				(width 0.1)
				(type default)
			)
			(layer "F.SilkS")
		)
		(fp_line
			(start 9.477248 -3.896614)
			(end 8.107172 -2.582418)
			(stroke
				(width 0.1)
				(type default)
			)
			(layer "F.SilkS")
		)
		(fp_line
			(start 9.477248 -3.896614)
			(end 8.107172 -2.582418)
			(stroke
				(width 0.1)
				(type default)
			)
			(layer "F.SilkS")
		)
		(fp_line
			(start 9.477248 -3.896614)
			(end 9.48944 -3.965956)
			(stroke
				(width 0.1)
				(type default)
			)
			(layer "F.SilkS")
		)
		(fp_line
			(start 9.477248 -3.896614)
			(end 9.48944 -3.965956)
			(stroke
				(width 0.1)
				(type default)
			)
			(layer "F.SilkS")
		)
		(fp_line
			(start 9.482836 -5.171694)
			(end 8.389366 -4.122674)
			(stroke
				(width 0.1)
				(type default)
			)
			(layer "F.SilkS")
		)
		(fp_line
			(start 9.482836 -5.171694)
			(end 8.389366 -4.122674)
			(stroke
				(width 0.1)
				(type default)
			)
			(layer "F.SilkS")
		)
		(fp_line
			(start 9.482836 -5.171694)
			(end 9.422638 -5.171694)
			(stroke
				(width 0.1)
				(type default)
			)
			(layer "F.SilkS")
		)
		(fp_line
			(start 9.482836 -5.171694)
			(end 9.422638 -5.171694)
			(stroke
				(width 0.1)
				(type default)
			)
			(layer "F.SilkS")
		)
		(fp_line
			(start 9.48944 -3.965956)
			(end 8.123682 -2.655824)
			(stroke
				(width 0.1)
				(type default)
			)
			(layer "F.SilkS")
		)
		(fp_line
			(start 9.48944 -3.965956)
			(end 8.123682 -2.655824)
			(stroke
				(width 0.1)
				(type default)
			)
			(layer "F.SilkS")
		)
		(fp_line
			(start 9.48944 -3.965956)
			(end 9.501632 -4.035552)
			(stroke
				(width 0.1)
				(type default)
			)
			(layer "F.SilkS")
		)
		(fp_line
			(start 9.48944 -3.965956)
			(end 9.501632 -4.035552)
			(stroke
				(width 0.1)
				(type default)
			)
			(layer "F.SilkS")
		)
		(fp_line
			(start 9.501632 -4.035552)
			(end 8.140446 -2.729738)
			(stroke
				(width 0.1)
				(type default)
			)
			(layer "F.SilkS")
		)
		(fp_line
			(start 9.501632 -4.035552)
			(end 8.140446 -2.729738)
			(stroke
				(width 0.1)
				(type default)
			)
			(layer "F.SilkS")
		)
		(fp_line
			(start 9.501632 -4.035552)
			(end 9.513824 -4.104894)
			(stroke
				(width 0.1)
				(type default)
			)
			(layer "F.SilkS")
		)
		(fp_line
			(start 9.501632 -4.035552)
			(end 9.513824 -4.104894)
			(stroke
				(width 0.1)
				(type default)
			)
			(layer "F.SilkS")
		)
		(fp_line
			(start 9.513824 -4.104894)
			(end 8.156956 -2.803398)
			(stroke
				(width 0.1)
				(type default)
			)
			(layer "F.SilkS")
		)
		(fp_line
			(start 9.513824 -4.104894)
			(end 8.156956 -2.803398)
			(stroke
				(width 0.1)
				(type default)
			)
			(layer "F.SilkS")
		)
		(fp_line
			(start 9.513824 -4.104894)
			(end 9.526016 -4.174236)
			(stroke
				(width 0.1)
				(type default)
			)
			(layer "F.SilkS")
		)
		(fp_line
			(start 9.513824 -4.104894)
			(end 9.526016 -4.174236)
			(stroke
				(width 0.1)
				(type default)
			)
			(layer "F.SilkS")
		)
		(fp_line
			(start 9.526016 -4.174236)
			(end 8.170418 -2.87401)
			(stroke
				(width 0.1)
				(type default)
			)
			(layer "F.SilkS")
		)
		(fp_line
			(start 9.526016 -4.174236)
			(end 8.170418 -2.87401)
			(stroke
				(width 0.1)
				(type default)
			)
			(layer "F.SilkS")
		)
		(fp_line
			(start 9.526016 -4.174236)
			(end 9.538208 -4.243578)
			(stroke
				(width 0.1)
				(type default)
			)
			(layer "F.SilkS")
		)
		(fp_line
			(start 9.526016 -4.174236)
			(end 9.538208 -4.243578)
			(stroke
				(width 0.1)
				(type default)
			)
			(layer "F.SilkS")
		)
		(fp_line
			(start 9.538208 -4.243578)
			(end 8.18261 -2.943352)
			(stroke
				(width 0.1)
				(type default)
			)
			(layer "F.SilkS")
		)
		(fp_line
			(start 9.538208 -4.243578)
			(end 8.18261 -2.943352)
			(stroke
				(width 0.1)
				(type default)
			)
			(layer "F.SilkS")
		)
		(fp_line
			(start 9.538208 -4.243578)
			(end 9.5504 -4.313174)
			(stroke
				(width 0.1)
				(type default)
			)
			(layer "F.SilkS")
		)
		(fp_line
			(start 9.538208 -4.243578)
			(end 9.5504 -4.313174)
			(stroke
				(width 0.1)
				(type default)
			)
			(layer "F.SilkS")
		)
		(fp_line
			(start 9.543034 -5.171694)
			(end 8.377174 -4.053332)
			(stroke
				(width 0.1)
				(type default)
			)
			(layer "F.SilkS")
		)
		(fp_line
			(start 9.543034 -5.171694)
			(end 8.377174 -4.053332)
			(stroke
				(width 0.1)
				(type default)
			)
			(layer "F.SilkS")
		)
		(fp_line
			(start 9.543034 -5.171694)
			(end 9.482836 -5.171694)
			(stroke
				(width 0.1)
				(type default)
			)
			(layer "F.SilkS")
		)
		(fp_line
			(start 9.543034 -5.171694)
			(end 9.482836 -5.171694)
			(stroke
				(width 0.1)
				(type default)
			)
			(layer "F.SilkS")
		)
		(fp_line
			(start 9.5504 -4.313174)
			(end 8.194802 -3.012694)
			(stroke
				(width 0.1)
				(type default)
			)
			(layer "F.SilkS")
		)
		(fp_line
			(start 9.5504 -4.313174)
			(end 8.194802 -3.012694)
			(stroke
				(width 0.1)
				(type default)
			)
			(layer "F.SilkS")
		)
		(fp_line
			(start 9.5504 -4.313174)
			(end 9.562592 -4.382516)
			(stroke
				(width 0.1)
				(type default)
			)
			(layer "F.SilkS")
		)
		(fp_line
			(start 9.5504 -4.313174)
			(end 9.562592 -4.382516)
			(stroke
				(width 0.1)
				(type default)
			)
			(layer "F.SilkS")
		)
		(fp_line
			(start 9.562592 -4.382516)
			(end 8.206994 -3.08229)
			(stroke
				(width 0.1)
				(type default)
			)
			(layer "F.SilkS")
		)
		(fp_line
			(start 9.562592 -4.382516)
			(end 8.206994 -3.08229)
			(stroke
				(width 0.1)
				(type default)
			)
			(layer "F.SilkS")
		)
		(fp_line
			(start 9.562592 -4.382516)
			(end 9.574784 -4.452112)
			(stroke
				(width 0.1)
				(type default)
			)
			(layer "F.SilkS")
		)
		(fp_line
			(start 9.562592 -4.382516)
			(end 9.574784 -4.452112)
			(stroke
				(width 0.1)
				(type default)
			)
			(layer "F.SilkS")
		)
		(fp_line
			(start 9.574784 -4.452112)
			(end 8.219186 -3.151378)
			(stroke
				(width 0.1)
				(type default)
			)
			(layer "F.SilkS")
		)
		(fp_line
			(start 9.574784 -4.452112)
			(end 8.219186 -3.151378)
			(stroke
				(width 0.1)
				(type default)
			)
			(layer "F.SilkS")
		)
		(fp_line
			(start 9.574784 -4.452112)
			(end 9.586976 -4.5212)
			(stroke
				(width 0.1)
				(type default)
			)
			(layer "F.SilkS")
		)
		(fp_line
			(start 9.574784 -4.452112)
			(end 9.586976 -4.5212)
			(stroke
				(width 0.1)
				(type default)
			)
			(layer "F.SilkS")
		)
		(fp_line
			(start 9.586976 -4.5212)
			(end 8.231378 -3.22072)
			(stroke
				(width 0.1)
				(type default)
			)
			(layer "F.SilkS")
		)
		(fp_line
			(start 9.586976 -4.5212)
			(end 8.231378 -3.22072)
			(stroke
				(width 0.1)
				(type default)
			)
			(layer "F.SilkS")
		)
		(fp_line
			(start 9.586976 -4.5212)
			(end 9.599168 -4.590796)
			(stroke
				(width 0.1)
				(type default)
			)
			(layer "F.SilkS")
		)
		(fp_line
			(start 9.586976 -4.5212)
			(end 9.599168 -4.590796)
			(stroke
				(width 0.1)
				(type default)
			)
			(layer "F.SilkS")
		)
		(fp_line
			(start 9.599168 -4.590796)
			(end 8.24357 -3.290316)
			(stroke
				(width 0.1)
				(type default)
			)
			(layer "F.SilkS")
		)
		(fp_line
			(start 9.599168 -4.590796)
			(end 8.24357 -3.290316)
			(stroke
				(width 0.1)
				(type default)
			)
			(layer "F.SilkS")
		)
		(fp_line
			(start 9.599168 -4.590796)
			(end 9.61136 -4.660138)
			(stroke
				(width 0.1)
				(type default)
			)
			(layer "F.SilkS")
		)
		(fp_line
			(start 9.599168 -4.590796)
			(end 9.61136 -4.660138)
			(stroke
				(width 0.1)
				(type default)
			)
			(layer "F.SilkS")
		)
		(fp_line
			(start 9.603232 -5.171694)
			(end 8.365236 -3.98399)
			(stroke
				(width 0.1)
				(type default)
			)
			(layer "F.SilkS")
		)
		(fp_line
			(start 9.603232 -5.171694)
			(end 8.365236 -3.98399)
			(stroke
				(width 0.1)
				(type default)
			)
			(layer "F.SilkS")
		)
		(fp_line
			(start 9.603232 -5.171694)
			(end 9.543034 -5.171694)
			(stroke
				(width 0.1)
				(type default)
			)
			(layer "F.SilkS")
		)
		(fp_line
			(start 9.603232 -5.171694)
			(end 9.543034 -5.171694)
			(stroke
				(width 0.1)
				(type default)
			)
			(layer "F.SilkS")
		)
		(fp_line
			(start 9.61136 -4.660138)
			(end 8.255762 -3.359658)
			(stroke
				(width 0.1)
				(type default)
			)
			(layer "F.SilkS")
		)
		(fp_line
			(start 9.61136 -4.660138)
			(end 8.255762 -3.359658)
			(stroke
				(width 0.1)
				(type default)
			)
			(layer "F.SilkS")
		)
		(fp_line
			(start 9.61136 -4.660138)
			(end 9.623552 -4.729734)
			(stroke
				(width 0.1)
				(type default)
			)
			(layer "F.SilkS")
		)
		(fp_line
			(start 9.61136 -4.660138)
			(end 9.623552 -4.729734)
			(stroke
				(width 0.1)
				(type default)
			)
			(layer "F.SilkS")
		)
		(fp_line
			(start 9.623552 -4.729734)
			(end 8.2677 -3.429)
			(stroke
				(width 0.1)
				(type default)
			)
			(layer "F.SilkS")
		)
		(fp_line
			(start 9.623552 -4.729734)
			(end 8.2677 -3.429)
			(stroke
				(width 0.1)
				(type default)
			)
			(layer "F.SilkS")
		)
		(fp_line
			(start 9.623552 -4.729734)
			(end 9.635744 -4.798822)
			(stroke
				(width 0.1)
				(type default)
			)
			(layer "F.SilkS")
		)
		(fp_line
			(start 9.623552 -4.729734)
			(end 9.635744 -4.798822)
			(stroke
				(width 0.1)
				(type default)
			)
			(layer "F.SilkS")
		)
		(fp_line
			(start 9.635744 -4.798822)
			(end 8.279892 -3.498342)
			(stroke
				(width 0.1)
				(type default)
			)
			(layer "F.SilkS")
		)
		(fp_line
			(start 9.635744 -4.798822)
			(end 8.279892 -3.498342)
			(stroke
				(width 0.1)
				(type default)
			)
			(layer "F.SilkS")
		)
		(fp_line
			(start 9.635744 -4.798822)
			(end 9.64819 -4.868418)
			(stroke
				(width 0.1)
				(type default)
			)
			(layer "F.SilkS")
		)
		(fp_line
			(start 9.635744 -4.798822)
			(end 9.64819 -4.868418)
			(stroke
				(width 0.1)
				(type default)
			)
			(layer "F.SilkS")
		)
		(fp_line
			(start 9.64819 -4.868418)
			(end 8.292084 -3.567684)
			(stroke
				(width 0.1)
				(type default)
			)
			(layer "F.SilkS")
		)
		(fp_line
			(start 9.64819 -4.868418)
			(end 8.292084 -3.567684)
			(stroke
				(width 0.1)
				(type default)
			)
			(layer "F.SilkS")
		)
		(fp_line
			(start 9.64819 -4.868418)
			(end 9.660382 -4.938014)
			(stroke
				(width 0.1)
				(type default)
			)
			(layer "F.SilkS")
		)
		(fp_line
			(start 9.64819 -4.868418)
			(end 9.660382 -4.938014)
			(stroke
				(width 0.1)
				(type default)
			)
			(layer "F.SilkS")
		)
		(fp_line
			(start 9.660382 -4.938014)
			(end 8.304276 -3.63728)
			(stroke
				(width 0.1)
				(type default)
			)
			(layer "F.SilkS")
		)
		(fp_line
			(start 9.660382 -4.938014)
			(end 8.304276 -3.63728)
			(stroke
				(width 0.1)
				(type default)
			)
			(layer "F.SilkS")
		)
		(fp_line
			(start 9.660382 -4.938014)
			(end 9.67232 -5.007356)
			(stroke
				(width 0.1)
				(type default)
			)
			(layer "F.SilkS")
		)
		(fp_line
			(start 9.660382 -4.938014)
			(end 9.67232 -5.007356)
			(stroke
				(width 0.1)
				(type default)
			)
			(layer "F.SilkS")
		)
		(fp_line
			(start 9.663176 -5.171694)
			(end 8.35279 -3.914648)
			(stroke
				(width 0.1)
				(type default)
			)
			(layer "F.SilkS")
		)
		(fp_line
			(start 9.663176 -5.171694)
			(end 8.35279 -3.914648)
			(stroke
				(width 0.1)
				(type default)
			)
			(layer "F.SilkS")
		)
		(fp_line
			(start 9.663176 -5.171694)
			(end 9.603232 -5.171694)
			(stroke
				(width 0.1)
				(type default)
			)
			(layer "F.SilkS")
		)
		(fp_line
			(start 9.663176 -5.171694)
			(end 9.603232 -5.171694)
			(stroke
				(width 0.1)
				(type default)
			)
			(layer "F.SilkS")
		)
		(fp_line
			(start 9.67232 -5.007356)
			(end 8.316468 -3.706368)
			(stroke
				(width 0.1)
				(type default)
			)
			(layer "F.SilkS")
		)
		(fp_line
			(start 9.67232 -5.007356)
			(end 8.316468 -3.706368)
			(stroke
				(width 0.1)
				(type default)
			)
			(layer "F.SilkS")
		)
		(fp_line
			(start 9.67232 -5.007356)
			(end 9.684512 -5.076698)
			(stroke
				(width 0.1)
				(type default)
			)
			(layer "F.SilkS")
		)
		(fp_line
			(start 9.67232 -5.007356)
			(end 9.684512 -5.076698)
			(stroke
				(width 0.1)
				(type default)
			)
			(layer "F.SilkS")
		)
		(fp_line
			(start 9.684512 -5.076698)
			(end 8.32866 -3.77571)
			(stroke
				(width 0.1)
				(type default)
			)
			(layer "F.SilkS")
		)
		(fp_line
			(start 9.684512 -5.076698)
			(end 8.32866 -3.77571)
			(stroke
				(width 0.1)
				(type default)
			)
			(layer "F.SilkS")
		)
		(fp_line
			(start 9.684512 -5.076698)
			(end 9.696704 -5.14604)
			(stroke
				(width 0.1)
				(type default)
			)
			(layer "F.SilkS")
		)
		(fp_line
			(start 9.684512 -5.076698)
			(end 9.696704 -5.14604)
			(stroke
				(width 0.1)
				(type default)
			)
			(layer "F.SilkS")
		)
		(fp_line
			(start 9.696704 -5.14604)
			(end 8.340852 -3.845306)
			(stroke
				(width 0.1)
				(type default)
			)
			(layer "F.SilkS")
		)
		(fp_line
			(start 9.696704 -5.14604)
			(end 8.340852 -3.845306)
			(stroke
				(width 0.1)
				(type default)
			)
			(layer "F.SilkS")
		)
		(fp_line
			(start 9.696704 -5.14604)
			(end 9.701276 -5.171694)
			(stroke
				(width 0.1)
				(type default)
			)
			(layer "F.SilkS")
		)
		(fp_line
			(start 9.696704 -5.14604)
			(end 9.701276 -5.171694)
			(stroke
				(width 0.1)
				(type default)
			)
			(layer "F.SilkS")
		)
		(fp_line
			(start 9.701276 -5.171694)
			(end 9.663176 -5.171694)
			(stroke
				(width 0.1)
				(type default)
			)
			(layer "F.SilkS")
		)
		(fp_line
			(start 9.701276 -5.171694)
			(end 9.663176 -5.171694)
			(stroke
				(width 0.1)
				(type default)
			)
			(layer "F.SilkS")
		)
		(fp_line
			(start 9.754616 -1.96977)
			(end 11.590528 -3.730752)
			(stroke
				(width 0.1)
				(type default)
			)
			(layer "F.SilkS")
		)
		(fp_line
			(start 9.754616 -1.96977)
			(end 11.590528 -3.730752)
			(stroke
				(width 0.1)
				(type default)
			)
			(layer "F.SilkS")
		)
		(fp_line
			(start 9.75614 -2.028698)
			(end 11.526012 -3.726688)
			(stroke
				(width 0.1)
				(type default)
			)
			(layer "F.SilkS")
		)
		(fp_line
			(start 9.75614 -2.028698)
			(end 11.526012 -3.726688)
			(stroke
				(width 0.1)
				(type default)
			)
			(layer "F.SilkS")
		)
		(fp_line
			(start 9.75741 -2.08788)
			(end 11.46175 -3.722878)
			(stroke
				(width 0.1)
				(type default)
			)
			(layer "F.SilkS")
		)
		(fp_line
			(start 9.75741 -2.08788)
			(end 11.46175 -3.722878)
			(stroke
				(width 0.1)
				(type default)
			)
			(layer "F.SilkS")
		)
		(fp_line
			(start 9.758172 -1.915414)
			(end 11.65479 -3.734816)
			(stroke
				(width 0.1)
				(type default)
			)
			(layer "F.SilkS")
		)
		(fp_line
			(start 9.758172 -1.915414)
			(end 11.65479 -3.734816)
			(stroke
				(width 0.1)
				(type default)
			)
			(layer "F.SilkS")
		)
		(fp_line
			(start 9.760458 -2.148332)
			(end 11.394694 -3.71602)
			(stroke
				(width 0.1)
				(type default)
			)
			(layer "F.SilkS")
		)
		(fp_line
			(start 9.760458 -2.148332)
			(end 11.394694 -3.71602)
			(stroke
				(width 0.1)
				(type default)
			)
			(layer "F.SilkS")
		)
		(fp_line
			(start 9.762998 -1.862074)
			(end 11.719052 -3.738626)
			(stroke
				(width 0.1)
				(type default)
			)
			(layer "F.SilkS")
		)
		(fp_line
			(start 9.762998 -1.862074)
			(end 11.719052 -3.738626)
			(stroke
				(width 0.1)
				(type default)
			)
			(layer "F.SilkS")
		)
		(fp_line
			(start 9.76757 -1.808988)
			(end 11.782044 -3.74142)
			(stroke
				(width 0.1)
				(type default)
			)
			(layer "F.SilkS")
		)
		(fp_line
			(start 9.76757 -1.808988)
			(end 11.782044 -3.74142)
			(stroke
				(width 0.1)
				(type default)
			)
			(layer "F.SilkS")
		)
		(fp_line
			(start 9.768586 -2.214118)
			(end 11.319002 -3.701288)
			(stroke
				(width 0.1)
				(type default)
			)
			(layer "F.SilkS")
		)
		(fp_line
			(start 9.768586 -2.214118)
			(end 11.319002 -3.701288)
			(stroke
				(width 0.1)
				(type default)
			)
			(layer "F.SilkS")
		)
		(fp_line
			(start 9.77646 -1.759712)
			(end 11.83894 -3.738372)
			(stroke
				(width 0.1)
				(type default)
			)
			(layer "F.SilkS")
		)
		(fp_line
			(start 9.77646 -1.759712)
			(end 11.83894 -3.738372)
			(stroke
				(width 0.1)
				(type default)
			)
			(layer "F.SilkS")
		)
		(fp_line
			(start 9.777222 -2.279904)
			(end 11.24331 -3.686556)
			(stroke
				(width 0.1)
				(type default)
			)
			(layer "F.SilkS")
		)
		(fp_line
			(start 9.777222 -2.279904)
			(end 11.24331 -3.686556)
			(stroke
				(width 0.1)
				(type default)
			)
			(layer "F.SilkS")
		)
		(fp_line
			(start 9.78662 -1.711706)
			(end 11.89609 -3.735324)
			(stroke
				(width 0.1)
				(type default)
			)
			(layer "F.SilkS")
		)
		(fp_line
			(start 9.78662 -1.711706)
			(end 11.89609 -3.735324)
			(stroke
				(width 0.1)
				(type default)
			)
			(layer "F.SilkS")
		)
		(fp_line
			(start 9.79043 -2.350262)
			(end 11.167872 -3.67157)
			(stroke
				(width 0.1)
				(type default)
			)
			(layer "F.SilkS")
		)
		(fp_line
			(start 9.79043 -2.350262)
			(end 11.167872 -3.67157)
			(stroke
				(width 0.1)
				(type default)
			)
			(layer "F.SilkS")
		)
		(fp_line
			(start 9.797034 -1.663954)
			(end 11.952986 -3.732276)
			(stroke
				(width 0.1)
				(type default)
			)
			(layer "F.SilkS")
		)
		(fp_line
			(start 9.797034 -1.663954)
			(end 11.952986 -3.732276)
			(stroke
				(width 0.1)
				(type default)
			)
			(layer "F.SilkS")
		)
		(fp_line
			(start 9.809988 -1.618742)
			(end 12.010136 -3.729482)
			(stroke
				(width 0.1)
				(type default)
			)
			(layer "F.SilkS")
		)
		(fp_line
			(start 9.809988 -1.618742)
			(end 12.010136 -3.729482)
			(stroke
				(width 0.1)
				(type default)
			)
			(layer "F.SilkS")
		)
		(fp_line
			(start 9.812528 -2.429256)
			(end 11.09218 -3.656838)
			(stroke
				(width 0.1)
				(type default)
			)
			(layer "F.SilkS")
		)
		(fp_line
			(start 9.812528 -2.429256)
			(end 11.09218 -3.656838)
			(stroke
				(width 0.1)
				(type default)
			)
			(layer "F.SilkS")
		)
		(fp_line
			(start 9.825228 -1.575562)
			(end 12.063984 -3.723132)
			(stroke
				(width 0.1)
				(type default)
			)
			(layer "F.SilkS")
		)
		(fp_line
			(start 9.825228 -1.575562)
			(end 12.063984 -3.723132)
			(stroke
				(width 0.1)
				(type default)
			)
			(layer "F.SilkS")
		)
		(fp_line
			(start 9.834626 -2.507996)
			(end 11.00201 -3.627882)
			(stroke
				(width 0.1)
				(type default)
			)
			(layer "F.SilkS")
		)
		(fp_line
			(start 9.834626 -2.507996)
			(end 11.00201 -3.627882)
			(stroke
				(width 0.1)
				(type default)
			)
			(layer "F.SilkS")
		)
		(fp_line
			(start 9.840214 -1.532382)
			(end 12.115038 -3.714496)
			(stroke
				(width 0.1)
				(type default)
			)
			(layer "F.SilkS")
		)
		(fp_line
			(start 9.840214 -1.532382)
			(end 12.115038 -3.714496)
			(stroke
				(width 0.1)
				(type default)
			)
			(layer "F.SilkS")
		)
		(fp_line
			(start 9.856978 -2.587244)
			(end 10.90676 -3.594354)
			(stroke
				(width 0.1)
				(type default)
			)
			(layer "F.SilkS")
		)
		(fp_line
			(start 9.856978 -2.587244)
			(end 10.90676 -3.594354)
			(stroke
				(width 0.1)
				(type default)
			)
			(layer "F.SilkS")
		)
		(fp_line
			(start 9.857232 -1.49098)
			(end 12.165838 -3.705352)
			(stroke
				(width 0.1)
				(type default)
			)
			(layer "F.SilkS")
		)
		(fp_line
			(start 9.857232 -1.49098)
			(end 12.165838 -3.705352)
			(stroke
				(width 0.1)
				(type default)
			)
			(layer "F.SilkS")
		)
		(fp_line
			(start 9.87679 -1.452118)
			(end 10.97661 -2.50698)
			(stroke
				(width 0.1)
				(type default)
			)
			(layer "F.SilkS")
		)
		(fp_line
			(start 9.87679 -1.452118)
			(end 10.97661 -2.50698)
			(stroke
				(width 0.1)
				(type default)
			)
			(layer "F.SilkS")
		)
		(fp_line
			(start 9.884664 -2.671572)
			(end 10.811764 -3.560826)
			(stroke
				(width 0.1)
				(type default)
			)
			(layer "F.SilkS")
		)
		(fp_line
			(start 9.884664 -2.671572)
			(end 10.811764 -3.560826)
			(stroke
				(width 0.1)
				(type default)
			)
			(layer "F.SilkS")
		)
		(fp_line
			(start 9.896602 -1.413256)
			(end 10.944606 -2.418588)
			(stroke
				(width 0.1)
				(type default)
			)
			(layer "F.SilkS")
		)
		(fp_line
			(start 9.896602 -1.413256)
			(end 10.944606 -2.418588)
			(stroke
				(width 0.1)
				(type default)
			)
			(layer "F.SilkS")
		)
		(fp_line
			(start 9.916922 -1.375156)
			(end 10.912856 -2.33045)
			(stroke
				(width 0.1)
				(type default)
			)
			(layer "F.SilkS")
		)
		(fp_line
			(start 9.916922 -1.375156)
			(end 10.912856 -2.33045)
			(stroke
				(width 0.1)
				(type default)
			)
			(layer "F.SilkS")
		)
		(fp_line
			(start 9.940798 -1.340358)
			(end 10.903712 -2.263902)
			(stroke
				(width 0.1)
				(type default)
			)
			(layer "F.SilkS")
		)
		(fp_line
			(start 9.940798 -1.340358)
			(end 10.903712 -2.263902)
			(stroke
				(width 0.1)
				(type default)
			)
			(layer "F.SilkS")
		)
		(fp_line
			(start 9.945116 -2.787142)
			(end 10.69721 -3.508502)
			(stroke
				(width 0.1)
				(type default)
			)
			(layer "F.SilkS")
		)
		(fp_line
			(start 9.945116 -2.787142)
			(end 10.69721 -3.508502)
			(stroke
				(width 0.1)
				(type default)
			)
			(layer "F.SilkS")
		)
		(fp_line
			(start 9.964674 -1.30556)
			(end 10.898632 -2.201418)
			(stroke
				(width 0.1)
				(type default)
			)
			(layer "F.SilkS")
		)
		(fp_line
			(start 9.964674 -1.30556)
			(end 10.898632 -2.201418)
			(stroke
				(width 0.1)
				(type default)
			)
			(layer "F.SilkS")
		)
		(fp_line
			(start 9.98855 -1.270508)
			(end 10.902442 -2.147316)
			(stroke
				(width 0.1)
				(type default)
			)
			(layer "F.SilkS")
		)
		(fp_line
			(start 9.98855 -1.270508)
			(end 10.902442 -2.147316)
			(stroke
				(width 0.1)
				(type default)
			)
			(layer "F.SilkS")
		)
		(fp_line
			(start 10.005568 -2.902966)
			(end 10.557002 -3.431794)
			(stroke
				(width 0.1)
				(type default)
			)
			(layer "F.SilkS")
		)
		(fp_line
			(start 10.005568 -2.902966)
			(end 10.557002 -3.431794)
			(stroke
				(width 0.1)
				(type default)
			)
			(layer "F.SilkS")
		)
		(fp_line
			(start 10.015982 -1.239266)
			(end 10.90803 -2.094992)
			(stroke
				(width 0.1)
				(type default)
			)
			(layer "F.SilkS")
		)
		(fp_line
			(start 10.015982 -1.239266)
			(end 10.90803 -2.094992)
			(stroke
				(width 0.1)
				(type default)
			)
			(layer "F.SilkS")
		)
		(fp_line
			(start 10.043668 -1.208278)
			(end 10.921238 -2.04978)
			(stroke
				(width 0.1)
				(type default)
			)
			(layer "F.SilkS")
		)
		(fp_line
			(start 10.043668 -1.208278)
			(end 10.921238 -2.04978)
			(stroke
				(width 0.1)
				(type default)
			)
			(layer "F.SilkS")
		)
		(fp_line
			(start 10.071608 -1.17729)
			(end 10.9347 -2.00533)
			(stroke
				(width 0.1)
				(type default)
			)
			(layer "F.SilkS")
		)
		(fp_line
			(start 10.071608 -1.17729)
			(end 10.9347 -2.00533)
			(stroke
				(width 0.1)
				(type default)
			)
			(layer "F.SilkS")
		)
		(fp_line
			(start 10.102088 -1.148588)
			(end 10.956798 -1.9685)
			(stroke
				(width 0.1)
				(type default)
			)
			(layer "F.SilkS")
		)
		(fp_line
			(start 10.102088 -1.148588)
			(end 10.956798 -1.9685)
			(stroke
				(width 0.1)
				(type default)
			)
			(layer "F.SilkS")
		)
		(fp_line
			(start 10.133584 -1.121156)
			(end 10.978642 -1.931924)
			(stroke
				(width 0.1)
				(type default)
			)
			(layer "F.SilkS")
		)
		(fp_line
			(start 10.133584 -1.121156)
			(end 10.978642 -1.931924)
			(stroke
				(width 0.1)
				(type default)
			)
			(layer "F.SilkS")
		)
		(fp_line
			(start 10.16508 -1.093724)
			(end 11.006582 -1.90119)
			(stroke
				(width 0.1)
				(type default)
			)
			(layer "F.SilkS")
		)
		(fp_line
			(start 10.16508 -1.093724)
			(end 11.006582 -1.90119)
			(stroke
				(width 0.1)
				(type default)
			)
			(layer "F.SilkS")
		)
		(fp_line
			(start 10.198354 -1.067816)
			(end 11.037062 -1.872742)
			(stroke
				(width 0.1)
				(type default)
			)
			(layer "F.SilkS")
		)
		(fp_line
			(start 10.198354 -1.067816)
			(end 11.037062 -1.872742)
			(stroke
				(width 0.1)
				(type default)
			)
			(layer "F.SilkS")
		)
		(fp_line
			(start 10.233406 -1.043686)
			(end 11.06932 -1.845818)
			(stroke
				(width 0.1)
				(type default)
			)
			(layer "F.SilkS")
		)
		(fp_line
			(start 10.233406 -1.043686)
			(end 11.06932 -1.845818)
			(stroke
				(width 0.1)
				(type default)
			)
			(layer "F.SilkS")
		)
		(fp_line
			(start 10.268458 -1.01981)
			(end 11.108182 -1.825244)
			(stroke
				(width 0.1)
				(type default)
			)
			(layer "F.SilkS")
		)
		(fp_line
			(start 10.268458 -1.01981)
			(end 11.108182 -1.825244)
			(stroke
				(width 0.1)
				(type default)
			)
			(layer "F.SilkS")
		)
		(fp_line
			(start 10.30478 -0.99695)
			(end 11.147044 -1.804924)
			(stroke
				(width 0.1)
				(type default)
			)
			(layer "F.SilkS")
		)
		(fp_line
			(start 10.30478 -0.99695)
			(end 11.147044 -1.804924)
			(stroke
				(width 0.1)
				(type default)
			)
			(layer "F.SilkS")
		)
		(fp_line
			(start 10.343388 -0.976122)
			(end 11.190478 -1.788922)
			(stroke
				(width 0.1)
				(type default)
			)
			(layer "F.SilkS")
		)
		(fp_line
			(start 10.343388 -0.976122)
			(end 11.190478 -1.788922)
			(stroke
				(width 0.1)
				(type default)
			)
			(layer "F.SilkS")
		)
		(fp_line
			(start 10.381996 -0.955548)
			(end 11.237722 -1.776476)
			(stroke
				(width 0.1)
				(type default)
			)
			(layer "F.SilkS")
		)
		(fp_line
			(start 10.381996 -0.955548)
			(end 11.237722 -1.776476)
			(stroke
				(width 0.1)
				(type default)
			)
			(layer "F.SilkS")
		)
		(fp_line
			(start 10.421366 -0.935482)
			(end 11.28522 -1.76403)
			(stroke
				(width 0.1)
				(type default)
			)
			(layer "F.SilkS")
		)
		(fp_line
			(start 10.421366 -0.935482)
			(end 11.28522 -1.76403)
			(stroke
				(width 0.1)
				(type default)
			)
			(layer "F.SilkS")
		)
		(fp_line
			(start 10.46353 -0.918464)
			(end 11.33856 -1.75768)
			(stroke
				(width 0.1)
				(type default)
			)
			(layer "F.SilkS")
		)
		(fp_line
			(start 10.46353 -0.918464)
			(end 11.33856 -1.75768)
			(stroke
				(width 0.1)
				(type default)
			)
			(layer "F.SilkS")
		)
		(fp_line
			(start 10.505694 -0.901192)
			(end 11.39444 -1.753616)
			(stroke
				(width 0.1)
				(type default)
			)
			(layer "F.SilkS")
		)
		(fp_line
			(start 10.505694 -0.901192)
			(end 11.39444 -1.753616)
			(stroke
				(width 0.1)
				(type default)
			)
			(layer "F.SilkS")
		)
		(fp_line
			(start 10.548366 -0.884682)
			(end 11.45032 -1.749552)
			(stroke
				(width 0.1)
				(type default)
			)
			(layer "F.SilkS")
		)
		(fp_line
			(start 10.548366 -0.884682)
			(end 11.45032 -1.749552)
			(stroke
				(width 0.1)
				(type default)
			)
			(layer "F.SilkS")
		)
		(fp_line
			(start 10.572496 -4.831842)
			(end 10.566146 -4.825746)
			(stroke
				(width 0.1)
				(type default)
			)
			(layer "F.SilkS")
		)
		(fp_line
			(start 10.572496 -4.831842)
			(end 10.566146 -4.825746)
			(stroke
				(width 0.1)
				(type default)
			)
			(layer "F.SilkS")
		)
		(fp_line
			(start 10.582148 -4.783328)
			(end 10.566146 -4.825746)
			(stroke
				(width 0.1)
				(type default)
			)
			(layer "F.SilkS")
		)
		(fp_line
			(start 10.582148 -4.783328)
			(end 10.566146 -4.825746)
			(stroke
				(width 0.1)
				(type default)
			)
			(layer "F.SilkS")
		)
		(fp_line
			(start 10.59434 -0.870712)
			(end 11.516614 -1.75514)
			(stroke
				(width 0.1)
				(type default)
			)
			(layer "F.SilkS")
		)
		(fp_line
			(start 10.59434 -0.870712)
			(end 11.516614 -1.75514)
			(stroke
				(width 0.1)
				(type default)
			)
			(layer "F.SilkS")
		)
		(fp_line
			(start 10.59815 -4.74091)
			(end 10.582148 -4.783328)
			(stroke
				(width 0.1)
				(type default)
			)
			(layer "F.SilkS")
		)
		(fp_line
			(start 10.59815 -4.74091)
			(end 10.582148 -4.783328)
			(stroke
				(width 0.1)
				(type default)
			)
			(layer "F.SilkS")
		)
		(fp_line
			(start 10.613898 -4.698746)
			(end 10.59815 -4.74091)
			(stroke
				(width 0.1)
				(type default)
			)
			(layer "F.SilkS")
		)
		(fp_line
			(start 10.613898 -4.698746)
			(end 10.59815 -4.74091)
			(stroke
				(width 0.1)
				(type default)
			)
			(layer "F.SilkS")
		)
		(fp_line
			(start 10.613898 -4.698746)
			(end 10.6299 -4.656074)
			(stroke
				(width 0.1)
				(type default)
			)
			(layer "F.SilkS")
		)
		(fp_line
			(start 10.613898 -4.698746)
			(end 10.6299 -4.656074)
			(stroke
				(width 0.1)
				(type default)
			)
			(layer "F.SilkS")
		)
		(fp_line
			(start 10.6299 -4.656074)
			(end 10.645902 -4.613656)
			(stroke
				(width 0.1)
				(type default)
			)
			(layer "F.SilkS")
		)
		(fp_line
			(start 10.6299 -4.656074)
			(end 10.645902 -4.613656)
			(stroke
				(width 0.1)
				(type default)
			)
			(layer "F.SilkS")
		)
		(fp_line
			(start 10.64006 -0.856996)
			(end 11.585448 -1.763522)
			(stroke
				(width 0.1)
				(type default)
			)
			(layer "F.SilkS")
		)
		(fp_line
			(start 10.64006 -0.856996)
			(end 11.585448 -1.763522)
			(stroke
				(width 0.1)
				(type default)
			)
			(layer "F.SilkS")
		)
		(fp_line
			(start 10.645902 -4.613656)
			(end 10.661904 -4.571492)
			(stroke
				(width 0.1)
				(type default)
			)
			(layer "F.SilkS")
		)
		(fp_line
			(start 10.645902 -4.613656)
			(end 10.661904 -4.571492)
			(stroke
				(width 0.1)
				(type default)
			)
			(layer "F.SilkS")
		)
		(fp_line
			(start 10.661904 -4.571492)
			(end 10.677906 -4.529074)
			(stroke
				(width 0.1)
				(type default)
			)
			(layer "F.SilkS")
		)
		(fp_line
			(start 10.661904 -4.571492)
			(end 10.677906 -4.529074)
			(stroke
				(width 0.1)
				(type default)
			)
			(layer "F.SilkS")
		)
		(fp_line
			(start 10.677906 -4.529074)
			(end 10.693908 -4.486402)
			(stroke
				(width 0.1)
				(type default)
			)
			(layer "F.SilkS")
		)
		(fp_line
			(start 10.677906 -4.529074)
			(end 10.693908 -4.486402)
			(stroke
				(width 0.1)
				(type default)
			)
			(layer "F.SilkS")
		)
		(fp_line
			(start 10.686542 -0.843534)
			(end 11.654282 -1.772158)
			(stroke
				(width 0.1)
				(type default)
			)
			(layer "F.SilkS")
		)
		(fp_line
			(start 10.686542 -0.843534)
			(end 11.654282 -1.772158)
			(stroke
				(width 0.1)
				(type default)
			)
			(layer "F.SilkS")
		)
		(fp_line
			(start 10.693908 -4.486402)
			(end 10.709656 -4.443984)
			(stroke
				(width 0.1)
				(type default)
			)
			(layer "F.SilkS")
		)
		(fp_line
			(start 10.693908 -4.486402)
			(end 10.709656 -4.443984)
			(stroke
				(width 0.1)
				(type default)
			)
			(layer "F.SilkS")
		)
		(fp_line
			(start 10.698734 -4.895088)
			(end 10.582148 -4.783328)
			(stroke
				(width 0.1)
				(type default)
			)
			(layer "F.SilkS")
		)
		(fp_line
			(start 10.698734 -4.895088)
			(end 10.582148 -4.783328)
			(stroke
				(width 0.1)
				(type default)
			)
			(layer "F.SilkS")
		)
		(fp_line
			(start 10.709656 -4.443984)
			(end 10.725658 -4.40182)
			(stroke
				(width 0.1)
				(type default)
			)
			(layer "F.SilkS")
		)
		(fp_line
			(start 10.709656 -4.443984)
			(end 10.725658 -4.40182)
			(stroke
				(width 0.1)
				(type default)
			)
			(layer "F.SilkS")
		)
		(fp_line
			(start 10.725658 -4.40182)
			(end 10.74166 -4.359402)
			(stroke
				(width 0.1)
				(type default)
			)
			(layer "F.SilkS")
		)
		(fp_line
			(start 10.725658 -4.40182)
			(end 10.74166 -4.359402)
			(stroke
				(width 0.1)
				(type default)
			)
			(layer "F.SilkS")
		)
		(fp_line
			(start 10.736072 -0.833628)
			(end 11.723116 -1.78054)
			(stroke
				(width 0.1)
				(type default)
			)
			(layer "F.SilkS")
		)
		(fp_line
			(start 10.736072 -0.833628)
			(end 11.723116 -1.78054)
			(stroke
				(width 0.1)
				(type default)
			)
			(layer "F.SilkS")
		)
		(fp_line
			(start 10.74166 -4.359402)
			(end 10.757662 -4.316984)
			(stroke
				(width 0.1)
				(type default)
			)
			(layer "F.SilkS")
		)
		(fp_line
			(start 10.74166 -4.359402)
			(end 10.757662 -4.316984)
			(stroke
				(width 0.1)
				(type default)
			)
			(layer "F.SilkS")
		)
		(fp_line
			(start 10.757662 -4.316984)
			(end 10.773664 -4.274566)
			(stroke
				(width 0.1)
				(type default)
			)
			(layer "F.SilkS")
		)
		(fp_line
			(start 10.757662 -4.316984)
			(end 10.773664 -4.274566)
			(stroke
				(width 0.1)
				(type default)
			)
			(layer "F.SilkS")
		)
		(fp_line
			(start 10.773664 -4.274566)
			(end 10.789666 -4.232148)
			(stroke
				(width 0.1)
				(type default)
			)
			(layer "F.SilkS")
		)
		(fp_line
			(start 10.773664 -4.274566)
			(end 10.789666 -4.232148)
			(stroke
				(width 0.1)
				(type default)
			)
			(layer "F.SilkS")
		)
		(fp_line
			(start 10.785602 -0.823214)
			(end 11.818112 -1.813814)
			(stroke
				(width 0.1)
				(type default)
			)
			(layer "F.SilkS")
		)
		(fp_line
			(start 10.785602 -0.823214)
			(end 11.818112 -1.813814)
			(stroke
				(width 0.1)
				(type default)
			)
			(layer "F.SilkS")
		)
		(fp_line
			(start 10.789666 -4.232148)
			(end 10.805414 -4.18973)
			(stroke
				(width 0.1)
				(type default)
			)
			(layer "F.SilkS")
		)
		(fp_line
			(start 10.789666 -4.232148)
			(end 10.805414 -4.18973)
			(stroke
				(width 0.1)
				(type default)
			)
			(layer "F.SilkS")
		)
		(fp_line
			(start 10.805414 -4.18973)
			(end 10.821416 -4.147312)
			(stroke
				(width 0.1)
				(type default)
			)
			(layer "F.SilkS")
		)
		(fp_line
			(start 10.805414 -4.18973)
			(end 10.821416 -4.147312)
			(stroke
				(width 0.1)
				(type default)
			)
			(layer "F.SilkS")
		)
		(fp_line
			(start 10.818368 -4.952492)
			(end 10.59815 -4.74091)
			(stroke
				(width 0.1)
				(type default)
			)
			(layer "F.SilkS")
		)
		(fp_line
			(start 10.818368 -4.952492)
			(end 10.59815 -4.74091)
			(stroke
				(width 0.1)
				(type default)
			)
			(layer "F.SilkS")
		)
		(fp_line
			(start 10.821416 -4.147312)
			(end 10.837418 -4.104894)
			(stroke
				(width 0.1)
				(type default)
			)
			(layer "F.SilkS")
		)
		(fp_line
			(start 10.821416 -4.147312)
			(end 10.837418 -4.104894)
			(stroke
				(width 0.1)
				(type default)
			)
			(layer "F.SilkS")
		)
		(fp_line
			(start 10.836402 -0.814324)
			(end 11.91514 -1.84912)
			(stroke
				(width 0.1)
				(type default)
			)
			(layer "F.SilkS")
		)
		(fp_line
			(start 10.836402 -0.814324)
			(end 11.91514 -1.84912)
			(stroke
				(width 0.1)
				(type default)
			)
			(layer "F.SilkS")
		)
		(fp_line
			(start 10.837418 -4.104894)
			(end 10.85342 -4.062476)
			(stroke
				(width 0.1)
				(type default)
			)
			(layer "F.SilkS")
		)
		(fp_line
			(start 10.837418 -4.104894)
			(end 10.85342 -4.062476)
			(stroke
				(width 0.1)
				(type default)
			)
			(layer "F.SilkS")
		)
		(fp_line
			(start 10.889742 -0.808228)
			(end 12.047474 -1.918462)
			(stroke
				(width 0.1)
				(type default)
			)
			(layer "F.SilkS")
		)
		(fp_line
			(start 10.889742 -0.808228)
			(end 12.047474 -1.918462)
			(stroke
				(width 0.1)
				(type default)
			)
			(layer "F.SilkS")
		)
		(fp_line
			(start 10.931144 -5.002784)
			(end 10.613898 -4.698746)
			(stroke
				(width 0.1)
				(type default)
			)
			(layer "F.SilkS")
		)
		(fp_line
			(start 10.931144 -5.002784)
			(end 10.613898 -4.698746)
			(stroke
				(width 0.1)
				(type default)
			)
			(layer "F.SilkS")
		)
		(fp_line
			(start 10.99947 -0.797814)
			(end 13.653516 -3.343402)
			(stroke
				(width 0.1)
				(type default)
			)
			(layer "F.SilkS")
		)
		(fp_line
			(start 10.99947 -0.797814)
			(end 13.653516 -3.343402)
			(stroke
				(width 0.1)
				(type default)
			)
			(layer "F.SilkS")
		)
		(fp_line
			(start 11.03503 -5.044694)
			(end 10.6299 -4.656074)
			(stroke
				(width 0.1)
				(type default)
			)
			(layer "F.SilkS")
		)
		(fp_line
			(start 11.03503 -5.044694)
			(end 10.6299 -4.656074)
			(stroke
				(width 0.1)
				(type default)
			)
			(layer "F.SilkS")
		)
		(fp_line
			(start 11.057382 -0.795274)
			(end 13.64107 -3.27406)
			(stroke
				(width 0.1)
				(type default)
			)
			(layer "F.SilkS")
		)
		(fp_line
			(start 11.057382 -0.795274)
			(end 13.64107 -3.27406)
			(stroke
				(width 0.1)
				(type default)
			)
			(layer "F.SilkS")
		)
		(fp_line
			(start 11.11504 -0.792988)
			(end 13.629132 -3.204972)
			(stroke
				(width 0.1)
				(type default)
			)
			(layer "F.SilkS")
		)
		(fp_line
			(start 11.11504 -0.792988)
			(end 13.629132 -3.204972)
			(stroke
				(width 0.1)
				(type default)
			)
			(layer "F.SilkS")
		)
		(fp_line
			(start 11.13536 -5.083048)
			(end 10.645902 -4.613656)
			(stroke
				(width 0.1)
				(type default)
			)
			(layer "F.SilkS")
		)
		(fp_line
			(start 11.13536 -5.083048)
			(end 10.645902 -4.613656)
			(stroke
				(width 0.1)
				(type default)
			)
			(layer "F.SilkS")
		)
		(fp_line
			(start 11.182096 -0.799846)
			(end 13.61694 -3.135376)
			(stroke
				(width 0.1)
				(type default)
			)
			(layer "F.SilkS")
		)
		(fp_line
			(start 11.182096 -0.799846)
			(end 13.61694 -3.135376)
			(stroke
				(width 0.1)
				(type default)
			)
			(layer "F.SilkS")
		)
		(fp_line
			(start 11.226546 -5.11302)
			(end 10.661904 -4.571492)
			(stroke
				(width 0.1)
				(type default)
			)
			(layer "F.SilkS")
		)
		(fp_line
			(start 11.226546 -5.11302)
			(end 10.661904 -4.571492)
			(stroke
				(width 0.1)
				(type default)
			)
			(layer "F.SilkS")
		)
		(fp_line
			(start 11.246612 -2.76606)
			(end 12.216638 -3.696716)
			(stroke
				(width 0.1)
				(type default)
			)
			(layer "F.SilkS")
		)
		(fp_line
			(start 11.246612 -2.76606)
			(end 12.216638 -3.696716)
			(stroke
				(width 0.1)
				(type default)
			)
			(layer "F.SilkS")
		)
		(fp_line
			(start 11.248898 -0.805942)
			(end 13.604494 -3.06578)
			(stroke
				(width 0.1)
				(type default)
			)
			(layer "F.SilkS")
		)
		(fp_line
			(start 11.248898 -0.805942)
			(end 13.604494 -3.06578)
			(stroke
				(width 0.1)
				(type default)
			)
			(layer "F.SilkS")
		)
		(fp_line
			(start 11.315446 -5.140706)
			(end 10.677906 -4.529074)
			(stroke
				(width 0.1)
				(type default)
			)
			(layer "F.SilkS")
		)
		(fp_line
			(start 11.315446 -5.140706)
			(end 10.677906 -4.529074)
			(stroke
				(width 0.1)
				(type default)
			)
			(layer "F.SilkS")
		)
		(fp_line
			(start 11.315954 -0.813054)
			(end 13.592556 -2.996692)
			(stroke
				(width 0.1)
				(type default)
			)
			(layer "F.SilkS")
		)
		(fp_line
			(start 11.315954 -0.813054)
			(end 13.592556 -2.996692)
			(stroke
				(width 0.1)
				(type default)
			)
			(layer "F.SilkS")
		)
		(fp_line
			(start 11.364722 -2.821686)
			(end 12.265914 -3.686302)
			(stroke
				(width 0.1)
				(type default)
			)
			(layer "F.SilkS")
		)
		(fp_line
			(start 11.364722 -2.821686)
			(end 12.265914 -3.686302)
			(stroke
				(width 0.1)
				(type default)
			)
			(layer "F.SilkS")
		)
		(fp_line
			(start 11.382756 -0.81915)
			(end 13.580364 -2.927096)
			(stroke
				(width 0.1)
				(type default)
			)
			(layer "F.SilkS")
		)
		(fp_line
			(start 11.382756 -0.81915)
			(end 13.580364 -2.927096)
			(stroke
				(width 0.1)
				(type default)
			)
			(layer "F.SilkS")
		)
		(fp_line
			(start 11.398758 -5.163058)
			(end 10.693908 -4.486402)
			(stroke
				(width 0.1)
				(type default)
			)
			(layer "F.SilkS")
		)
		(fp_line
			(start 11.398758 -5.163058)
			(end 10.693908 -4.486402)
			(stroke
				(width 0.1)
				(type default)
			)
			(layer "F.SilkS")
		)
		(fp_line
			(start 11.436096 -2.832354)
			(end 12.31138 -3.672078)
			(stroke
				(width 0.1)
				(type default)
			)
			(layer "F.SilkS")
		)
		(fp_line
			(start 11.436096 -2.832354)
			(end 12.31138 -3.672078)
			(stroke
				(width 0.1)
				(type default)
			)
			(layer "F.SilkS")
		)
		(fp_line
			(start 11.460734 -0.836422)
			(end 13.568172 -2.857754)
			(stroke
				(width 0.1)
				(type default)
			)
			(layer "F.SilkS")
		)
		(fp_line
			(start 11.460734 -0.836422)
			(end 13.568172 -2.857754)
			(stroke
				(width 0.1)
				(type default)
			)
			(layer "F.SilkS")
		)
		(fp_line
			(start 11.478514 -5.1816)
			(end 10.709656 -4.443984)
			(stroke
				(width 0.1)
				(type default)
			)
			(layer "F.SilkS")
		)
		(fp_line
			(start 11.478514 -5.1816)
			(end 10.709656 -4.443984)
			(stroke
				(width 0.1)
				(type default)
			)
			(layer "F.SilkS")
		)
		(fp_line
			(start 11.505184 -2.84099)
			(end 12.356592 -3.657854)
			(stroke
				(width 0.1)
				(type default)
			)
			(layer "F.SilkS")
		)
		(fp_line
			(start 11.505184 -2.84099)
			(end 12.356592 -3.657854)
			(stroke
				(width 0.1)
				(type default)
			)
			(layer "F.SilkS")
		)
		(fp_line
			(start 11.546332 -0.860552)
			(end 13.55598 -2.788412)
			(stroke
				(width 0.1)
				(type default)
			)
			(layer "F.SilkS")
		)
		(fp_line
			(start 11.546332 -0.860552)
			(end 13.55598 -2.788412)
			(stroke
				(width 0.1)
				(type default)
			)
			(layer "F.SilkS")
		)
		(fp_line
			(start 11.557762 -5.199888)
			(end 10.725658 -4.40182)
			(stroke
				(width 0.1)
				(type default)
			)
			(layer "F.SilkS")
		)
		(fp_line
			(start 11.557762 -5.199888)
			(end 10.725658 -4.40182)
			(stroke
				(width 0.1)
				(type default)
			)
			(layer "F.SilkS")
		)
		(fp_line
			(start 11.629898 -5.211572)
			(end 10.74166 -4.359402)
			(stroke
				(width 0.1)
				(type default)
			)
			(layer "F.SilkS")
		)
		(fp_line
			(start 11.629898 -5.211572)
			(end 10.74166 -4.359402)
			(stroke
				(width 0.1)
				(type default)
			)
			(layer "F.SilkS")
		)
		(fp_line
			(start 11.63193 -0.884936)
			(end 13.544042 -2.71907)
			(stroke
				(width 0.1)
				(type default)
			)
			(layer "F.SilkS")
		)
		(fp_line
			(start 11.63193 -0.884936)
			(end 13.544042 -2.71907)
			(stroke
				(width 0.1)
				(type default)
			)
			(layer "F.SilkS")
		)
		(fp_line
			(start 11.702034 -5.223002)
			(end 10.757662 -4.316984)
			(stroke
				(width 0.1)
				(type default)
			)
			(layer "F.SilkS")
		)
		(fp_line
			(start 11.702034 -5.223002)
			(end 10.757662 -4.316984)
			(stroke
				(width 0.1)
				(type default)
			)
			(layer "F.SilkS")
		)
		(fp_line
			(start 11.728704 -0.919988)
			(end 13.531596 -2.649728)
			(stroke
				(width 0.1)
				(type default)
			)
			(layer "F.SilkS")
		)
		(fp_line
			(start 11.728704 -0.919988)
			(end 13.531596 -2.649728)
			(stroke
				(width 0.1)
				(type default)
			)
			(layer "F.SilkS")
		)
		(fp_line
			(start 11.77417 -5.234178)
			(end 10.773664 -4.274566)
			(stroke
				(width 0.1)
				(type default)
			)
			(layer "F.SilkS")
		)
		(fp_line
			(start 11.77417 -5.234178)
			(end 10.773664 -4.274566)
			(stroke
				(width 0.1)
				(type default)
			)
			(layer "F.SilkS")
		)
		(fp_line
			(start 11.84021 -5.24002)
			(end 10.789666 -4.232148)
			(stroke
				(width 0.1)
				(type default)
			)
			(layer "F.SilkS")
		)
		(fp_line
			(start 11.84021 -5.24002)
			(end 10.789666 -4.232148)
			(stroke
				(width 0.1)
				(type default)
			)
			(layer "F.SilkS")
		)
		(fp_line
			(start 11.8491 -0.9779)
			(end 13.519404 -2.580386)
			(stroke
				(width 0.1)
				(type default)
			)
			(layer "F.SilkS")
		)
		(fp_line
			(start 11.8491 -0.9779)
			(end 13.519404 -2.580386)
			(stroke
				(width 0.1)
				(type default)
			)
			(layer "F.SilkS")
		)
		(fp_line
			(start 11.906504 -5.245862)
			(end 10.805414 -4.18973)
			(stroke
				(width 0.1)
				(type default)
			)
			(layer "F.SilkS")
		)
		(fp_line
			(start 11.906504 -5.245862)
			(end 10.805414 -4.18973)
			(stroke
				(width 0.1)
				(type default)
			)
			(layer "F.SilkS")
		)
		(fp_line
			(start 11.972798 -5.251958)
			(end 10.821416 -4.147312)
			(stroke
				(width 0.1)
				(type default)
			)
			(layer "F.SilkS")
		)
		(fp_line
			(start 11.972798 -5.251958)
			(end 10.821416 -4.147312)
			(stroke
				(width 0.1)
				(type default)
			)
			(layer "F.SilkS")
		)
		(fp_line
			(start 12.000738 -1.06553)
			(end 13.507466 -2.51079)
			(stroke
				(width 0.1)
				(type default)
			)
			(layer "F.SilkS")
		)
		(fp_line
			(start 12.000738 -1.06553)
			(end 13.507466 -2.51079)
			(stroke
				(width 0.1)
				(type default)
			)
			(layer "F.SilkS")
		)
		(fp_line
			(start 12.036806 -5.255514)
			(end 10.837418 -4.104894)
			(stroke
				(width 0.1)
				(type default)
			)
			(layer "F.SilkS")
		)
		(fp_line
			(start 12.036806 -5.255514)
			(end 10.837418 -4.104894)
			(stroke
				(width 0.1)
				(type default)
			)
			(layer "F.SilkS")
		)
		(fp_line
			(start 12.093956 -0.882904)
			(end 12.111228 -0.882904)
			(stroke
				(width 0.1)
				(type default)
			)
			(layer "F.SilkS")
		)
		(fp_line
			(start 12.093956 -0.882904)
			(end 12.111228 -0.882904)
			(stroke
				(width 0.1)
				(type default)
			)
			(layer "F.SilkS")
		)
		(fp_line
			(start 12.098528 -5.257038)
			(end 10.85342 -4.062476)
			(stroke
				(width 0.1)
				(type default)
			)
			(layer "F.SilkS")
		)
		(fp_line
			(start 12.098528 -5.257038)
			(end 10.85342 -4.062476)
			(stroke
				(width 0.1)
				(type default)
			)
			(layer "F.SilkS")
		)
		(fp_line
			(start 12.102592 -0.932434)
			(end 12.093956 -0.882904)
			(stroke
				(width 0.1)
				(type default)
			)
			(layer "F.SilkS")
		)
		(fp_line
			(start 12.102592 -0.932434)
			(end 12.093956 -0.882904)
			(stroke
				(width 0.1)
				(type default)
			)
			(layer "F.SilkS")
		)
		(fp_line
			(start 12.102592 -0.932434)
			(end 13.458444 -2.233422)
			(stroke
				(width 0.1)
				(type default)
			)
			(layer "F.SilkS")
		)
		(fp_line
			(start 12.102592 -0.932434)
			(end 13.458444 -2.233422)
			(stroke
				(width 0.1)
				(type default)
			)
			(layer "F.SilkS")
		)
		(fp_line
			(start 12.111228 -0.882904)
			(end 12.171172 -0.882904)
			(stroke
				(width 0.1)
				(type default)
			)
			(layer "F.SilkS")
		)
		(fp_line
			(start 12.111228 -0.882904)
			(end 12.171172 -0.882904)
			(stroke
				(width 0.1)
				(type default)
			)
			(layer "F.SilkS")
		)
		(fp_line
			(start 12.111228 -0.882904)
			(end 13.446506 -2.163826)
			(stroke
				(width 0.1)
				(type default)
			)
			(layer "F.SilkS")
		)
		(fp_line
			(start 12.111228 -0.882904)
			(end 13.446506 -2.163826)
			(stroke
				(width 0.1)
				(type default)
			)
			(layer "F.SilkS")
		)
		(fp_line
			(start 12.115038 -1.00203)
			(end 12.102592 -0.932434)
			(stroke
				(width 0.1)
				(type default)
			)
			(layer "F.SilkS")
		)
		(fp_line
			(start 12.115038 -1.00203)
			(end 12.102592 -0.932434)
			(stroke
				(width 0.1)
				(type default)
			)
			(layer "F.SilkS")
		)
		(fp_line
			(start 12.115038 -1.00203)
			(end 13.47089 -2.302764)
			(stroke
				(width 0.1)
				(type default)
			)
			(layer "F.SilkS")
		)
		(fp_line
			(start 12.115038 -1.00203)
			(end 13.47089 -2.302764)
			(stroke
				(width 0.1)
				(type default)
			)
			(layer "F.SilkS")
		)
		(fp_line
			(start 12.12723 -1.071626)
			(end 12.115038 -1.00203)
			(stroke
				(width 0.1)
				(type default)
			)
			(layer "F.SilkS")
		)
		(fp_line
			(start 12.12723 -1.071626)
			(end 12.115038 -1.00203)
			(stroke
				(width 0.1)
				(type default)
			)
			(layer "F.SilkS")
		)
		(fp_line
			(start 12.12723 -1.071626)
			(end 13.483082 -2.372106)
			(stroke
				(width 0.1)
				(type default)
			)
			(layer "F.SilkS")
		)
		(fp_line
			(start 12.12723 -1.071626)
			(end 13.483082 -2.372106)
			(stroke
				(width 0.1)
				(type default)
			)
			(layer "F.SilkS")
		)
		(fp_line
			(start 12.139676 -1.140968)
			(end 12.12723 -1.071626)
			(stroke
				(width 0.1)
				(type default)
			)
			(layer "F.SilkS")
		)
		(fp_line
			(start 12.139676 -1.140968)
			(end 12.12723 -1.071626)
			(stroke
				(width 0.1)
				(type default)
			)
			(layer "F.SilkS")
		)
		(fp_line
			(start 12.139676 -1.140968)
			(end 13.49502 -2.441448)
			(stroke
				(width 0.1)
				(type default)
			)
			(layer "F.SilkS")
		)
		(fp_line
			(start 12.139676 -1.140968)
			(end 13.49502 -2.441448)
			(stroke
				(width 0.1)
				(type default)
			)
			(layer "F.SilkS")
		)
		(fp_line
			(start 12.160504 -5.258816)
			(end 10.92708 -4.07543)
			(stroke
				(width 0.1)
				(type default)
			)
			(layer "F.SilkS")
		)
		(fp_line
			(start 12.160504 -5.258816)
			(end 10.92708 -4.07543)
			(stroke
				(width 0.1)
				(type default)
			)
			(layer "F.SilkS")
		)
		(fp_line
			(start 12.171172 -0.882904)
			(end 12.23137 -0.882904)
			(stroke
				(width 0.1)
				(type default)
			)
			(layer "F.SilkS")
		)
		(fp_line
			(start 12.171172 -0.882904)
			(end 12.23137 -0.882904)
			(stroke
				(width 0.1)
				(type default)
			)
			(layer "F.SilkS")
		)
		(fp_line
			(start 12.171172 -0.882904)
			(end 13.434314 -2.094738)
			(stroke
				(width 0.1)
				(type default)
			)
			(layer "F.SilkS")
		)
		(fp_line
			(start 12.171172 -0.882904)
			(end 13.434314 -2.094738)
			(stroke
				(width 0.1)
				(type default)
			)
			(layer "F.SilkS")
		)
		(fp_line
			(start 12.22248 -5.260594)
			(end 11.042904 -4.12877)
			(stroke
				(width 0.1)
				(type default)
			)
			(layer "F.SilkS")
		)
		(fp_line
			(start 12.22248 -5.260594)
			(end 11.042904 -4.12877)
			(stroke
				(width 0.1)
				(type default)
			)
			(layer "F.SilkS")
		)
		(fp_line
			(start 12.23137 -0.882904)
			(end 12.291568 -0.882904)
			(stroke
				(width 0.1)
				(type default)
			)
			(layer "F.SilkS")
		)
		(fp_line
			(start 12.23137 -0.882904)
			(end 12.291568 -0.882904)
			(stroke
				(width 0.1)
				(type default)
			)
			(layer "F.SilkS")
		)
		(fp_line
			(start 12.23137 -0.882904)
			(end 13.422122 -2.025396)
			(stroke
				(width 0.1)
				(type default)
			)
			(layer "F.SilkS")
		)
		(fp_line
			(start 12.23137 -0.882904)
			(end 13.422122 -2.025396)
			(stroke
				(width 0.1)
				(type default)
			)
			(layer "F.SilkS")
		)
		(fp_line
			(start 12.281408 -5.25907)
			(end 11.150092 -4.173728)
			(stroke
				(width 0.1)
				(type default)
			)
			(layer "F.SilkS")
		)
		(fp_line
			(start 12.281408 -5.25907)
			(end 11.150092 -4.173728)
			(stroke
				(width 0.1)
				(type default)
			)
			(layer "F.SilkS")
		)
		(fp_line
			(start 12.291568 -0.882904)
			(end 12.351512 -0.882904)
			(stroke
				(width 0.1)
				(type default)
			)
			(layer "F.SilkS")
		)
		(fp_line
			(start 12.291568 -0.882904)
			(end 12.351512 -0.882904)
			(stroke
				(width 0.1)
				(type default)
			)
			(layer "F.SilkS")
		)
		(fp_line
			(start 12.291568 -0.882904)
			(end 13.40993 -1.9558)
			(stroke
				(width 0.1)
				(type default)
			)
			(layer "F.SilkS")
		)
		(fp_line
			(start 12.291568 -0.882904)
			(end 13.40993 -1.9558)
			(stroke
				(width 0.1)
				(type default)
			)
			(layer "F.SilkS")
		)
		(fp_line
			(start 12.335002 -2.251964)
			(end 12.323064 -2.182622)
			(stroke
				(width 0.1)
				(type default)
			)
			(layer "F.SilkS")
		)
		(fp_line
			(start 12.335002 -2.251964)
			(end 12.323064 -2.182622)
			(stroke
				(width 0.1)
				(type default)
			)
			(layer "F.SilkS")
		)
		(fp_line
			(start 12.337542 -5.255514)
			(end 11.246358 -4.208526)
			(stroke
				(width 0.1)
				(type default)
			)
			(layer "F.SilkS")
		)
		(fp_line
			(start 12.337542 -5.255514)
			(end 11.246358 -4.208526)
			(stroke
				(width 0.1)
				(type default)
			)
			(layer "F.SilkS")
		)
		(fp_line
			(start 12.347194 -2.321306)
			(end 12.335002 -2.251964)
			(stroke
				(width 0.1)
				(type default)
			)
			(layer "F.SilkS")
		)
		(fp_line
			(start 12.347194 -2.321306)
			(end 12.335002 -2.251964)
			(stroke
				(width 0.1)
				(type default)
			)
			(layer "F.SilkS")
		)
		(fp_line
			(start 12.351512 -0.882904)
			(end 12.41171 -0.882904)
			(stroke
				(width 0.1)
				(type default)
			)
			(layer "F.SilkS")
		)
		(fp_line
			(start 12.351512 -0.882904)
			(end 12.41171 -0.882904)
			(stroke
				(width 0.1)
				(type default)
			)
			(layer "F.SilkS")
		)
		(fp_line
			(start 12.351512 -0.882904)
			(end 13.397992 -1.886458)
			(stroke
				(width 0.1)
				(type default)
			)
			(layer "F.SilkS")
		)
		(fp_line
			(start 12.351512 -0.882904)
			(end 13.397992 -1.886458)
			(stroke
				(width 0.1)
				(type default)
			)
			(layer "F.SilkS")
		)
		(fp_line
			(start 12.359386 -2.390902)
			(end 12.347194 -2.321306)
			(stroke
				(width 0.1)
				(type default)
			)
			(layer "F.SilkS")
		)
		(fp_line
			(start 12.359386 -2.390902)
			(end 12.347194 -2.321306)
			(stroke
				(width 0.1)
				(type default)
			)
			(layer "F.SilkS")
		)
		(fp_line
			(start 12.371578 -2.460244)
			(end 12.359386 -2.390902)
			(stroke
				(width 0.1)
				(type default)
			)
			(layer "F.SilkS")
		)
		(fp_line
			(start 12.371578 -2.460244)
			(end 12.359386 -2.390902)
			(stroke
				(width 0.1)
				(type default)
			)
			(layer "F.SilkS")
		)
		(fp_line
			(start 12.38377 -2.529586)
			(end 12.371578 -2.460244)
			(stroke
				(width 0.1)
				(type default)
			)
			(layer "F.SilkS")
		)
		(fp_line
			(start 12.38377 -2.529586)
			(end 12.371578 -2.460244)
			(stroke
				(width 0.1)
				(type default)
			)
			(layer "F.SilkS")
		)
		(fp_line
			(start 12.393676 -5.251704)
			(end 11.336782 -4.237736)
			(stroke
				(width 0.1)
				(type default)
			)
			(layer "F.SilkS")
		)
		(fp_line
			(start 12.393676 -5.251704)
			(end 11.336782 -4.237736)
			(stroke
				(width 0.1)
				(type default)
			)
			(layer "F.SilkS")
		)
		(fp_line
			(start 12.395962 -2.598928)
			(end 12.38377 -2.529586)
			(stroke
				(width 0.1)
				(type default)
			)
			(layer "F.SilkS")
		)
		(fp_line
			(start 12.395962 -2.598928)
			(end 12.38377 -2.529586)
			(stroke
				(width 0.1)
				(type default)
			)
			(layer "F.SilkS")
		)
		(fp_line
			(start 12.401804 -3.64363)
			(end 11.574526 -2.849626)
			(stroke
				(width 0.1)
				(type default)
			)
			(layer "F.SilkS")
		)
		(fp_line
			(start 12.401804 -3.64363)
			(end 11.574526 -2.849626)
			(stroke
				(width 0.1)
				(type default)
			)
			(layer "F.SilkS")
		)
		(fp_line
			(start 12.408154 -2.668524)
			(end 12.395962 -2.598928)
			(stroke
				(width 0.1)
				(type default)
			)
			(layer "F.SilkS")
		)
		(fp_line
			(start 12.408154 -2.668524)
			(end 12.395962 -2.598928)
			(stroke
				(width 0.1)
				(type default)
			)
			(layer "F.SilkS")
		)
		(fp_line
			(start 12.41171 -0.882904)
			(end 12.471908 -0.882904)
			(stroke
				(width 0.1)
				(type default)
			)
			(layer "F.SilkS")
		)
		(fp_line
			(start 12.41171 -0.882904)
			(end 12.471908 -0.882904)
			(stroke
				(width 0.1)
				(type default)
			)
			(layer "F.SilkS")
		)
		(fp_line
			(start 12.41171 -0.882904)
			(end 13.385546 -1.817116)
			(stroke
				(width 0.1)
				(type default)
			)
			(layer "F.SilkS")
		)
		(fp_line
			(start 12.41171 -0.882904)
			(end 13.385546 -1.817116)
			(stroke
				(width 0.1)
				(type default)
			)
			(layer "F.SilkS")
		)
		(fp_line
			(start 12.445238 -3.62712)
			(end 11.643614 -2.858262)
			(stroke
				(width 0.1)
				(type default)
			)
			(layer "F.SilkS")
		)
		(fp_line
			(start 12.445238 -3.62712)
			(end 11.643614 -2.858262)
			(stroke
				(width 0.1)
				(type default)
			)
			(layer "F.SilkS")
		)
		(fp_line
			(start 12.44981 -5.24764)
			(end 11.421364 -4.261104)
			(stroke
				(width 0.1)
				(type default)
			)
			(layer "F.SilkS")
		)
		(fp_line
			(start 12.44981 -5.24764)
			(end 11.421364 -4.261104)
			(stroke
				(width 0.1)
				(type default)
			)
			(layer "F.SilkS")
		)
		(fp_line
			(start 12.471908 -0.882904)
			(end 12.53236 -0.882904)
			(stroke
				(width 0.1)
				(type default)
			)
			(layer "F.SilkS")
		)
		(fp_line
			(start 12.471908 -0.882904)
			(end 12.53236 -0.882904)
			(stroke
				(width 0.1)
				(type default)
			)
			(layer "F.SilkS")
		)
		(fp_line
			(start 12.471908 -0.882904)
			(end 13.373354 -1.74752)
			(stroke
				(width 0.1)
				(type default)
			)
			(layer "F.SilkS")
		)
		(fp_line
			(start 12.471908 -0.882904)
			(end 13.373354 -1.74752)
			(stroke
				(width 0.1)
				(type default)
			)
			(layer "F.SilkS")
		)
		(fp_line
			(start 12.485624 -3.608324)
			(end 11.704574 -2.859278)
			(stroke
				(width 0.1)
				(type default)
			)
			(layer "F.SilkS")
		)
		(fp_line
			(start 12.485624 -3.608324)
			(end 11.704574 -2.859278)
			(stroke
				(width 0.1)
				(type default)
			)
			(layer "F.SilkS")
		)
		(fp_line
			(start 12.506198 -5.24383)
			(end 11.499596 -4.278376)
			(stroke
				(width 0.1)
				(type default)
			)
			(layer "F.SilkS")
		)
		(fp_line
			(start 12.506198 -5.24383)
			(end 11.499596 -4.278376)
			(stroke
				(width 0.1)
				(type default)
			)
			(layer "F.SilkS")
		)
		(fp_line
			(start 12.52601 -3.589274)
			(end 11.763502 -2.858008)
			(stroke
				(width 0.1)
				(type default)
			)
			(layer "F.SilkS")
		)
		(fp_line
			(start 12.52601 -3.589274)
			(end 11.763502 -2.858008)
			(stroke
				(width 0.1)
				(type default)
			)
			(layer "F.SilkS")
		)
		(fp_line
			(start 12.53236 -0.882904)
			(end 12.592558 -0.882904)
			(stroke
				(width 0.1)
				(type default)
			)
			(layer "F.SilkS")
		)
		(fp_line
			(start 12.53236 -0.882904)
			(end 12.592558 -0.882904)
			(stroke
				(width 0.1)
				(type default)
			)
			(layer "F.SilkS")
		)
		(fp_line
			(start 12.53236 -0.882904)
			(end 13.361416 -1.678178)
			(stroke
				(width 0.1)
				(type default)
			)
			(layer "F.SilkS")
		)
		(fp_line
			(start 12.53236 -0.882904)
			(end 13.361416 -1.678178)
			(stroke
				(width 0.1)
				(type default)
			)
			(layer "F.SilkS")
		)
		(fp_line
			(start 12.562078 -5.24002)
			(end 11.575542 -4.293616)
			(stroke
				(width 0.1)
				(type default)
			)
			(layer "F.SilkS")
		)
		(fp_line
			(start 12.562078 -5.24002)
			(end 11.575542 -4.293616)
			(stroke
				(width 0.1)
				(type default)
			)
			(layer "F.SilkS")
		)
		(fp_line
			(start 12.590018 -3.708654)
			(end 12.57808 -3.639312)
			(stroke
				(width 0.1)
				(type default)
			)
			(layer "F.SilkS")
		)
		(fp_line
			(start 12.590018 -3.708654)
			(end 12.57808 -3.639312)
			(stroke
				(width 0.1)
				(type default)
			)
			(layer "F.SilkS")
		)
		(fp_line
			(start 12.592558 -0.882904)
			(end 12.652502 -0.882904)
			(stroke
				(width 0.1)
				(type default)
			)
			(layer "F.SilkS")
		)
		(fp_line
			(start 12.592558 -0.882904)
			(end 12.652502 -0.882904)
			(stroke
				(width 0.1)
				(type default)
			)
			(layer "F.SilkS")
		)
		(fp_line
			(start 12.592558 -0.882904)
			(end 13.34897 -1.608836)
			(stroke
				(width 0.1)
				(type default)
			)
			(layer "F.SilkS")
		)
		(fp_line
			(start 12.592558 -0.882904)
			(end 13.34897 -1.608836)
			(stroke
				(width 0.1)
				(type default)
			)
			(layer "F.SilkS")
		)
		(fp_line
			(start 12.601956 -3.777996)
			(end 12.590018 -3.708654)
			(stroke
				(width 0.1)
				(type default)
			)
			(layer "F.SilkS")
		)
		(fp_line
			(start 12.601956 -3.777996)
			(end 12.590018 -3.708654)
			(stroke
				(width 0.1)
				(type default)
			)
			(layer "F.SilkS")
		)
		(fp_line
			(start 12.618212 -5.23621)
			(end 11.6459 -4.303268)
			(stroke
				(width 0.1)
				(type default)
			)
			(layer "F.SilkS")
		)
		(fp_line
			(start 12.618212 -5.23621)
			(end 11.6459 -4.303268)
			(stroke
				(width 0.1)
				(type default)
			)
			(layer "F.SilkS")
		)
		(fp_line
			(start 12.652502 -0.882904)
			(end 12.7127 -0.882904)
			(stroke
				(width 0.1)
				(type default)
			)
			(layer "F.SilkS")
		)
		(fp_line
			(start 12.652502 -0.882904)
			(end 12.7127 -0.882904)
			(stroke
				(width 0.1)
				(type default)
			)
			(layer "F.SilkS")
		)
		(fp_line
			(start 12.652502 -0.882904)
			(end 13.337286 -1.539494)
			(stroke
				(width 0.1)
				(type default)
			)
			(layer "F.SilkS")
		)
		(fp_line
			(start 12.652502 -0.882904)
			(end 13.337286 -1.539494)
			(stroke
				(width 0.1)
				(type default)
			)
			(layer "F.SilkS")
		)
		(fp_line
			(start 12.666726 -5.225034)
			(end 11.715242 -4.312412)
			(stroke
				(width 0.1)
				(type default)
			)
			(layer "F.SilkS")
		)
		(fp_line
			(start 12.666726 -5.225034)
			(end 11.715242 -4.312412)
			(stroke
				(width 0.1)
				(type default)
			)
			(layer "F.SilkS")
		)
		(fp_line
			(start 12.7127 -0.882904)
			(end 12.772898 -0.882904)
			(stroke
				(width 0.1)
				(type default)
			)
			(layer "F.SilkS")
		)
		(fp_line
			(start 12.7127 -0.882904)
			(end 12.772898 -0.882904)
			(stroke
				(width 0.1)
				(type default)
			)
			(layer "F.SilkS")
		)
		(fp_line
			(start 12.7127 -0.882904)
			(end 13.32484 -1.470152)
			(stroke
				(width 0.1)
				(type default)
			)
			(layer "F.SilkS")
		)
		(fp_line
			(start 12.7127 -0.882904)
			(end 13.32484 -1.470152)
			(stroke
				(width 0.1)
				(type default)
			)
			(layer "F.SilkS")
		)
		(fp_line
			(start 12.715494 -5.214112)
			(end 11.78179 -4.318254)
			(stroke
				(width 0.1)
				(type default)
			)
			(layer "F.SilkS")
		)
		(fp_line
			(start 12.715494 -5.214112)
			(end 11.78179 -4.318254)
			(stroke
				(width 0.1)
				(type default)
			)
			(layer "F.SilkS")
		)
		(fp_line
			(start 12.764008 -5.202936)
			(end 11.846306 -4.322572)
			(stroke
				(width 0.1)
				(type default)
			)
			(layer "F.SilkS")
		)
		(fp_line
			(start 12.764008 -5.202936)
			(end 11.846306 -4.322572)
			(stroke
				(width 0.1)
				(type default)
			)
			(layer "F.SilkS")
		)
		(fp_line
			(start 12.772898 -0.882904)
			(end 12.832842 -0.882904)
			(stroke
				(width 0.1)
				(type default)
			)
			(layer "F.SilkS")
		)
		(fp_line
			(start 12.772898 -0.882904)
			(end 12.832842 -0.882904)
			(stroke
				(width 0.1)
				(type default)
			)
			(layer "F.SilkS")
		)
		(fp_line
			(start 12.772898 -0.882904)
			(end 13.312394 -1.400556)
			(stroke
				(width 0.1)
				(type default)
			)
			(layer "F.SilkS")
		)
		(fp_line
			(start 12.772898 -0.882904)
			(end 13.312394 -1.400556)
			(stroke
				(width 0.1)
				(type default)
			)
			(layer "F.SilkS")
		)
		(fp_line
			(start 12.812522 -5.19176)
			(end 11.910568 -4.326636)
			(stroke
				(width 0.1)
				(type default)
			)
			(layer "F.SilkS")
		)
		(fp_line
			(start 12.812522 -5.19176)
			(end 11.910568 -4.326636)
			(stroke
				(width 0.1)
				(type default)
			)
			(layer "F.SilkS")
		)
		(fp_line
			(start 12.832842 -0.882904)
			(end 12.89304 -0.882904)
			(stroke
				(width 0.1)
				(type default)
			)
			(layer "F.SilkS")
		)
		(fp_line
			(start 12.832842 -0.882904)
			(end 12.89304 -0.882904)
			(stroke
				(width 0.1)
				(type default)
			)
			(layer "F.SilkS")
		)
		(fp_line
			(start 12.832842 -0.882904)
			(end 13.30071 -1.331468)
			(stroke
				(width 0.1)
				(type default)
			)
			(layer "F.SilkS")
		)
		(fp_line
			(start 12.832842 -0.882904)
			(end 13.30071 -1.331468)
			(stroke
				(width 0.1)
				(type default)
			)
			(layer "F.SilkS")
		)
		(fp_line
			(start 12.861036 -5.180584)
			(end 11.972036 -4.327906)
			(stroke
				(width 0.1)
				(type default)
			)
			(layer "F.SilkS")
		)
		(fp_line
			(start 12.861036 -5.180584)
			(end 11.972036 -4.327906)
			(stroke
				(width 0.1)
				(type default)
			)
			(layer "F.SilkS")
		)
		(fp_line
			(start 12.89304 -0.882904)
			(end 12.953238 -0.882904)
			(stroke
				(width 0.1)
				(type default)
			)
			(layer "F.SilkS")
		)
		(fp_line
			(start 12.89304 -0.882904)
			(end 12.953238 -0.882904)
			(stroke
				(width 0.1)
				(type default)
			)
			(layer "F.SilkS")
		)
		(fp_line
			(start 12.89304 -0.882904)
			(end 13.288264 -1.262126)
			(stroke
				(width 0.1)
				(type default)
			)
			(layer "F.SilkS")
		)
		(fp_line
			(start 12.89304 -0.882904)
			(end 13.288264 -1.262126)
			(stroke
				(width 0.1)
				(type default)
			)
			(layer "F.SilkS")
		)
		(fp_line
			(start 12.909804 -5.169408)
			(end 12.033758 -4.328922)
			(stroke
				(width 0.1)
				(type default)
			)
			(layer "F.SilkS")
		)
		(fp_line
			(start 12.909804 -5.169408)
			(end 12.033758 -4.328922)
			(stroke
				(width 0.1)
				(type default)
			)
			(layer "F.SilkS")
		)
		(fp_line
			(start 12.953238 -0.882904)
			(end 13.01369 -0.882904)
			(stroke
				(width 0.1)
				(type default)
			)
			(layer "F.SilkS")
		)
		(fp_line
			(start 12.953238 -0.882904)
			(end 13.01369 -0.882904)
			(stroke
				(width 0.1)
				(type default)
			)
			(layer "F.SilkS")
		)
		(fp_line
			(start 12.953238 -0.882904)
			(end 13.275818 -1.19253)
			(stroke
				(width 0.1)
				(type default)
			)
			(layer "F.SilkS")
		)
		(fp_line
			(start 12.953238 -0.882904)
			(end 13.275818 -1.19253)
			(stroke
				(width 0.1)
				(type default)
			)
			(layer "F.SilkS")
		)
		(fp_line
			(start 12.955778 -5.155946)
			(end 12.09421 -4.32943)
			(stroke
				(width 0.1)
				(type default)
			)
			(layer "F.SilkS")
		)
		(fp_line
			(start 12.955778 -5.155946)
			(end 12.09421 -4.32943)
			(stroke
				(width 0.1)
				(type default)
			)
			(layer "F.SilkS")
		)
		(fp_line
			(start 12.996926 -5.137658)
			(end 12.149836 -4.325112)
			(stroke
				(width 0.1)
				(type default)
			)
			(layer "F.SilkS")
		)
		(fp_line
			(start 12.996926 -5.137658)
			(end 12.149836 -4.325112)
			(stroke
				(width 0.1)
				(type default)
			)
			(layer "F.SilkS")
		)
		(fp_line
			(start 13.01369 -0.882904)
			(end 13.073634 -0.882904)
			(stroke
				(width 0.1)
				(type default)
			)
			(layer "F.SilkS")
		)
		(fp_line
			(start 13.01369 -0.882904)
			(end 13.073634 -0.882904)
			(stroke
				(width 0.1)
				(type default)
			)
			(layer "F.SilkS")
		)
		(fp_line
			(start 13.01369 -0.882904)
			(end 13.264134 -1.123188)
			(stroke
				(width 0.1)
				(type default)
			)
			(layer "F.SilkS")
		)
		(fp_line
			(start 13.01369 -0.882904)
			(end 13.264134 -1.123188)
			(stroke
				(width 0.1)
				(type default)
			)
			(layer "F.SilkS")
		)
		(fp_line
			(start 13.038074 -5.11937)
			(end 12.205462 -4.320794)
			(stroke
				(width 0.1)
				(type default)
			)
			(layer "F.SilkS")
		)
		(fp_line
			(start 13.038074 -5.11937)
			(end 12.205462 -4.320794)
			(stroke
				(width 0.1)
				(type default)
			)
			(layer "F.SilkS")
		)
		(fp_line
			(start 13.073634 -0.882904)
			(end 13.133578 -0.882904)
			(stroke
				(width 0.1)
				(type default)
			)
			(layer "F.SilkS")
		)
		(fp_line
			(start 13.073634 -0.882904)
			(end 13.133578 -0.882904)
			(stroke
				(width 0.1)
				(type default)
			)
			(layer "F.SilkS")
		)
		(fp_line
			(start 13.073634 -0.882904)
			(end 13.251942 -1.053846)
			(stroke
				(width 0.1)
				(type default)
			)
			(layer "F.SilkS")
		)
		(fp_line
			(start 13.073634 -0.882904)
			(end 13.251942 -1.053846)
			(stroke
				(width 0.1)
				(type default)
			)
			(layer "F.SilkS")
		)
		(fp_line
			(start 13.079222 -5.101336)
			(end 12.256008 -4.311396)
			(stroke
				(width 0.1)
				(type default)
			)
			(layer "F.SilkS")
		)
		(fp_line
			(start 13.079222 -5.101336)
			(end 12.256008 -4.311396)
			(stroke
				(width 0.1)
				(type default)
			)
			(layer "F.SilkS")
		)
		(fp_line
			(start 13.120116 -5.083048)
			(end 12.302998 -4.29895)
			(stroke
				(width 0.1)
				(type default)
			)
			(layer "F.SilkS")
		)
		(fp_line
			(start 13.120116 -5.083048)
			(end 12.302998 -4.29895)
			(stroke
				(width 0.1)
				(type default)
			)
			(layer "F.SilkS")
		)
		(fp_line
			(start 13.133578 -0.882904)
			(end 13.19403 -0.882904)
			(stroke
				(width 0.1)
				(type default)
			)
			(layer "F.SilkS")
		)
		(fp_line
			(start 13.133578 -0.882904)
			(end 13.19403 -0.882904)
			(stroke
				(width 0.1)
				(type default)
			)
			(layer "F.SilkS")
		)
		(fp_line
			(start 13.133578 -0.882904)
			(end 13.23975 -0.984504)
			(stroke
				(width 0.1)
				(type default)
			)
			(layer "F.SilkS")
		)
		(fp_line
			(start 13.133578 -0.882904)
			(end 13.23975 -0.984504)
			(stroke
				(width 0.1)
				(type default)
			)
			(layer "F.SilkS")
		)
		(fp_line
			(start 13.161518 -5.06476)
			(end 12.34948 -4.285742)
			(stroke
				(width 0.1)
				(type default)
			)
			(layer "F.SilkS")
		)
		(fp_line
			(start 13.161518 -5.06476)
			(end 12.34948 -4.285742)
			(stroke
				(width 0.1)
				(type default)
			)
			(layer "F.SilkS")
		)
		(fp_line
			(start 13.19403 -0.882904)
			(end 13.22197 -0.882904)
			(stroke
				(width 0.1)
				(type default)
			)
			(layer "F.SilkS")
		)
		(fp_line
			(start 13.19403 -0.882904)
			(end 13.22197 -0.882904)
			(stroke
				(width 0.1)
				(type default)
			)
			(layer "F.SilkS")
		)
		(fp_line
			(start 13.19403 -0.882904)
			(end 13.227812 -0.914908)
			(stroke
				(width 0.1)
				(type default)
			)
			(layer "F.SilkS")
		)
		(fp_line
			(start 13.19403 -0.882904)
			(end 13.227812 -0.914908)
			(stroke
				(width 0.1)
				(type default)
			)
			(layer "F.SilkS")
		)
		(fp_line
			(start 13.20292 -5.046472)
			(end 12.388596 -4.265422)
			(stroke
				(width 0.1)
				(type default)
			)
			(layer "F.SilkS")
		)
		(fp_line
			(start 13.20292 -5.046472)
			(end 12.388596 -4.265422)
			(stroke
				(width 0.1)
				(type default)
			)
			(layer "F.SilkS")
		)
		(fp_line
			(start 13.22197 -0.882904)
			(end 13.227812 -0.914908)
			(stroke
				(width 0.1)
				(type default)
			)
			(layer "F.SilkS")
		)
		(fp_line
			(start 13.22197 -0.882904)
			(end 13.227812 -0.914908)
			(stroke
				(width 0.1)
				(type default)
			)
			(layer "F.SilkS")
		)
		(fp_line
			(start 13.227812 -0.914908)
			(end 13.23975 -0.984504)
			(stroke
				(width 0.1)
				(type default)
			)
			(layer "F.SilkS")
		)
		(fp_line
			(start 13.227812 -0.914908)
			(end 13.23975 -0.984504)
			(stroke
				(width 0.1)
				(type default)
			)
			(layer "F.SilkS")
		)
		(fp_line
			(start 13.238988 -5.023612)
			(end 12.427458 -4.245102)
			(stroke
				(width 0.1)
				(type default)
			)
			(layer "F.SilkS")
		)
		(fp_line
			(start 13.238988 -5.023612)
			(end 12.427458 -4.245102)
			(stroke
				(width 0.1)
				(type default)
			)
			(layer "F.SilkS")
		)
		(fp_line
			(start 13.23975 -0.984504)
			(end 13.251942 -1.053846)
			(stroke
				(width 0.1)
				(type default)
			)
			(layer "F.SilkS")
		)
		(fp_line
			(start 13.23975 -0.984504)
			(end 13.251942 -1.053846)
			(stroke
				(width 0.1)
				(type default)
			)
			(layer "F.SilkS")
		)
		(fp_line
			(start 13.251942 -1.053846)
			(end 13.264134 -1.123188)
			(stroke
				(width 0.1)
				(type default)
			)
			(layer "F.SilkS")
		)
		(fp_line
			(start 13.251942 -1.053846)
			(end 13.264134 -1.123188)
			(stroke
				(width 0.1)
				(type default)
			)
			(layer "F.SilkS")
		)
		(fp_line
			(start 13.264134 -1.123188)
			(end 13.275818 -1.19253)
			(stroke
				(width 0.1)
				(type default)
			)
			(layer "F.SilkS")
		)
		(fp_line
			(start 13.264134 -1.123188)
			(end 13.275818 -1.19253)
			(stroke
				(width 0.1)
				(type default)
			)
			(layer "F.SilkS")
		)
		(fp_line
			(start 13.272516 -4.998212)
			(end 12.461748 -4.22021)
			(stroke
				(width 0.1)
				(type default)
			)
			(layer "F.SilkS")
		)
		(fp_line
			(start 13.272516 -4.998212)
			(end 12.461748 -4.22021)
			(stroke
				(width 0.1)
				(type default)
			)
			(layer "F.SilkS")
		)
		(fp_line
			(start 13.275818 -1.19253)
			(end 13.288264 -1.262126)
			(stroke
				(width 0.1)
				(type default)
			)
			(layer "F.SilkS")
		)
		(fp_line
			(start 13.275818 -1.19253)
			(end 13.288264 -1.262126)
			(stroke
				(width 0.1)
				(type default)
			)
			(layer "F.SilkS")
		)
		(fp_line
			(start 13.288264 -1.262126)
			(end 13.30071 -1.331468)
			(stroke
				(width 0.1)
				(type default)
			)
			(layer "F.SilkS")
		)
		(fp_line
			(start 13.288264 -1.262126)
			(end 13.30071 -1.331468)
			(stroke
				(width 0.1)
				(type default)
			)
			(layer "F.SilkS")
		)
		(fp_line
			(start 13.30071 -1.331468)
			(end 13.312394 -1.400556)
			(stroke
				(width 0.1)
				(type default)
			)
			(layer "F.SilkS")
		)
		(fp_line
			(start 13.30071 -1.331468)
			(end 13.312394 -1.400556)
			(stroke
				(width 0.1)
				(type default)
			)
			(layer "F.SilkS")
		)
		(fp_line
			(start 13.306298 -4.972812)
			(end 12.49299 -4.192524)
			(stroke
				(width 0.1)
				(type default)
			)
			(layer "F.SilkS")
		)
		(fp_line
			(start 13.306298 -4.972812)
			(end 12.49299 -4.192524)
			(stroke
				(width 0.1)
				(type default)
			)
			(layer "F.SilkS")
		)
		(fp_line
			(start 13.312394 -1.400556)
			(end 13.32484 -1.470152)
			(stroke
				(width 0.1)
				(type default)
			)
			(layer "F.SilkS")
		)
		(fp_line
			(start 13.312394 -1.400556)
			(end 13.32484 -1.470152)
			(stroke
				(width 0.1)
				(type default)
			)
			(layer "F.SilkS")
		)
		(fp_line
			(start 13.32484 -1.470152)
			(end 13.337286 -1.539494)
			(stroke
				(width 0.1)
				(type default)
			)
			(layer "F.SilkS")
		)
		(fp_line
			(start 13.32484 -1.470152)
			(end 13.337286 -1.539494)
			(stroke
				(width 0.1)
				(type default)
			)
			(layer "F.SilkS")
		)
		(fp_line
			(start 13.337286 -1.539494)
			(end 13.34897 -1.608836)
			(stroke
				(width 0.1)
				(type default)
			)
			(layer "F.SilkS")
		)
		(fp_line
			(start 13.337286 -1.539494)
			(end 13.34897 -1.608836)
			(stroke
				(width 0.1)
				(type default)
			)
			(layer "F.SilkS")
		)
		(fp_line
			(start 13.34008 -4.947412)
			(end 12.522454 -4.16306)
			(stroke
				(width 0.1)
				(type default)
			)
			(layer "F.SilkS")
		)
		(fp_line
			(start 13.34008 -4.947412)
			(end 12.522454 -4.16306)
			(stroke
				(width 0.1)
				(type default)
			)
			(layer "F.SilkS")
		)
		(fp_line
			(start 13.34897 -1.608836)
			(end 13.361416 -1.678178)
			(stroke
				(width 0.1)
				(type default)
			)
			(layer "F.SilkS")
		)
		(fp_line
			(start 13.34897 -1.608836)
			(end 13.361416 -1.678178)
			(stroke
				(width 0.1)
				(type default)
			)
			(layer "F.SilkS")
		)
		(fp_line
			(start 13.361416 -1.678178)
			(end 13.373354 -1.74752)
			(stroke
				(width 0.1)
				(type default)
			)
			(layer "F.SilkS")
		)
		(fp_line
			(start 13.361416 -1.678178)
			(end 13.373354 -1.74752)
			(stroke
				(width 0.1)
				(type default)
			)
			(layer "F.SilkS")
		)
		(fp_line
			(start 13.373354 -1.74752)
			(end 13.385546 -1.817116)
			(stroke
				(width 0.1)
				(type default)
			)
			(layer "F.SilkS")
		)
		(fp_line
			(start 13.373354 -1.74752)
			(end 13.385546 -1.817116)
			(stroke
				(width 0.1)
				(type default)
			)
			(layer "F.SilkS")
		)
		(fp_line
			(start 13.373862 -4.922012)
			(end 12.545822 -4.127754)
			(stroke
				(width 0.1)
				(type default)
			)
			(layer "F.SilkS")
		)
		(fp_line
			(start 13.373862 -4.922012)
			(end 12.545822 -4.127754)
			(stroke
				(width 0.1)
				(type default)
			)
			(layer "F.SilkS")
		)
		(fp_line
			(start 13.385546 -1.817116)
			(end 13.397992 -1.886458)
			(stroke
				(width 0.1)
				(type default)
			)
			(layer "F.SilkS")
		)
		(fp_line
			(start 13.385546 -1.817116)
			(end 13.397992 -1.886458)
			(stroke
				(width 0.1)
				(type default)
			)
			(layer "F.SilkS")
		)
		(fp_line
			(start 13.397992 -1.886458)
			(end 13.40993 -1.9558)
			(stroke
				(width 0.1)
				(type default)
			)
			(layer "F.SilkS")
		)
		(fp_line
			(start 13.397992 -1.886458)
			(end 13.40993 -1.9558)
			(stroke
				(width 0.1)
				(type default)
			)
			(layer "F.SilkS")
		)
		(fp_line
			(start 13.407136 -4.896358)
			(end 12.568936 -4.092194)
			(stroke
				(width 0.1)
				(type default)
			)
			(layer "F.SilkS")
		)
		(fp_line
			(start 13.407136 -4.896358)
			(end 12.568936 -4.092194)
			(stroke
				(width 0.1)
				(type default)
			)
			(layer "F.SilkS")
		)
		(fp_line
			(start 13.40993 -1.9558)
			(end 13.422122 -2.025396)
			(stroke
				(width 0.1)
				(type default)
			)
			(layer "F.SilkS")
		)
		(fp_line
			(start 13.40993 -1.9558)
			(end 13.422122 -2.025396)
			(stroke
				(width 0.1)
				(type default)
			)
			(layer "F.SilkS")
		)
		(fp_line
			(start 13.422122 -2.025396)
			(end 13.434314 -2.094738)
			(stroke
				(width 0.1)
				(type default)
			)
			(layer "F.SilkS")
		)
		(fp_line
			(start 13.422122 -2.025396)
			(end 13.434314 -2.094738)
			(stroke
				(width 0.1)
				(type default)
			)
			(layer "F.SilkS")
		)
		(fp_line
			(start 13.434314 -2.094738)
			(end 13.446506 -2.163826)
			(stroke
				(width 0.1)
				(type default)
			)
			(layer "F.SilkS")
		)
		(fp_line
			(start 13.434314 -2.094738)
			(end 13.446506 -2.163826)
			(stroke
				(width 0.1)
				(type default)
			)
			(layer "F.SilkS")
		)
		(fp_line
			(start 13.440664 -4.871212)
			(end 12.58443 -4.049522)
			(stroke
				(width 0.1)
				(type default)
			)
			(layer "F.SilkS")
		)
		(fp_line
			(start 13.440664 -4.871212)
			(end 12.58443 -4.049522)
			(stroke
				(width 0.1)
				(type default)
			)
			(layer "F.SilkS")
		)
		(fp_line
			(start 13.446506 -2.163826)
			(end 13.458444 -2.233422)
			(stroke
				(width 0.1)
				(type default)
			)
			(layer "F.SilkS")
		)
		(fp_line
			(start 13.446506 -2.163826)
			(end 13.458444 -2.233422)
			(stroke
				(width 0.1)
				(type default)
			)
			(layer "F.SilkS")
		)
		(fp_line
			(start 13.458444 -2.233422)
			(end 13.47089 -2.302764)
			(stroke
				(width 0.1)
				(type default)
			)
			(layer "F.SilkS")
		)
		(fp_line
			(start 13.458444 -2.233422)
			(end 13.47089 -2.302764)
			(stroke
				(width 0.1)
				(type default)
			)
			(layer "F.SilkS")
		)
		(fp_line
			(start 13.466826 -4.837938)
			(end 12.599162 -4.005834)
			(stroke
				(width 0.1)
				(type default)
			)
			(layer "F.SilkS")
		)
		(fp_line
			(start 13.466826 -4.837938)
			(end 12.599162 -4.005834)
			(stroke
				(width 0.1)
				(type default)
			)
			(layer "F.SilkS")
		)
		(fp_line
			(start 13.47089 -2.302764)
			(end 13.483082 -2.372106)
			(stroke
				(width 0.1)
				(type default)
			)
			(layer "F.SilkS")
		)
		(fp_line
			(start 13.47089 -2.302764)
			(end 13.483082 -2.372106)
			(stroke
				(width 0.1)
				(type default)
			)
			(layer "F.SilkS")
		)
		(fp_line
			(start 13.483082 -2.372106)
			(end 13.49502 -2.441448)
			(stroke
				(width 0.1)
				(type default)
			)
			(layer "F.SilkS")
		)
		(fp_line
			(start 13.483082 -2.372106)
			(end 13.49502 -2.441448)
			(stroke
				(width 0.1)
				(type default)
			)
			(layer "F.SilkS")
		)
		(fp_line
			(start 13.492226 -4.804918)
			(end 12.606782 -3.955288)
			(stroke
				(width 0.1)
				(type default)
			)
			(layer "F.SilkS")
		)
		(fp_line
			(start 13.492226 -4.804918)
			(end 12.606782 -3.955288)
			(stroke
				(width 0.1)
				(type default)
			)
			(layer "F.SilkS")
		)
		(fp_line
			(start 13.49502 -2.441448)
			(end 13.507466 -2.51079)
			(stroke
				(width 0.1)
				(type default)
			)
			(layer "F.SilkS")
		)
		(fp_line
			(start 13.49502 -2.441448)
			(end 13.507466 -2.51079)
			(stroke
				(width 0.1)
				(type default)
			)
			(layer "F.SilkS")
		)
		(fp_line
			(start 13.507466 -2.51079)
			(end 13.519404 -2.580386)
			(stroke
				(width 0.1)
				(type default)
			)
			(layer "F.SilkS")
		)
		(fp_line
			(start 13.507466 -2.51079)
			(end 13.519404 -2.580386)
			(stroke
				(width 0.1)
				(type default)
			)
			(layer "F.SilkS")
		)
		(fp_line
			(start 13.518134 -4.771898)
			(end 12.612116 -3.902964)
			(stroke
				(width 0.1)
				(type default)
			)
			(layer "F.SilkS")
		)
		(fp_line
			(start 13.518134 -4.771898)
			(end 12.612116 -3.902964)
			(stroke
				(width 0.1)
				(type default)
			)
			(layer "F.SilkS")
		)
		(fp_line
			(start 13.519404 -2.580386)
			(end 13.531596 -2.649728)
			(stroke
				(width 0.1)
				(type default)
			)
			(layer "F.SilkS")
		)
		(fp_line
			(start 13.519404 -2.580386)
			(end 13.531596 -2.649728)
			(stroke
				(width 0.1)
				(type default)
			)
			(layer "F.SilkS")
		)
		(fp_line
			(start 13.531596 -2.649728)
			(end 13.544042 -2.71907)
			(stroke
				(width 0.1)
				(type default)
			)
			(layer "F.SilkS")
		)
		(fp_line
			(start 13.531596 -2.649728)
			(end 13.544042 -2.71907)
			(stroke
				(width 0.1)
				(type default)
			)
			(layer "F.SilkS")
		)
		(fp_line
			(start 13.544042 -4.738878)
			(end 12.60856 -3.84175)
			(stroke
				(width 0.1)
				(type default)
			)
			(layer "F.SilkS")
		)
		(fp_line
			(start 13.544042 -4.738878)
			(end 12.60856 -3.84175)
			(stroke
				(width 0.1)
				(type default)
			)
			(layer "F.SilkS")
		)
		(fp_line
			(start 13.544042 -2.71907)
			(end 13.55598 -2.788412)
			(stroke
				(width 0.1)
				(type default)
			)
			(layer "F.SilkS")
		)
		(fp_line
			(start 13.544042 -2.71907)
			(end 13.55598 -2.788412)
			(stroke
				(width 0.1)
				(type default)
			)
			(layer "F.SilkS")
		)
		(fp_line
			(start 13.55598 -2.788412)
			(end 13.568172 -2.857754)
			(stroke
				(width 0.1)
				(type default)
			)
			(layer "F.SilkS")
		)
		(fp_line
			(start 13.55598 -2.788412)
			(end 13.568172 -2.857754)
			(stroke
				(width 0.1)
				(type default)
			)
			(layer "F.SilkS")
		)
		(fp_line
			(start 13.568172 -2.857754)
			(end 13.580364 -2.927096)
			(stroke
				(width 0.1)
				(type default)
			)
			(layer "F.SilkS")
		)
		(fp_line
			(start 13.568172 -2.857754)
			(end 13.580364 -2.927096)
			(stroke
				(width 0.1)
				(type default)
			)
			(layer "F.SilkS")
		)
		(fp_line
			(start 13.569442 -4.705858)
			(end 12.601956 -3.777996)
			(stroke
				(width 0.1)
				(type default)
			)
			(layer "F.SilkS")
		)
		(fp_line
			(start 13.569442 -4.705858)
			(end 12.601956 -3.777996)
			(stroke
				(width 0.1)
				(type default)
			)
			(layer "F.SilkS")
		)
		(fp_line
			(start 13.580364 -2.927096)
			(end 13.592556 -2.996692)
			(stroke
				(width 0.1)
				(type default)
			)
			(layer "F.SilkS")
		)
		(fp_line
			(start 13.580364 -2.927096)
			(end 13.592556 -2.996692)
			(stroke
				(width 0.1)
				(type default)
			)
			(layer "F.SilkS")
		)
		(fp_line
			(start 13.592556 -2.996692)
			(end 13.604494 -3.06578)
			(stroke
				(width 0.1)
				(type default)
			)
			(layer "F.SilkS")
		)
		(fp_line
			(start 13.592556 -2.996692)
			(end 13.604494 -3.06578)
			(stroke
				(width 0.1)
				(type default)
			)
			(layer "F.SilkS")
		)
		(fp_line
			(start 13.59535 -4.672838)
			(end 12.590018 -3.708654)
			(stroke
				(width 0.1)
				(type default)
			)
			(layer "F.SilkS")
		)
		(fp_line
			(start 13.59535 -4.672838)
			(end 12.590018 -3.708654)
			(stroke
				(width 0.1)
				(type default)
			)
			(layer "F.SilkS")
		)
		(fp_line
			(start 13.604494 -3.06578)
			(end 13.61694 -3.135376)
			(stroke
				(width 0.1)
				(type default)
			)
			(layer "F.SilkS")
		)
		(fp_line
			(start 13.604494 -3.06578)
			(end 13.61694 -3.135376)
			(stroke
				(width 0.1)
				(type default)
			)
			(layer "F.SilkS")
		)
		(fp_line
			(start 13.616432 -4.635246)
			(end 12.57808 -3.639312)
			(stroke
				(width 0.1)
				(type default)
			)
			(layer "F.SilkS")
		)
		(fp_line
			(start 13.616432 -4.635246)
			(end 12.57808 -3.639312)
			(stroke
				(width 0.1)
				(type default)
			)
			(layer "F.SilkS")
		)
		(fp_line
			(start 13.61694 -3.135376)
			(end 13.629132 -3.204972)
			(stroke
				(width 0.1)
				(type default)
			)
			(layer "F.SilkS")
		)
		(fp_line
			(start 13.61694 -3.135376)
			(end 13.629132 -3.204972)
			(stroke
				(width 0.1)
				(type default)
			)
			(layer "F.SilkS")
		)
		(fp_line
			(start 13.629132 -3.204972)
			(end 13.64107 -3.27406)
			(stroke
				(width 0.1)
				(type default)
			)
			(layer "F.SilkS")
		)
		(fp_line
			(start 13.629132 -3.204972)
			(end 13.64107 -3.27406)
			(stroke
				(width 0.1)
				(type default)
			)
			(layer "F.SilkS")
		)
		(fp_line
			(start 13.633196 -4.593844)
			(end 11.82116 -2.855722)
			(stroke
				(width 0.1)
				(type default)
			)
			(layer "F.SilkS")
		)
		(fp_line
			(start 13.633196 -4.593844)
			(end 11.82116 -2.855722)
			(stroke
				(width 0.1)
				(type default)
			)
			(layer "F.SilkS")
		)
		(fp_line
			(start 13.64996 -4.552442)
			(end 11.877548 -2.851912)
			(stroke
				(width 0.1)
				(type default)
			)
			(layer "F.SilkS")
		)
		(fp_line
			(start 13.64996 -4.552442)
			(end 11.877548 -2.851912)
			(stroke
				(width 0.1)
				(type default)
			)
			(layer "F.SilkS")
		)
		(fp_line
			(start 13.653516 -3.343402)
			(end 13.64107 -3.27406)
			(stroke
				(width 0.1)
				(type default)
			)
			(layer "F.SilkS")
		)
		(fp_line
			(start 13.653516 -3.343402)
			(end 13.64107 -3.27406)
			(stroke
				(width 0.1)
				(type default)
			)
			(layer "F.SilkS")
		)
		(fp_line
			(start 13.665708 -3.412998)
			(end 10.943336 -0.801624)
			(stroke
				(width 0.1)
				(type default)
			)
			(layer "F.SilkS")
		)
		(fp_line
			(start 13.665708 -3.412998)
			(end 10.943336 -0.801624)
			(stroke
				(width 0.1)
				(type default)
			)
			(layer "F.SilkS")
		)
		(fp_line
			(start 13.665708 -3.412998)
			(end 13.653516 -3.343402)
			(stroke
				(width 0.1)
				(type default)
			)
			(layer "F.SilkS")
		)
		(fp_line
			(start 13.665708 -3.412998)
			(end 13.653516 -3.343402)
			(stroke
				(width 0.1)
				(type default)
			)
			(layer "F.SilkS")
		)
		(fp_line
			(start 13.667232 -4.51104)
			(end 11.93292 -2.84734)
			(stroke
				(width 0.1)
				(type default)
			)
			(layer "F.SilkS")
		)
		(fp_line
			(start 13.667232 -4.51104)
			(end 11.93292 -2.84734)
			(stroke
				(width 0.1)
				(type default)
			)
			(layer "F.SilkS")
		)
		(fp_line
			(start 13.677646 -3.48234)
			(end 12.323064 -2.182622)
			(stroke
				(width 0.1)
				(type default)
			)
			(layer "F.SilkS")
		)
		(fp_line
			(start 13.677646 -3.48234)
			(end 12.323064 -2.182622)
			(stroke
				(width 0.1)
				(type default)
			)
			(layer "F.SilkS")
		)
		(fp_line
			(start 13.677646 -3.48234)
			(end 13.665708 -3.412998)
			(stroke
				(width 0.1)
				(type default)
			)
			(layer "F.SilkS")
		)
		(fp_line
			(start 13.677646 -3.48234)
			(end 13.665708 -3.412998)
			(stroke
				(width 0.1)
				(type default)
			)
			(layer "F.SilkS")
		)
		(fp_line
			(start 13.684504 -4.469638)
			(end 11.986006 -2.840482)
			(stroke
				(width 0.1)
				(type default)
			)
			(layer "F.SilkS")
		)
		(fp_line
			(start 13.684504 -4.469638)
			(end 11.986006 -2.840482)
			(stroke
				(width 0.1)
				(type default)
			)
			(layer "F.SilkS")
		)
		(fp_line
			(start 13.690092 -3.551682)
			(end 12.335002 -2.251964)
			(stroke
				(width 0.1)
				(type default)
			)
			(layer "F.SilkS")
		)
		(fp_line
			(start 13.690092 -3.551682)
			(end 12.335002 -2.251964)
			(stroke
				(width 0.1)
				(type default)
			)
			(layer "F.SilkS")
		)
		(fp_line
			(start 13.690092 -3.551682)
			(end 13.677646 -3.48234)
			(stroke
				(width 0.1)
				(type default)
			)
			(layer "F.SilkS")
		)
		(fp_line
			(start 13.690092 -3.551682)
			(end 13.677646 -3.48234)
			(stroke
				(width 0.1)
				(type default)
			)
			(layer "F.SilkS")
		)
		(fp_line
			(start 13.701014 -4.42849)
			(end 12.037822 -2.832862)
			(stroke
				(width 0.1)
				(type default)
			)
			(layer "F.SilkS")
		)
		(fp_line
			(start 13.701014 -4.42849)
			(end 12.037822 -2.832862)
			(stroke
				(width 0.1)
				(type default)
			)
			(layer "F.SilkS")
		)
		(fp_line
			(start 13.70203 -3.621024)
			(end 12.347194 -2.321306)
			(stroke
				(width 0.1)
				(type default)
			)
			(layer "F.SilkS")
		)
		(fp_line
			(start 13.70203 -3.621024)
			(end 12.347194 -2.321306)
			(stroke
				(width 0.1)
				(type default)
			)
			(layer "F.SilkS")
		)
		(fp_line
			(start 13.70203 -3.621024)
			(end 13.690092 -3.551682)
			(stroke
				(width 0.1)
				(type default)
			)
			(layer "F.SilkS")
		)
		(fp_line
			(start 13.70203 -3.621024)
			(end 13.690092 -3.551682)
			(stroke
				(width 0.1)
				(type default)
			)
			(layer "F.SilkS")
		)
		(fp_line
			(start 13.714222 -3.690366)
			(end 12.359386 -2.390902)
			(stroke
				(width 0.1)
				(type default)
			)
			(layer "F.SilkS")
		)
		(fp_line
			(start 13.714222 -3.690366)
			(end 12.359386 -2.390902)
			(stroke
				(width 0.1)
				(type default)
			)
			(layer "F.SilkS")
		)
		(fp_line
			(start 13.714222 -3.690366)
			(end 13.70203 -3.621024)
			(stroke
				(width 0.1)
				(type default)
			)
			(layer "F.SilkS")
		)
		(fp_line
			(start 13.714222 -3.690366)
			(end 13.70203 -3.621024)
			(stroke
				(width 0.1)
				(type default)
			)
			(layer "F.SilkS")
		)
		(fp_line
			(start 13.715238 -4.383786)
			(end 12.087352 -2.822448)
			(stroke
				(width 0.1)
				(type default)
			)
			(layer "F.SilkS")
		)
		(fp_line
			(start 13.715238 -4.383786)
			(end 12.087352 -2.822448)
			(stroke
				(width 0.1)
				(type default)
			)
			(layer "F.SilkS")
		)
		(fp_line
			(start 13.722096 -4.332732)
			(end 12.135612 -2.810764)
			(stroke
				(width 0.1)
				(type default)
			)
			(layer "F.SilkS")
		)
		(fp_line
			(start 13.722096 -4.332732)
			(end 12.135612 -2.810764)
			(stroke
				(width 0.1)
				(type default)
			)
			(layer "F.SilkS")
		)
		(fp_line
			(start 13.72616 -3.759962)
			(end 12.371578 -2.460244)
			(stroke
				(width 0.1)
				(type default)
			)
			(layer "F.SilkS")
		)
		(fp_line
			(start 13.72616 -3.759962)
			(end 12.371578 -2.460244)
			(stroke
				(width 0.1)
				(type default)
			)
			(layer "F.SilkS")
		)
		(fp_line
			(start 13.729208 -4.281932)
			(end 12.181078 -2.796794)
			(stroke
				(width 0.1)
				(type default)
			)
			(layer "F.SilkS")
		)
		(fp_line
			(start 13.729208 -4.281932)
			(end 12.181078 -2.796794)
			(stroke
				(width 0.1)
				(type default)
			)
			(layer "F.SilkS")
		)
		(fp_line
			(start 13.731494 -3.822446)
			(end 12.38377 -2.529586)
			(stroke
				(width 0.1)
				(type default)
			)
			(layer "F.SilkS")
		)
		(fp_line
			(start 13.731494 -3.822446)
			(end 12.38377 -2.529586)
			(stroke
				(width 0.1)
				(type default)
			)
			(layer "F.SilkS")
		)
		(fp_line
			(start 13.73632 -4.230878)
			(end 12.224766 -2.781046)
			(stroke
				(width 0.1)
				(type default)
			)
			(layer "F.SilkS")
		)
		(fp_line
			(start 13.73632 -4.230878)
			(end 12.224766 -2.781046)
			(stroke
				(width 0.1)
				(type default)
			)
			(layer "F.SilkS")
		)
		(fp_line
			(start 13.736574 -3.88493)
			(end 12.395962 -2.598928)
			(stroke
				(width 0.1)
				(type default)
			)
			(layer "F.SilkS")
		)
		(fp_line
			(start 13.736574 -3.88493)
			(end 12.395962 -2.598928)
			(stroke
				(width 0.1)
				(type default)
			)
			(layer "F.SilkS")
		)
		(fp_line
			(start 13.741654 -3.947668)
			(end 12.408154 -2.668524)
			(stroke
				(width 0.1)
				(type default)
			)
			(layer "F.SilkS")
		)
		(fp_line
			(start 13.741654 -3.947668)
			(end 12.408154 -2.668524)
			(stroke
				(width 0.1)
				(type default)
			)
			(layer "F.SilkS")
		)
		(fp_line
			(start 13.743178 -4.179824)
			(end 12.266422 -2.76352)
			(stroke
				(width 0.1)
				(type default)
			)
			(layer "F.SilkS")
		)
		(fp_line
			(start 13.743178 -4.179824)
			(end 12.266422 -2.76352)
			(stroke
				(width 0.1)
				(type default)
			)
			(layer "F.SilkS")
		)
		(fp_line
			(start 13.74648 -4.010152)
			(end 12.380214 -2.699512)
			(stroke
				(width 0.1)
				(type default)
			)
			(layer "F.SilkS")
		)
		(fp_line
			(start 13.74648 -4.010152)
			(end 12.380214 -2.699512)
			(stroke
				(width 0.1)
				(type default)
			)
			(layer "F.SilkS")
		)
		(fp_line
			(start 13.750036 -4.12877)
			(end 12.306046 -2.743454)
			(stroke
				(width 0.1)
				(type default)
			)
			(layer "F.SilkS")
		)
		(fp_line
			(start 13.750036 -4.12877)
			(end 12.306046 -2.743454)
			(stroke
				(width 0.1)
				(type default)
			)
			(layer "F.SilkS")
		)
		(fp_line
			(start 13.751814 -4.072636)
			(end 12.344654 -2.722626)
			(stroke
				(width 0.1)
				(type default)
			)
			(layer "F.SilkS")
		)
		(fp_line
			(start 13.751814 -4.072636)
			(end 12.344654 -2.722626)
			(stroke
				(width 0.1)
				(type default)
			)
			(layer "F.SilkS")
		)
		(fp_line
			(start 13.944854 -0.882904)
			(end 13.976096 -0.882904)
			(stroke
				(width 0.1)
				(type default)
			)
			(layer "F.SilkS")
		)
		(fp_line
			(start 13.944854 -0.882904)
			(end 13.976096 -0.882904)
			(stroke
				(width 0.1)
				(type default)
			)
			(layer "F.SilkS")
		)
		(fp_line
			(start 13.95095 -0.916178)
			(end 13.944854 -0.882904)
			(stroke
				(width 0.1)
				(type default)
			)
			(layer "F.SilkS")
		)
		(fp_line
			(start 13.95095 -0.916178)
			(end 13.944854 -0.882904)
			(stroke
				(width 0.1)
				(type default)
			)
			(layer "F.SilkS")
		)
		(fp_line
			(start 13.95095 -0.916178)
			(end 15.307056 -2.21742)
			(stroke
				(width 0.1)
				(type default)
			)
			(layer "F.SilkS")
		)
		(fp_line
			(start 13.95095 -0.916178)
			(end 15.307056 -2.21742)
			(stroke
				(width 0.1)
				(type default)
			)
			(layer "F.SilkS")
		)
		(fp_line
			(start 13.962888 -0.985774)
			(end 13.95095 -0.916178)
			(stroke
				(width 0.1)
				(type default)
			)
			(layer "F.SilkS")
		)
		(fp_line
			(start 13.962888 -0.985774)
			(end 13.95095 -0.916178)
			(stroke
				(width 0.1)
				(type default)
			)
			(layer "F.SilkS")
		)
		(fp_line
			(start 13.962888 -0.985774)
			(end 15.319248 -2.286762)
			(stroke
				(width 0.1)
				(type default)
			)
			(layer "F.SilkS")
		)
		(fp_line
			(start 13.962888 -0.985774)
			(end 15.319248 -2.286762)
			(stroke
				(width 0.1)
				(type default)
			)
			(layer "F.SilkS")
		)
		(fp_line
			(start 13.975334 -1.055116)
			(end 13.962888 -0.985774)
			(stroke
				(width 0.1)
				(type default)
			)
			(layer "F.SilkS")
		)
		(fp_line
			(start 13.975334 -1.055116)
			(end 13.962888 -0.985774)
			(stroke
				(width 0.1)
				(type default)
			)
			(layer "F.SilkS")
		)
		(fp_line
			(start 13.975334 -1.055116)
			(end 15.331186 -2.356104)
			(stroke
				(width 0.1)
				(type default)
			)
			(layer "F.SilkS")
		)
		(fp_line
			(start 13.975334 -1.055116)
			(end 15.331186 -2.356104)
			(stroke
				(width 0.1)
				(type default)
			)
			(layer "F.SilkS")
		)
		(fp_line
			(start 13.976096 -0.882904)
			(end 14.036294 -0.882904)
			(stroke
				(width 0.1)
				(type default)
			)
			(layer "F.SilkS")
		)
		(fp_line
			(start 13.976096 -0.882904)
			(end 14.036294 -0.882904)
			(stroke
				(width 0.1)
				(type default)
			)
			(layer "F.SilkS")
		)
		(fp_line
			(start 13.976096 -0.882904)
			(end 15.294864 -2.147824)
			(stroke
				(width 0.1)
				(type default)
			)
			(layer "F.SilkS")
		)
		(fp_line
			(start 13.976096 -0.882904)
			(end 15.294864 -2.147824)
			(stroke
				(width 0.1)
				(type default)
			)
			(layer "F.SilkS")
		)
		(fp_line
			(start 13.987272 -1.124458)
			(end 13.975334 -1.055116)
			(stroke
				(width 0.1)
				(type default)
			)
			(layer "F.SilkS")
		)
		(fp_line
			(start 13.987272 -1.124458)
			(end 13.975334 -1.055116)
			(stroke
				(width 0.1)
				(type default)
			)
			(layer "F.SilkS")
		)
		(fp_line
			(start 13.987272 -1.124458)
			(end 15.343632 -2.425446)
			(stroke
				(width 0.1)
				(type default)
			)
			(layer "F.SilkS")
		)
		(fp_line
			(start 13.987272 -1.124458)
			(end 15.343632 -2.425446)
			(stroke
				(width 0.1)
				(type default)
			)
			(layer "F.SilkS")
		)
		(fp_line
			(start 13.999464 -1.194054)
			(end 13.987272 -1.124458)
			(stroke
				(width 0.1)
				(type default)
			)
			(layer "F.SilkS")
		)
		(fp_line
			(start 13.999464 -1.194054)
			(end 13.987272 -1.124458)
			(stroke
				(width 0.1)
				(type default)
			)
			(layer "F.SilkS")
		)
		(fp_line
			(start 13.999464 -1.194054)
			(end 15.355824 -2.495042)
			(stroke
				(width 0.1)
				(type default)
			)
			(layer "F.SilkS")
		)
		(fp_line
			(start 13.999464 -1.194054)
			(end 15.355824 -2.495042)
			(stroke
				(width 0.1)
				(type default)
			)
			(layer "F.SilkS")
		)
		(fp_line
			(start 14.01191 -1.26365)
			(end 13.999464 -1.194054)
			(stroke
				(width 0.1)
				(type default)
			)
			(layer "F.SilkS")
		)
		(fp_line
			(start 14.01191 -1.26365)
			(end 13.999464 -1.194054)
			(stroke
				(width 0.1)
				(type default)
			)
			(layer "F.SilkS")
		)
		(fp_line
			(start 14.01191 -1.26365)
			(end 15.367762 -2.564384)
			(stroke
				(width 0.1)
				(type default)
			)
			(layer "F.SilkS")
		)
		(fp_line
			(start 14.01191 -1.26365)
			(end 15.367762 -2.564384)
			(stroke
				(width 0.1)
				(type default)
			)
			(layer "F.SilkS")
		)
		(fp_line
			(start 14.023848 -1.332738)
			(end 14.01191 -1.26365)
			(stroke
				(width 0.1)
				(type default)
			)
			(layer "F.SilkS")
		)
		(fp_line
			(start 14.023848 -1.332738)
			(end 14.01191 -1.26365)
			(stroke
				(width 0.1)
				(type default)
			)
			(layer "F.SilkS")
		)
		(fp_line
			(start 14.023848 -1.332738)
			(end 15.380208 -2.633726)
			(stroke
				(width 0.1)
				(type default)
			)
			(layer "F.SilkS")
		)
		(fp_line
			(start 14.023848 -1.332738)
			(end 15.380208 -2.633726)
			(stroke
				(width 0.1)
				(type default)
			)
			(layer "F.SilkS")
		)
		(fp_line
			(start 14.03604 -1.40208)
			(end 14.023848 -1.332738)
			(stroke
				(width 0.1)
				(type default)
			)
			(layer "F.SilkS")
		)
		(fp_line
			(start 14.03604 -1.40208)
			(end 14.023848 -1.332738)
			(stroke
				(width 0.1)
				(type default)
			)
			(layer "F.SilkS")
		)
		(fp_line
			(start 14.03604 -1.40208)
			(end 15.392654 -2.703322)
			(stroke
				(width 0.1)
				(type default)
			)
			(layer "F.SilkS")
		)
		(fp_line
			(start 14.03604 -1.40208)
			(end 15.392654 -2.703322)
			(stroke
				(width 0.1)
				(type default)
			)
			(layer "F.SilkS")
		)
		(fp_line
			(start 14.036294 -0.882904)
			(end 14.096238 -0.882904)
			(stroke
				(width 0.1)
				(type default)
			)
			(layer "F.SilkS")
		)
		(fp_line
			(start 14.036294 -0.882904)
			(end 14.096238 -0.882904)
			(stroke
				(width 0.1)
				(type default)
			)
			(layer "F.SilkS")
		)
		(fp_line
			(start 14.036294 -0.882904)
			(end 15.282418 -2.078482)
			(stroke
				(width 0.1)
				(type default)
			)
			(layer "F.SilkS")
		)
		(fp_line
			(start 14.036294 -0.882904)
			(end 15.282418 -2.078482)
			(stroke
				(width 0.1)
				(type default)
			)
			(layer "F.SilkS")
		)
		(fp_line
			(start 14.048232 -1.471676)
			(end 14.03604 -1.40208)
			(stroke
				(width 0.1)
				(type default)
			)
			(layer "F.SilkS")
		)
		(fp_line
			(start 14.048232 -1.471676)
			(end 14.03604 -1.40208)
			(stroke
				(width 0.1)
				(type default)
			)
			(layer "F.SilkS")
		)
		(fp_line
			(start 14.048232 -1.471676)
			(end 15.404592 -2.772664)
			(stroke
				(width 0.1)
				(type default)
			)
			(layer "F.SilkS")
		)
		(fp_line
			(start 14.048232 -1.471676)
			(end 15.404592 -2.772664)
			(stroke
				(width 0.1)
				(type default)
			)
			(layer "F.SilkS")
		)
		(fp_line
			(start 14.060678 -1.541018)
			(end 14.048232 -1.471676)
			(stroke
				(width 0.1)
				(type default)
			)
			(layer "F.SilkS")
		)
		(fp_line
			(start 14.060678 -1.541018)
			(end 14.048232 -1.471676)
			(stroke
				(width 0.1)
				(type default)
			)
			(layer "F.SilkS")
		)
		(fp_line
			(start 14.060678 -1.541018)
			(end 15.416784 -2.84226)
			(stroke
				(width 0.1)
				(type default)
			)
			(layer "F.SilkS")
		)
		(fp_line
			(start 14.060678 -1.541018)
			(end 15.416784 -2.84226)
			(stroke
				(width 0.1)
				(type default)
			)
			(layer "F.SilkS")
		)
		(fp_line
			(start 14.072362 -1.61036)
			(end 14.060678 -1.541018)
			(stroke
				(width 0.1)
				(type default)
			)
			(layer "F.SilkS")
		)
		(fp_line
			(start 14.072362 -1.61036)
			(end 14.060678 -1.541018)
			(stroke
				(width 0.1)
				(type default)
			)
			(layer "F.SilkS")
		)
		(fp_line
			(start 14.072362 -1.61036)
			(end 15.42923 -2.911602)
			(stroke
				(width 0.1)
				(type default)
			)
			(layer "F.SilkS")
		)
		(fp_line
			(start 14.072362 -1.61036)
			(end 15.42923 -2.911602)
			(stroke
				(width 0.1)
				(type default)
			)
			(layer "F.SilkS")
		)
		(fp_line
			(start 14.084808 -1.679702)
			(end 14.072362 -1.61036)
			(stroke
				(width 0.1)
				(type default)
			)
			(layer "F.SilkS")
		)
		(fp_line
			(start 14.084808 -1.679702)
			(end 14.072362 -1.61036)
			(stroke
				(width 0.1)
				(type default)
			)
			(layer "F.SilkS")
		)
		(fp_line
			(start 14.084808 -1.679702)
			(end 14.097254 -1.749044)
			(stroke
				(width 0.1)
				(type default)
			)
			(layer "F.SilkS")
		)
		(fp_line
			(start 14.084808 -1.679702)
			(end 14.097254 -1.749044)
			(stroke
				(width 0.1)
				(type default)
			)
			(layer "F.SilkS")
		)
		(fp_line
			(start 14.096238 -0.882904)
			(end 14.156436 -0.882904)
			(stroke
				(width 0.1)
				(type default)
			)
			(layer "F.SilkS")
		)
		(fp_line
			(start 14.096238 -0.882904)
			(end 14.156436 -0.882904)
			(stroke
				(width 0.1)
				(type default)
			)
			(layer "F.SilkS")
		)
		(fp_line
			(start 14.096238 -0.882904)
			(end 15.270226 -2.00914)
			(stroke
				(width 0.1)
				(type default)
			)
			(layer "F.SilkS")
		)
		(fp_line
			(start 14.096238 -0.882904)
			(end 15.270226 -2.00914)
			(stroke
				(width 0.1)
				(type default)
			)
			(layer "F.SilkS")
		)
		(fp_line
			(start 14.109192 -1.81864)
			(end 14.097254 -1.749044)
			(stroke
				(width 0.1)
				(type default)
			)
			(layer "F.SilkS")
		)
		(fp_line
			(start 14.109192 -1.81864)
			(end 14.097254 -1.749044)
			(stroke
				(width 0.1)
				(type default)
			)
			(layer "F.SilkS")
		)
		(fp_line
			(start 14.121384 -1.887982)
			(end 14.109192 -1.81864)
			(stroke
				(width 0.1)
				(type default)
			)
			(layer "F.SilkS")
		)
		(fp_line
			(start 14.121384 -1.887982)
			(end 14.109192 -1.81864)
			(stroke
				(width 0.1)
				(type default)
			)
			(layer "F.SilkS")
		)
		(fp_line
			(start 14.13383 -1.957324)
			(end 14.121384 -1.887982)
			(stroke
				(width 0.1)
				(type default)
			)
			(layer "F.SilkS")
		)
		(fp_line
			(start 14.13383 -1.957324)
			(end 14.121384 -1.887982)
			(stroke
				(width 0.1)
				(type default)
			)
			(layer "F.SilkS")
		)
		(fp_line
			(start 14.145768 -2.02692)
			(end 14.13383 -1.957324)
			(stroke
				(width 0.1)
				(type default)
			)
			(layer "F.SilkS")
		)
		(fp_line
			(start 14.145768 -2.02692)
			(end 14.13383 -1.957324)
			(stroke
				(width 0.1)
				(type default)
			)
			(layer "F.SilkS")
		)
		(fp_line
			(start 14.156436 -0.882904)
			(end 14.216888 -0.882904)
			(stroke
				(width 0.1)
				(type default)
			)
			(layer "F.SilkS")
		)
		(fp_line
			(start 14.156436 -0.882904)
			(end 14.216888 -0.882904)
			(stroke
				(width 0.1)
				(type default)
			)
			(layer "F.SilkS")
		)
		(fp_line
			(start 14.156436 -0.882904)
			(end 15.258288 -1.939544)
			(stroke
				(width 0.1)
				(type default)
			)
			(layer "F.SilkS")
		)
		(fp_line
			(start 14.156436 -0.882904)
			(end 15.258288 -1.939544)
			(stroke
				(width 0.1)
				(type default)
			)
			(layer "F.SilkS")
		)
		(fp_line
			(start 14.15796 -2.096262)
			(end 14.145768 -2.02692)
			(stroke
				(width 0.1)
				(type default)
			)
			(layer "F.SilkS")
		)
		(fp_line
			(start 14.15796 -2.096262)
			(end 14.145768 -2.02692)
			(stroke
				(width 0.1)
				(type default)
			)
			(layer "F.SilkS")
		)
		(fp_line
			(start 14.170406 -2.165604)
			(end 14.15796 -2.096262)
			(stroke
				(width 0.1)
				(type default)
			)
			(layer "F.SilkS")
		)
		(fp_line
			(start 14.170406 -2.165604)
			(end 14.15796 -2.096262)
			(stroke
				(width 0.1)
				(type default)
			)
			(layer "F.SilkS")
		)
		(fp_line
			(start 14.182344 -2.234946)
			(end 14.170406 -2.165604)
			(stroke
				(width 0.1)
				(type default)
			)
			(layer "F.SilkS")
		)
		(fp_line
			(start 14.182344 -2.234946)
			(end 14.170406 -2.165604)
			(stroke
				(width 0.1)
				(type default)
			)
			(layer "F.SilkS")
		)
		(fp_line
			(start 14.194282 -2.304288)
			(end 14.182344 -2.234946)
			(stroke
				(width 0.1)
				(type default)
			)
			(layer "F.SilkS")
		)
		(fp_line
			(start 14.194282 -2.304288)
			(end 14.182344 -2.234946)
			(stroke
				(width 0.1)
				(type default)
			)
			(layer "F.SilkS")
		)
		(fp_line
			(start 14.206728 -2.373884)
			(end 14.194282 -2.304288)
			(stroke
				(width 0.1)
				(type default)
			)
			(layer "F.SilkS")
		)
		(fp_line
			(start 14.206728 -2.373884)
			(end 14.194282 -2.304288)
			(stroke
				(width 0.1)
				(type default)
			)
			(layer "F.SilkS")
		)
		(fp_line
			(start 14.216888 -0.882904)
			(end 14.277086 -0.882904)
			(stroke
				(width 0.1)
				(type default)
			)
			(layer "F.SilkS")
		)
		(fp_line
			(start 14.216888 -0.882904)
			(end 14.277086 -0.882904)
			(stroke
				(width 0.1)
				(type default)
			)
			(layer "F.SilkS")
		)
		(fp_line
			(start 14.216888 -0.882904)
			(end 15.245842 -1.869948)
			(stroke
				(width 0.1)
				(type default)
			)
			(layer "F.SilkS")
		)
		(fp_line
			(start 14.216888 -0.882904)
			(end 15.245842 -1.869948)
			(stroke
				(width 0.1)
				(type default)
			)
			(layer "F.SilkS")
		)
		(fp_line
			(start 14.21892 -2.443226)
			(end 14.206728 -2.373884)
			(stroke
				(width 0.1)
				(type default)
			)
			(layer "F.SilkS")
		)
		(fp_line
			(start 14.21892 -2.443226)
			(end 14.206728 -2.373884)
			(stroke
				(width 0.1)
				(type default)
			)
			(layer "F.SilkS")
		)
		(fp_line
			(start 14.230858 -2.512314)
			(end 14.21892 -2.443226)
			(stroke
				(width 0.1)
				(type default)
			)
			(layer "F.SilkS")
		)
		(fp_line
			(start 14.230858 -2.512314)
			(end 14.21892 -2.443226)
			(stroke
				(width 0.1)
				(type default)
			)
			(layer "F.SilkS")
		)
		(fp_line
			(start 14.243304 -2.58191)
			(end 14.230858 -2.512314)
			(stroke
				(width 0.1)
				(type default)
			)
			(layer "F.SilkS")
		)
		(fp_line
			(start 14.243304 -2.58191)
			(end 14.230858 -2.512314)
			(stroke
				(width 0.1)
				(type default)
			)
			(layer "F.SilkS")
		)
		(fp_line
			(start 14.255496 -2.651506)
			(end 14.243304 -2.58191)
			(stroke
				(width 0.1)
				(type default)
			)
			(layer "F.SilkS")
		)
		(fp_line
			(start 14.255496 -2.651506)
			(end 14.243304 -2.58191)
			(stroke
				(width 0.1)
				(type default)
			)
			(layer "F.SilkS")
		)
		(fp_line
			(start 14.267434 -2.720594)
			(end 14.255496 -2.651506)
			(stroke
				(width 0.1)
				(type default)
			)
			(layer "F.SilkS")
		)
		(fp_line
			(start 14.267434 -2.720594)
			(end 14.255496 -2.651506)
			(stroke
				(width 0.1)
				(type default)
			)
			(layer "F.SilkS")
		)
		(fp_line
			(start 14.277086 -0.882904)
			(end 14.33703 -0.882904)
			(stroke
				(width 0.1)
				(type default)
			)
			(layer "F.SilkS")
		)
		(fp_line
			(start 14.277086 -0.882904)
			(end 14.33703 -0.882904)
			(stroke
				(width 0.1)
				(type default)
			)
			(layer "F.SilkS")
		)
		(fp_line
			(start 14.277086 -0.882904)
			(end 15.233396 -1.800606)
			(stroke
				(width 0.1)
				(type default)
			)
			(layer "F.SilkS")
		)
		(fp_line
			(start 14.277086 -0.882904)
			(end 15.233396 -1.800606)
			(stroke
				(width 0.1)
				(type default)
			)
			(layer "F.SilkS")
		)
		(fp_line
			(start 14.27988 -2.79019)
			(end 14.267434 -2.720594)
			(stroke
				(width 0.1)
				(type default)
			)
			(layer "F.SilkS")
		)
		(fp_line
			(start 14.27988 -2.79019)
			(end 14.267434 -2.720594)
			(stroke
				(width 0.1)
				(type default)
			)
			(layer "F.SilkS")
		)
		(fp_line
			(start 14.291818 -2.859532)
			(end 14.27988 -2.79019)
			(stroke
				(width 0.1)
				(type default)
			)
			(layer "F.SilkS")
		)
		(fp_line
			(start 14.291818 -2.859532)
			(end 14.27988 -2.79019)
			(stroke
				(width 0.1)
				(type default)
			)
			(layer "F.SilkS")
		)
		(fp_line
			(start 14.30401 -2.928874)
			(end 14.291818 -2.859532)
			(stroke
				(width 0.1)
				(type default)
			)
			(layer "F.SilkS")
		)
		(fp_line
			(start 14.30401 -2.928874)
			(end 14.291818 -2.859532)
			(stroke
				(width 0.1)
				(type default)
			)
			(layer "F.SilkS")
		)
		(fp_line
			(start 14.316456 -2.998216)
			(end 14.30401 -2.928874)
			(stroke
				(width 0.1)
				(type default)
			)
			(layer "F.SilkS")
		)
		(fp_line
			(start 14.316456 -2.998216)
			(end 14.30401 -2.928874)
			(stroke
				(width 0.1)
				(type default)
			)
			(layer "F.SilkS")
		)
		(fp_line
			(start 14.328394 -3.067558)
			(end 14.316456 -2.998216)
			(stroke
				(width 0.1)
				(type default)
			)
			(layer "F.SilkS")
		)
		(fp_line
			(start 14.328394 -3.067558)
			(end 14.316456 -2.998216)
			(stroke
				(width 0.1)
				(type default)
			)
			(layer "F.SilkS")
		)
		(fp_line
			(start 14.33703 -0.882904)
			(end 14.396974 -0.882904)
			(stroke
				(width 0.1)
				(type default)
			)
			(layer "F.SilkS")
		)
		(fp_line
			(start 14.33703 -0.882904)
			(end 14.396974 -0.882904)
			(stroke
				(width 0.1)
				(type default)
			)
			(layer "F.SilkS")
		)
		(fp_line
			(start 14.33703 -0.882904)
			(end 15.221458 -1.731518)
			(stroke
				(width 0.1)
				(type default)
			)
			(layer "F.SilkS")
		)
		(fp_line
			(start 14.33703 -0.882904)
			(end 15.221458 -1.731518)
			(stroke
				(width 0.1)
				(type default)
			)
			(layer "F.SilkS")
		)
		(fp_line
			(start 14.340586 -3.137154)
			(end 14.328394 -3.067558)
			(stroke
				(width 0.1)
				(type default)
			)
			(layer "F.SilkS")
		)
		(fp_line
			(start 14.340586 -3.137154)
			(end 14.328394 -3.067558)
			(stroke
				(width 0.1)
				(type default)
			)
			(layer "F.SilkS")
		)
		(fp_line
			(start 14.352778 -3.206496)
			(end 14.340586 -3.137154)
			(stroke
				(width 0.1)
				(type default)
			)
			(layer "F.SilkS")
		)
		(fp_line
			(start 14.352778 -3.206496)
			(end 14.340586 -3.137154)
			(stroke
				(width 0.1)
				(type default)
			)
			(layer "F.SilkS")
		)
		(fp_line
			(start 14.36497 -3.275838)
			(end 14.352778 -3.206496)
			(stroke
				(width 0.1)
				(type default)
			)
			(layer "F.SilkS")
		)
		(fp_line
			(start 14.36497 -3.275838)
			(end 14.352778 -3.206496)
			(stroke
				(width 0.1)
				(type default)
			)
			(layer "F.SilkS")
		)
		(fp_line
			(start 14.376908 -3.34518)
			(end 14.36497 -3.275838)
			(stroke
				(width 0.1)
				(type default)
			)
			(layer "F.SilkS")
		)
		(fp_line
			(start 14.376908 -3.34518)
			(end 14.36497 -3.275838)
			(stroke
				(width 0.1)
				(type default)
			)
			(layer "F.SilkS")
		)
		(fp_line
			(start 14.389354 -3.414776)
			(end 14.376908 -3.34518)
			(stroke
				(width 0.1)
				(type default)
			)
			(layer "F.SilkS")
		)
		(fp_line
			(start 14.389354 -3.414776)
			(end 14.376908 -3.34518)
			(stroke
				(width 0.1)
				(type default)
			)
			(layer "F.SilkS")
		)
		(fp_line
			(start 14.396974 -0.882904)
			(end 14.45768 -0.882904)
			(stroke
				(width 0.1)
				(type default)
			)
			(layer "F.SilkS")
		)
		(fp_line
			(start 14.396974 -0.882904)
			(end 14.45768 -0.882904)
			(stroke
				(width 0.1)
				(type default)
			)
			(layer "F.SilkS")
		)
		(fp_line
			(start 14.396974 -0.882904)
			(end 15.209266 -1.661922)
			(stroke
				(width 0.1)
				(type default)
			)
			(layer "F.SilkS")
		)
		(fp_line
			(start 14.396974 -0.882904)
			(end 15.209266 -1.661922)
			(stroke
				(width 0.1)
				(type default)
			)
			(layer "F.SilkS")
		)
		(fp_line
			(start 14.401546 -3.484118)
			(end 14.389354 -3.414776)
			(stroke
				(width 0.1)
				(type default)
			)
			(layer "F.SilkS")
		)
		(fp_line
			(start 14.401546 -3.484118)
			(end 14.389354 -3.414776)
			(stroke
				(width 0.1)
				(type default)
			)
			(layer "F.SilkS")
		)
		(fp_line
			(start 14.413484 -3.55346)
			(end 14.401546 -3.484118)
			(stroke
				(width 0.1)
				(type default)
			)
			(layer "F.SilkS")
		)
		(fp_line
			(start 14.413484 -3.55346)
			(end 14.401546 -3.484118)
			(stroke
				(width 0.1)
				(type default)
			)
			(layer "F.SilkS")
		)
		(fp_line
			(start 14.42593 -3.622802)
			(end 14.413484 -3.55346)
			(stroke
				(width 0.1)
				(type default)
			)
			(layer "F.SilkS")
		)
		(fp_line
			(start 14.42593 -3.622802)
			(end 14.413484 -3.55346)
			(stroke
				(width 0.1)
				(type default)
			)
			(layer "F.SilkS")
		)
		(fp_line
			(start 14.438376 -3.692398)
			(end 14.42593 -3.622802)
			(stroke
				(width 0.1)
				(type default)
			)
			(layer "F.SilkS")
		)
		(fp_line
			(start 14.438376 -3.692398)
			(end 14.42593 -3.622802)
			(stroke
				(width 0.1)
				(type default)
			)
			(layer "F.SilkS")
		)
		(fp_line
			(start 14.45006 -3.76174)
			(end 14.438376 -3.692398)
			(stroke
				(width 0.1)
				(type default)
			)
			(layer "F.SilkS")
		)
		(fp_line
			(start 14.45006 -3.76174)
			(end 14.438376 -3.692398)
			(stroke
				(width 0.1)
				(type default)
			)
			(layer "F.SilkS")
		)
		(fp_line
			(start 14.45768 -0.882904)
			(end 14.517624 -0.882904)
			(stroke
				(width 0.1)
				(type default)
			)
			(layer "F.SilkS")
		)
		(fp_line
			(start 14.45768 -0.882904)
			(end 14.517624 -0.882904)
			(stroke
				(width 0.1)
				(type default)
			)
			(layer "F.SilkS")
		)
		(fp_line
			(start 14.45768 -0.882904)
			(end 15.19682 -1.592326)
			(stroke
				(width 0.1)
				(type default)
			)
			(layer "F.SilkS")
		)
		(fp_line
			(start 14.45768 -0.882904)
			(end 15.19682 -1.592326)
			(stroke
				(width 0.1)
				(type default)
			)
			(layer "F.SilkS")
		)
		(fp_line
			(start 14.462506 -3.831082)
			(end 14.45006 -3.76174)
			(stroke
				(width 0.1)
				(type default)
			)
			(layer "F.SilkS")
		)
		(fp_line
			(start 14.462506 -3.831082)
			(end 14.45006 -3.76174)
			(stroke
				(width 0.1)
				(type default)
			)
			(layer "F.SilkS")
		)
		(fp_line
			(start 14.474952 -3.900424)
			(end 14.462506 -3.831082)
			(stroke
				(width 0.1)
				(type default)
			)
			(layer "F.SilkS")
		)
		(fp_line
			(start 14.474952 -3.900424)
			(end 14.462506 -3.831082)
			(stroke
				(width 0.1)
				(type default)
			)
			(layer "F.SilkS")
		)
		(fp_line
			(start 14.486636 -3.969766)
			(end 14.474952 -3.900424)
			(stroke
				(width 0.1)
				(type default)
			)
			(layer "F.SilkS")
		)
		(fp_line
			(start 14.486636 -3.969766)
			(end 14.474952 -3.900424)
			(stroke
				(width 0.1)
				(type default)
			)
			(layer "F.SilkS")
		)
		(fp_line
			(start 14.498828 -4.039362)
			(end 14.486636 -3.969766)
			(stroke
				(width 0.1)
				(type default)
			)
			(layer "F.SilkS")
		)
		(fp_line
			(start 14.498828 -4.039362)
			(end 14.486636 -3.969766)
			(stroke
				(width 0.1)
				(type default)
			)
			(layer "F.SilkS")
		)
		(fp_line
			(start 14.511274 -4.108704)
			(end 14.498828 -4.039362)
			(stroke
				(width 0.1)
				(type default)
			)
			(layer "F.SilkS")
		)
		(fp_line
			(start 14.511274 -4.108704)
			(end 14.498828 -4.039362)
			(stroke
				(width 0.1)
				(type default)
			)
			(layer "F.SilkS")
		)
		(fp_line
			(start 14.517624 -0.882904)
			(end 14.577568 -0.882904)
			(stroke
				(width 0.1)
				(type default)
			)
			(layer "F.SilkS")
		)
		(fp_line
			(start 14.517624 -0.882904)
			(end 14.577568 -0.882904)
			(stroke
				(width 0.1)
				(type default)
			)
			(layer "F.SilkS")
		)
		(fp_line
			(start 14.517624 -0.882904)
			(end 15.184882 -1.522984)
			(stroke
				(width 0.1)
				(type default)
			)
			(layer "F.SilkS")
		)
		(fp_line
			(start 14.517624 -0.882904)
			(end 15.184882 -1.522984)
			(stroke
				(width 0.1)
				(type default)
			)
			(layer "F.SilkS")
		)
		(fp_line
			(start 14.523466 -4.178046)
			(end 14.511274 -4.108704)
			(stroke
				(width 0.1)
				(type default)
			)
			(layer "F.SilkS")
		)
		(fp_line
			(start 14.523466 -4.178046)
			(end 14.511274 -4.108704)
			(stroke
				(width 0.1)
				(type default)
			)
			(layer "F.SilkS")
		)
		(fp_line
			(start 14.523466 -4.178046)
			(end 14.535404 -4.247388)
			(stroke
				(width 0.1)
				(type default)
			)
			(layer "F.SilkS")
		)
		(fp_line
			(start 14.523466 -4.178046)
			(end 14.535404 -4.247388)
			(stroke
				(width 0.1)
				(type default)
			)
			(layer "F.SilkS")
		)
		(fp_line
			(start 14.535404 -4.247388)
			(end 14.54785 -4.316984)
			(stroke
				(width 0.1)
				(type default)
			)
			(layer "F.SilkS")
		)
		(fp_line
			(start 14.535404 -4.247388)
			(end 14.54785 -4.316984)
			(stroke
				(width 0.1)
				(type default)
			)
			(layer "F.SilkS")
		)
		(fp_line
			(start 14.54785 -4.316984)
			(end 14.560042 -4.386326)
			(stroke
				(width 0.1)
				(type default)
			)
			(layer "F.SilkS")
		)
		(fp_line
			(start 14.54785 -4.316984)
			(end 14.560042 -4.386326)
			(stroke
				(width 0.1)
				(type default)
			)
			(layer "F.SilkS")
		)
		(fp_line
			(start 14.560042 -4.386326)
			(end 14.57198 -4.455668)
			(stroke
				(width 0.1)
				(type default)
			)
			(layer "F.SilkS")
		)
		(fp_line
			(start 14.560042 -4.386326)
			(end 14.57198 -4.455668)
			(stroke
				(width 0.1)
				(type default)
			)
			(layer "F.SilkS")
		)
		(fp_line
			(start 14.57198 -4.455668)
			(end 14.584426 -4.52501)
			(stroke
				(width 0.1)
				(type default)
			)
			(layer "F.SilkS")
		)
		(fp_line
			(start 14.57198 -4.455668)
			(end 14.584426 -4.52501)
			(stroke
				(width 0.1)
				(type default)
			)
			(layer "F.SilkS")
		)
		(fp_line
			(start 14.577568 -0.882904)
			(end 14.637766 -0.882904)
			(stroke
				(width 0.1)
				(type default)
			)
			(layer "F.SilkS")
		)
		(fp_line
			(start 14.577568 -0.882904)
			(end 14.637766 -0.882904)
			(stroke
				(width 0.1)
				(type default)
			)
			(layer "F.SilkS")
		)
		(fp_line
			(start 14.577568 -0.882904)
			(end 15.17269 -1.453642)
			(stroke
				(width 0.1)
				(type default)
			)
			(layer "F.SilkS")
		)
		(fp_line
			(start 14.577568 -0.882904)
			(end 15.17269 -1.453642)
			(stroke
				(width 0.1)
				(type default)
			)
			(layer "F.SilkS")
		)
		(fp_line
			(start 14.584426 -4.52501)
			(end 14.596364 -4.594352)
			(stroke
				(width 0.1)
				(type default)
			)
			(layer "F.SilkS")
		)
		(fp_line
			(start 14.584426 -4.52501)
			(end 14.596364 -4.594352)
			(stroke
				(width 0.1)
				(type default)
			)
			(layer "F.SilkS")
		)
		(fp_line
			(start 14.596364 -4.594352)
			(end 14.608556 -4.663948)
			(stroke
				(width 0.1)
				(type default)
			)
			(layer "F.SilkS")
		)
		(fp_line
			(start 14.596364 -4.594352)
			(end 14.608556 -4.663948)
			(stroke
				(width 0.1)
				(type default)
			)
			(layer "F.SilkS")
		)
		(fp_line
			(start 14.608556 -4.663948)
			(end 14.621002 -4.733036)
			(stroke
				(width 0.1)
				(type default)
			)
			(layer "F.SilkS")
		)
		(fp_line
			(start 14.608556 -4.663948)
			(end 14.621002 -4.733036)
			(stroke
				(width 0.1)
				(type default)
			)
			(layer "F.SilkS")
		)
		(fp_line
			(start 14.621002 -4.733036)
			(end 14.63294 -4.802632)
			(stroke
				(width 0.1)
				(type default)
			)
			(layer "F.SilkS")
		)
		(fp_line
			(start 14.621002 -4.733036)
			(end 14.63294 -4.802632)
			(stroke
				(width 0.1)
				(type default)
			)
			(layer "F.SilkS")
		)
		(fp_line
			(start 14.63294 -4.802632)
			(end 14.645132 -4.872228)
			(stroke
				(width 0.1)
				(type default)
			)
			(layer "F.SilkS")
		)
		(fp_line
			(start 14.63294 -4.802632)
			(end 14.645132 -4.872228)
			(stroke
				(width 0.1)
				(type default)
			)
			(layer "F.SilkS")
		)
		(fp_line
			(start 14.637766 -0.882904)
			(end 14.697964 -0.882904)
			(stroke
				(width 0.1)
				(type default)
			)
			(layer "F.SilkS")
		)
		(fp_line
			(start 14.637766 -0.882904)
			(end 14.697964 -0.882904)
			(stroke
				(width 0.1)
				(type default)
			)
			(layer "F.SilkS")
		)
		(fp_line
			(start 14.637766 -0.882904)
			(end 15.160498 -1.384046)
			(stroke
				(width 0.1)
				(type default)
			)
			(layer "F.SilkS")
		)
		(fp_line
			(start 14.637766 -0.882904)
			(end 15.160498 -1.384046)
			(stroke
				(width 0.1)
				(type default)
			)
			(layer "F.SilkS")
		)
		(fp_line
			(start 14.645132 -4.872228)
			(end 14.657324 -4.941316)
			(stroke
				(width 0.1)
				(type default)
			)
			(layer "F.SilkS")
		)
		(fp_line
			(start 14.645132 -4.872228)
			(end 14.657324 -4.941316)
			(stroke
				(width 0.1)
				(type default)
			)
			(layer "F.SilkS")
		)
		(fp_line
			(start 14.657324 -4.941316)
			(end 14.669516 -5.010912)
			(stroke
				(width 0.1)
				(type default)
			)
			(layer "F.SilkS")
		)
		(fp_line
			(start 14.657324 -4.941316)
			(end 14.669516 -5.010912)
			(stroke
				(width 0.1)
				(type default)
			)
			(layer "F.SilkS")
		)
		(fp_line
			(start 14.669516 -5.010912)
			(end 14.681454 -5.080254)
			(stroke
				(width 0.1)
				(type default)
			)
			(layer "F.SilkS")
		)
		(fp_line
			(start 14.669516 -5.010912)
			(end 14.681454 -5.080254)
			(stroke
				(width 0.1)
				(type default)
			)
			(layer "F.SilkS")
		)
		(fp_line
			(start 14.681454 -5.080254)
			(end 14.6939 -5.149596)
			(stroke
				(width 0.1)
				(type default)
			)
			(layer "F.SilkS")
		)
		(fp_line
			(start 14.681454 -5.080254)
			(end 14.6939 -5.149596)
			(stroke
				(width 0.1)
				(type default)
			)
			(layer "F.SilkS")
		)
		(fp_line
			(start 14.69771 -5.171694)
			(end 14.6939 -5.149596)
			(stroke
				(width 0.1)
				(type default)
			)
			(layer "F.SilkS")
		)
		(fp_line
			(start 14.69771 -5.171694)
			(end 14.6939 -5.149596)
			(stroke
				(width 0.1)
				(type default)
			)
			(layer "F.SilkS")
		)
		(fp_line
			(start 14.697964 -0.882904)
			(end 14.757908 -0.882904)
			(stroke
				(width 0.1)
				(type default)
			)
			(layer "F.SilkS")
		)
		(fp_line
			(start 14.697964 -0.882904)
			(end 14.757908 -0.882904)
			(stroke
				(width 0.1)
				(type default)
			)
			(layer "F.SilkS")
		)
		(fp_line
			(start 14.697964 -0.882904)
			(end 15.148052 -1.314704)
			(stroke
				(width 0.1)
				(type default)
			)
			(layer "F.SilkS")
		)
		(fp_line
			(start 14.697964 -0.882904)
			(end 15.148052 -1.314704)
			(stroke
				(width 0.1)
				(type default)
			)
			(layer "F.SilkS")
		)
		(fp_line
			(start 14.71676 -5.171694)
			(end 14.6939 -5.149596)
			(stroke
				(width 0.1)
				(type default)
			)
			(layer "F.SilkS")
		)
		(fp_line
			(start 14.71676 -5.171694)
			(end 14.6939 -5.149596)
			(stroke
				(width 0.1)
				(type default)
			)
			(layer "F.SilkS")
		)
		(fp_line
			(start 14.71676 -5.171694)
			(end 14.69771 -5.171694)
			(stroke
				(width 0.1)
				(type default)
			)
			(layer "F.SilkS")
		)
		(fp_line
			(start 14.71676 -5.171694)
			(end 14.69771 -5.171694)
			(stroke
				(width 0.1)
				(type default)
			)
			(layer "F.SilkS")
		)
		(fp_line
			(start 14.757908 -0.882904)
			(end 14.81836 -0.882904)
			(stroke
				(width 0.1)
				(type default)
			)
			(layer "F.SilkS")
		)
		(fp_line
			(start 14.757908 -0.882904)
			(end 14.81836 -0.882904)
			(stroke
				(width 0.1)
				(type default)
			)
			(layer "F.SilkS")
		)
		(fp_line
			(start 14.757908 -0.882904)
			(end 15.13586 -1.245362)
			(stroke
				(width 0.1)
				(type default)
			)
			(layer "F.SilkS")
		)
		(fp_line
			(start 14.757908 -0.882904)
			(end 15.13586 -1.245362)
			(stroke
				(width 0.1)
				(type default)
			)
			(layer "F.SilkS")
		)
		(fp_line
			(start 14.776958 -5.171694)
			(end 14.681454 -5.080254)
			(stroke
				(width 0.1)
				(type default)
			)
			(layer "F.SilkS")
		)
		(fp_line
			(start 14.776958 -5.171694)
			(end 14.681454 -5.080254)
			(stroke
				(width 0.1)
				(type default)
			)
			(layer "F.SilkS")
		)
		(fp_line
			(start 14.776958 -5.171694)
			(end 14.71676 -5.171694)
			(stroke
				(width 0.1)
				(type default)
			)
			(layer "F.SilkS")
		)
		(fp_line
			(start 14.776958 -5.171694)
			(end 14.71676 -5.171694)
			(stroke
				(width 0.1)
				(type default)
			)
			(layer "F.SilkS")
		)
		(fp_line
			(start 14.81836 -0.882904)
			(end 14.878558 -0.882904)
			(stroke
				(width 0.1)
				(type default)
			)
			(layer "F.SilkS")
		)
		(fp_line
			(start 14.81836 -0.882904)
			(end 14.878558 -0.882904)
			(stroke
				(width 0.1)
				(type default)
			)
			(layer "F.SilkS")
		)
		(fp_line
			(start 14.81836 -0.882904)
			(end 15.123922 -1.17602)
			(stroke
				(width 0.1)
				(type default)
			)
			(layer "F.SilkS")
		)
		(fp_line
			(start 14.81836 -0.882904)
			(end 15.123922 -1.17602)
			(stroke
				(width 0.1)
				(type default)
			)
			(layer "F.SilkS")
		)
		(fp_line
			(start 14.837156 -5.171694)
			(end 14.669516 -5.010912)
			(stroke
				(width 0.1)
				(type default)
			)
			(layer "F.SilkS")
		)
		(fp_line
			(start 14.837156 -5.171694)
			(end 14.669516 -5.010912)
			(stroke
				(width 0.1)
				(type default)
			)
			(layer "F.SilkS")
		)
		(fp_line
			(start 14.837156 -5.171694)
			(end 14.776958 -5.171694)
			(stroke
				(width 0.1)
				(type default)
			)
			(layer "F.SilkS")
		)
		(fp_line
			(start 14.837156 -5.171694)
			(end 14.776958 -5.171694)
			(stroke
				(width 0.1)
				(type default)
			)
			(layer "F.SilkS")
		)
		(fp_line
			(start 14.878558 -0.882904)
			(end 14.938502 -0.882904)
			(stroke
				(width 0.1)
				(type default)
			)
			(layer "F.SilkS")
		)
		(fp_line
			(start 14.878558 -0.882904)
			(end 14.938502 -0.882904)
			(stroke
				(width 0.1)
				(type default)
			)
			(layer "F.SilkS")
		)
		(fp_line
			(start 14.878558 -0.882904)
			(end 15.111476 -1.106424)
			(stroke
				(width 0.1)
				(type default)
			)
			(layer "F.SilkS")
		)
		(fp_line
			(start 14.878558 -0.882904)
			(end 15.111476 -1.106424)
			(stroke
				(width 0.1)
				(type default)
			)
			(layer "F.SilkS")
		)
		(fp_line
			(start 14.8971 -5.171694)
			(end 14.657324 -4.941316)
			(stroke
				(width 0.1)
				(type default)
			)
			(layer "F.SilkS")
		)
		(fp_line
			(start 14.8971 -5.171694)
			(end 14.657324 -4.941316)
			(stroke
				(width 0.1)
				(type default)
			)
			(layer "F.SilkS")
		)
		(fp_line
			(start 14.8971 -5.171694)
			(end 14.837156 -5.171694)
			(stroke
				(width 0.1)
				(type default)
			)
			(layer "F.SilkS")
		)
		(fp_line
			(start 14.8971 -5.171694)
			(end 14.837156 -5.171694)
			(stroke
				(width 0.1)
				(type default)
			)
			(layer "F.SilkS")
		)
		(fp_line
			(start 14.938502 -0.882904)
			(end 14.998954 -0.882904)
			(stroke
				(width 0.1)
				(type default)
			)
			(layer "F.SilkS")
		)
		(fp_line
			(start 14.938502 -0.882904)
			(end 14.998954 -0.882904)
			(stroke
				(width 0.1)
				(type default)
			)
			(layer "F.SilkS")
		)
		(fp_line
			(start 14.938502 -0.882904)
			(end 15.09903 -1.036828)
			(stroke
				(width 0.1)
				(type default)
			)
			(layer "F.SilkS")
		)
		(fp_line
			(start 14.938502 -0.882904)
			(end 15.09903 -1.036828)
			(stroke
				(width 0.1)
				(type default)
			)
			(layer "F.SilkS")
		)
		(fp_line
			(start 14.957552 -5.171694)
			(end 14.645132 -4.872228)
			(stroke
				(width 0.1)
				(type default)
			)
			(layer "F.SilkS")
		)
		(fp_line
			(start 14.957552 -5.171694)
			(end 14.645132 -4.872228)
			(stroke
				(width 0.1)
				(type default)
			)
			(layer "F.SilkS")
		)
		(fp_line
			(start 14.957552 -5.171694)
			(end 14.8971 -5.171694)
			(stroke
				(width 0.1)
				(type default)
			)
			(layer "F.SilkS")
		)
		(fp_line
			(start 14.957552 -5.171694)
			(end 14.8971 -5.171694)
			(stroke
				(width 0.1)
				(type default)
			)
			(layer "F.SilkS")
		)
		(fp_line
			(start 14.998954 -0.882904)
			(end 15.059152 -0.882904)
			(stroke
				(width 0.1)
				(type default)
			)
			(layer "F.SilkS")
		)
		(fp_line
			(start 14.998954 -0.882904)
			(end 15.059152 -0.882904)
			(stroke
				(width 0.1)
				(type default)
			)
			(layer "F.SilkS")
		)
		(fp_line
			(start 14.998954 -0.882904)
			(end 15.087092 -0.96774)
			(stroke
				(width 0.1)
				(type default)
			)
			(layer "F.SilkS")
		)
		(fp_line
			(start 14.998954 -0.882904)
			(end 15.087092 -0.96774)
			(stroke
				(width 0.1)
				(type default)
			)
			(layer "F.SilkS")
		)
		(fp_line
			(start 15.01775 -5.171694)
			(end 14.63294 -4.802632)
			(stroke
				(width 0.1)
				(type default)
			)
			(layer "F.SilkS")
		)
		(fp_line
			(start 15.01775 -5.171694)
			(end 14.63294 -4.802632)
			(stroke
				(width 0.1)
				(type default)
			)
			(layer "F.SilkS")
		)
		(fp_line
			(start 15.01775 -5.171694)
			(end 14.957552 -5.171694)
			(stroke
				(width 0.1)
				(type default)
			)
			(layer "F.SilkS")
		)
		(fp_line
			(start 15.01775 -5.171694)
			(end 14.957552 -5.171694)
			(stroke
				(width 0.1)
				(type default)
			)
			(layer "F.SilkS")
		)
		(fp_line
			(start 15.059152 -0.882904)
			(end 15.072106 -0.882904)
			(stroke
				(width 0.1)
				(type default)
			)
			(layer "F.SilkS")
		)
		(fp_line
			(start 15.059152 -0.882904)
			(end 15.072106 -0.882904)
			(stroke
				(width 0.1)
				(type default)
			)
			(layer "F.SilkS")
		)
		(fp_line
			(start 15.059152 -0.882904)
			(end 15.0749 -0.898398)
			(stroke
				(width 0.1)
				(type default)
			)
			(layer "F.SilkS")
		)
		(fp_line
			(start 15.059152 -0.882904)
			(end 15.0749 -0.898398)
			(stroke
				(width 0.1)
				(type default)
			)
			(layer "F.SilkS")
		)
		(fp_line
			(start 15.072106 -0.882904)
			(end 15.0749 -0.898398)
			(stroke
				(width 0.1)
				(type default)
			)
			(layer "F.SilkS")
		)
		(fp_line
			(start 15.072106 -0.882904)
			(end 15.0749 -0.898398)
			(stroke
				(width 0.1)
				(type default)
			)
			(layer "F.SilkS")
		)
		(fp_line
			(start 15.077694 -5.171694)
			(end 14.621002 -4.733036)
			(stroke
				(width 0.1)
				(type default)
			)
			(layer "F.SilkS")
		)
		(fp_line
			(start 15.077694 -5.171694)
			(end 14.621002 -4.733036)
			(stroke
				(width 0.1)
				(type default)
			)
			(layer "F.SilkS")
		)
		(fp_line
			(start 15.077694 -5.171694)
			(end 15.01775 -5.171694)
			(stroke
				(width 0.1)
				(type default)
			)
			(layer "F.SilkS")
		)
		(fp_line
			(start 15.077694 -5.171694)
			(end 15.01775 -5.171694)
			(stroke
				(width 0.1)
				(type default)
			)
			(layer "F.SilkS")
		)
		(fp_line
			(start 15.087092 -0.96774)
			(end 15.0749 -0.898398)
			(stroke
				(width 0.1)
				(type default)
			)
			(layer "F.SilkS")
		)
		(fp_line
			(start 15.087092 -0.96774)
			(end 15.0749 -0.898398)
			(stroke
				(width 0.1)
				(type default)
			)
			(layer "F.SilkS")
		)
		(fp_line
			(start 15.09903 -1.036828)
			(end 15.087092 -0.96774)
			(stroke
				(width 0.1)
				(type default)
			)
			(layer "F.SilkS")
		)
		(fp_line
			(start 15.09903 -1.036828)
			(end 15.087092 -0.96774)
			(stroke
				(width 0.1)
				(type default)
			)
			(layer "F.SilkS")
		)
		(fp_line
			(start 15.111476 -1.106424)
			(end 15.09903 -1.036828)
			(stroke
				(width 0.1)
				(type default)
			)
			(layer "F.SilkS")
		)
		(fp_line
			(start 15.111476 -1.106424)
			(end 15.09903 -1.036828)
			(stroke
				(width 0.1)
				(type default)
			)
			(layer "F.SilkS")
		)
		(fp_line
			(start 15.123922 -1.17602)
			(end 15.111476 -1.106424)
			(stroke
				(width 0.1)
				(type default)
			)
			(layer "F.SilkS")
		)
		(fp_line
			(start 15.123922 -1.17602)
			(end 15.111476 -1.106424)
			(stroke
				(width 0.1)
				(type default)
			)
			(layer "F.SilkS")
		)
		(fp_line
			(start 15.13586 -1.245362)
			(end 15.123922 -1.17602)
			(stroke
				(width 0.1)
				(type default)
			)
			(layer "F.SilkS")
		)
		(fp_line
			(start 15.13586 -1.245362)
			(end 15.123922 -1.17602)
			(stroke
				(width 0.1)
				(type default)
			)
			(layer "F.SilkS")
		)
		(fp_line
			(start 15.137892 -5.171694)
			(end 14.608556 -4.663948)
			(stroke
				(width 0.1)
				(type default)
			)
			(layer "F.SilkS")
		)
		(fp_line
			(start 15.137892 -5.171694)
			(end 14.608556 -4.663948)
			(stroke
				(width 0.1)
				(type default)
			)
			(layer "F.SilkS")
		)
		(fp_line
			(start 15.137892 -5.171694)
			(end 15.077694 -5.171694)
			(stroke
				(width 0.1)
				(type default)
			)
			(layer "F.SilkS")
		)
		(fp_line
			(start 15.137892 -5.171694)
			(end 15.077694 -5.171694)
			(stroke
				(width 0.1)
				(type default)
			)
			(layer "F.SilkS")
		)
		(fp_line
			(start 15.148052 -1.314704)
			(end 15.13586 -1.245362)
			(stroke
				(width 0.1)
				(type default)
			)
			(layer "F.SilkS")
		)
		(fp_line
			(start 15.148052 -1.314704)
			(end 15.13586 -1.245362)
			(stroke
				(width 0.1)
				(type default)
			)
			(layer "F.SilkS")
		)
		(fp_line
			(start 15.160498 -1.384046)
			(end 15.148052 -1.314704)
			(stroke
				(width 0.1)
				(type default)
			)
			(layer "F.SilkS")
		)
		(fp_line
			(start 15.160498 -1.384046)
			(end 15.148052 -1.314704)
			(stroke
				(width 0.1)
				(type default)
			)
			(layer "F.SilkS")
		)
		(fp_line
			(start 15.17269 -1.453642)
			(end 15.160498 -1.384046)
			(stroke
				(width 0.1)
				(type default)
			)
			(layer "F.SilkS")
		)
		(fp_line
			(start 15.17269 -1.453642)
			(end 15.160498 -1.384046)
			(stroke
				(width 0.1)
				(type default)
			)
			(layer "F.SilkS")
		)
		(fp_line
			(start 15.184882 -1.522984)
			(end 15.17269 -1.453642)
			(stroke
				(width 0.1)
				(type default)
			)
			(layer "F.SilkS")
		)
		(fp_line
			(start 15.184882 -1.522984)
			(end 15.17269 -1.453642)
			(stroke
				(width 0.1)
				(type default)
			)
			(layer "F.SilkS")
		)
		(fp_line
			(start 15.184882 -1.522984)
			(end 15.19682 -1.592326)
			(stroke
				(width 0.1)
				(type default)
			)
			(layer "F.SilkS")
		)
		(fp_line
			(start 15.184882 -1.522984)
			(end 15.19682 -1.592326)
			(stroke
				(width 0.1)
				(type default)
			)
			(layer "F.SilkS")
		)
		(fp_line
			(start 15.19682 -1.592326)
			(end 15.209266 -1.661922)
			(stroke
				(width 0.1)
				(type default)
			)
			(layer "F.SilkS")
		)
		(fp_line
			(start 15.19682 -1.592326)
			(end 15.209266 -1.661922)
			(stroke
				(width 0.1)
				(type default)
			)
			(layer "F.SilkS")
		)
		(fp_line
			(start 15.198344 -5.171694)
			(end 14.596364 -4.594352)
			(stroke
				(width 0.1)
				(type default)
			)
			(layer "F.SilkS")
		)
		(fp_line
			(start 15.198344 -5.171694)
			(end 14.596364 -4.594352)
			(stroke
				(width 0.1)
				(type default)
			)
			(layer "F.SilkS")
		)
		(fp_line
			(start 15.198344 -5.171694)
			(end 15.137892 -5.171694)
			(stroke
				(width 0.1)
				(type default)
			)
			(layer "F.SilkS")
		)
		(fp_line
			(start 15.198344 -5.171694)
			(end 15.137892 -5.171694)
			(stroke
				(width 0.1)
				(type default)
			)
			(layer "F.SilkS")
		)
		(fp_line
			(start 15.209266 -1.661922)
			(end 15.221458 -1.731518)
			(stroke
				(width 0.1)
				(type default)
			)
			(layer "F.SilkS")
		)
		(fp_line
			(start 15.209266 -1.661922)
			(end 15.221458 -1.731518)
			(stroke
				(width 0.1)
				(type default)
			)
			(layer "F.SilkS")
		)
		(fp_line
			(start 15.221458 -1.731518)
			(end 15.233396 -1.800606)
			(stroke
				(width 0.1)
				(type default)
			)
			(layer "F.SilkS")
		)
		(fp_line
			(start 15.221458 -1.731518)
			(end 15.233396 -1.800606)
			(stroke
				(width 0.1)
				(type default)
			)
			(layer "F.SilkS")
		)
		(fp_line
			(start 15.233396 -1.800606)
			(end 15.245842 -1.869948)
			(stroke
				(width 0.1)
				(type default)
			)
			(layer "F.SilkS")
		)
		(fp_line
			(start 15.233396 -1.800606)
			(end 15.245842 -1.869948)
			(stroke
				(width 0.1)
				(type default)
			)
			(layer "F.SilkS")
		)
		(fp_line
			(start 15.245842 -1.869948)
			(end 15.258288 -1.939544)
			(stroke
				(width 0.1)
				(type default)
			)
			(layer "F.SilkS")
		)
		(fp_line
			(start 15.245842 -1.869948)
			(end 15.258288 -1.939544)
			(stroke
				(width 0.1)
				(type default)
			)
			(layer "F.SilkS")
		)
		(fp_line
			(start 15.258288 -5.171694)
			(end 14.584426 -4.52501)
			(stroke
				(width 0.1)
				(type default)
			)
			(layer "F.SilkS")
		)
		(fp_line
			(start 15.258288 -5.171694)
			(end 14.584426 -4.52501)
			(stroke
				(width 0.1)
				(type default)
			)
			(layer "F.SilkS")
		)
		(fp_line
			(start 15.258288 -5.171694)
			(end 15.198344 -5.171694)
			(stroke
				(width 0.1)
				(type default)
			)
			(layer "F.SilkS")
		)
		(fp_line
			(start 15.258288 -5.171694)
			(end 15.198344 -5.171694)
			(stroke
				(width 0.1)
				(type default)
			)
			(layer "F.SilkS")
		)
		(fp_line
			(start 15.258288 -1.939544)
			(end 15.270226 -2.00914)
			(stroke
				(width 0.1)
				(type default)
			)
			(layer "F.SilkS")
		)
		(fp_line
			(start 15.258288 -1.939544)
			(end 15.270226 -2.00914)
			(stroke
				(width 0.1)
				(type default)
			)
			(layer "F.SilkS")
		)
		(fp_line
			(start 15.270226 -2.00914)
			(end 15.282418 -2.078482)
			(stroke
				(width 0.1)
				(type default)
			)
			(layer "F.SilkS")
		)
		(fp_line
			(start 15.270226 -2.00914)
			(end 15.282418 -2.078482)
			(stroke
				(width 0.1)
				(type default)
			)
			(layer "F.SilkS")
		)
		(fp_line
			(start 15.282418 -2.078482)
			(end 15.294864 -2.147824)
			(stroke
				(width 0.1)
				(type default)
			)
			(layer "F.SilkS")
		)
		(fp_line
			(start 15.282418 -2.078482)
			(end 15.294864 -2.147824)
			(stroke
				(width 0.1)
				(type default)
			)
			(layer "F.SilkS")
		)
		(fp_line
			(start 15.294864 -2.147824)
			(end 15.307056 -2.21742)
			(stroke
				(width 0.1)
				(type default)
			)
			(layer "F.SilkS")
		)
		(fp_line
			(start 15.294864 -2.147824)
			(end 15.307056 -2.21742)
			(stroke
				(width 0.1)
				(type default)
			)
			(layer "F.SilkS")
		)
		(fp_line
			(start 15.307056 -2.21742)
			(end 15.319248 -2.286762)
			(stroke
				(width 0.1)
				(type default)
			)
			(layer "F.SilkS")
		)
		(fp_line
			(start 15.307056 -2.21742)
			(end 15.319248 -2.286762)
			(stroke
				(width 0.1)
				(type default)
			)
			(layer "F.SilkS")
		)
		(fp_line
			(start 15.318486 -5.171694)
			(end 14.57198 -4.455668)
			(stroke
				(width 0.1)
				(type default)
			)
			(layer "F.SilkS")
		)
		(fp_line
			(start 15.318486 -5.171694)
			(end 14.57198 -4.455668)
			(stroke
				(width 0.1)
				(type default)
			)
			(layer "F.SilkS")
		)
		(fp_line
			(start 15.318486 -5.171694)
			(end 15.258288 -5.171694)
			(stroke
				(width 0.1)
				(type default)
			)
			(layer "F.SilkS")
		)
		(fp_line
			(start 15.318486 -5.171694)
			(end 15.258288 -5.171694)
			(stroke
				(width 0.1)
				(type default)
			)
			(layer "F.SilkS")
		)
		(fp_line
			(start 15.319248 -2.286762)
			(end 15.331186 -2.356104)
			(stroke
				(width 0.1)
				(type default)
			)
			(layer "F.SilkS")
		)
		(fp_line
			(start 15.319248 -2.286762)
			(end 15.331186 -2.356104)
			(stroke
				(width 0.1)
				(type default)
			)
			(layer "F.SilkS")
		)
		(fp_line
			(start 15.331186 -2.356104)
			(end 15.343632 -2.425446)
			(stroke
				(width 0.1)
				(type default)
			)
			(layer "F.SilkS")
		)
		(fp_line
			(start 15.331186 -2.356104)
			(end 15.343632 -2.425446)
			(stroke
				(width 0.1)
				(type default)
			)
			(layer "F.SilkS")
		)
		(fp_line
			(start 15.343632 -2.425446)
			(end 15.355824 -2.495042)
			(stroke
				(width 0.1)
				(type default)
			)
			(layer "F.SilkS")
		)
		(fp_line
			(start 15.343632 -2.425446)
			(end 15.355824 -2.495042)
			(stroke
				(width 0.1)
				(type default)
			)
			(layer "F.SilkS")
		)
		(fp_line
			(start 15.355824 -2.495042)
			(end 15.367762 -2.564384)
			(stroke
				(width 0.1)
				(type default)
			)
			(layer "F.SilkS")
		)
		(fp_line
			(start 15.355824 -2.495042)
			(end 15.367762 -2.564384)
			(stroke
				(width 0.1)
				(type default)
			)
			(layer "F.SilkS")
		)
		(fp_line
			(start 15.367762 -2.564384)
			(end 15.380208 -2.633726)
			(stroke
				(width 0.1)
				(type default)
			)
			(layer "F.SilkS")
		)
		(fp_line
			(start 15.367762 -2.564384)
			(end 15.380208 -2.633726)
			(stroke
				(width 0.1)
				(type default)
			)
			(layer "F.SilkS")
		)
		(fp_line
			(start 15.378938 -5.171694)
			(end 14.560042 -4.386326)
			(stroke
				(width 0.1)
				(type default)
			)
			(layer "F.SilkS")
		)
		(fp_line
			(start 15.378938 -5.171694)
			(end 14.560042 -4.386326)
			(stroke
				(width 0.1)
				(type default)
			)
			(layer "F.SilkS")
		)
		(fp_line
			(start 15.378938 -5.171694)
			(end 15.318486 -5.171694)
			(stroke
				(width 0.1)
				(type default)
			)
			(layer "F.SilkS")
		)
		(fp_line
			(start 15.378938 -5.171694)
			(end 15.318486 -5.171694)
			(stroke
				(width 0.1)
				(type default)
			)
			(layer "F.SilkS")
		)
		(fp_line
			(start 15.380208 -2.633726)
			(end 15.392654 -2.703322)
			(stroke
				(width 0.1)
				(type default)
			)
			(layer "F.SilkS")
		)
		(fp_line
			(start 15.380208 -2.633726)
			(end 15.392654 -2.703322)
			(stroke
				(width 0.1)
				(type default)
			)
			(layer "F.SilkS")
		)
		(fp_line
			(start 15.392654 -2.703322)
			(end 15.404592 -2.772664)
			(stroke
				(width 0.1)
				(type default)
			)
			(layer "F.SilkS")
		)
		(fp_line
			(start 15.392654 -2.703322)
			(end 15.404592 -2.772664)
			(stroke
				(width 0.1)
				(type default)
			)
			(layer "F.SilkS")
		)
		(fp_line
			(start 15.404592 -2.772664)
			(end 15.416784 -2.84226)
			(stroke
				(width 0.1)
				(type default)
			)
			(layer "F.SilkS")
		)
		(fp_line
			(start 15.404592 -2.772664)
			(end 15.416784 -2.84226)
			(stroke
				(width 0.1)
				(type default)
			)
			(layer "F.SilkS")
		)
		(fp_line
			(start 15.42923 -2.911602)
			(end 15.416784 -2.84226)
			(stroke
				(width 0.1)
				(type default)
			)
			(layer "F.SilkS")
		)
		(fp_line
			(start 15.42923 -2.911602)
			(end 15.416784 -2.84226)
			(stroke
				(width 0.1)
				(type default)
			)
			(layer "F.SilkS")
		)
		(fp_line
			(start 15.438882 -5.171694)
			(end 14.54785 -4.316984)
			(stroke
				(width 0.1)
				(type default)
			)
			(layer "F.SilkS")
		)
		(fp_line
			(start 15.438882 -5.171694)
			(end 14.54785 -4.316984)
			(stroke
				(width 0.1)
				(type default)
			)
			(layer "F.SilkS")
		)
		(fp_line
			(start 15.438882 -5.171694)
			(end 15.378938 -5.171694)
			(stroke
				(width 0.1)
				(type default)
			)
			(layer "F.SilkS")
		)
		(fp_line
			(start 15.438882 -5.171694)
			(end 15.378938 -5.171694)
			(stroke
				(width 0.1)
				(type default)
			)
			(layer "F.SilkS")
		)
		(fp_line
			(start 15.441168 -2.980944)
			(end 14.084808 -1.679702)
			(stroke
				(width 0.1)
				(type default)
			)
			(layer "F.SilkS")
		)
		(fp_line
			(start 15.441168 -2.980944)
			(end 14.084808 -1.679702)
			(stroke
				(width 0.1)
				(type default)
			)
			(layer "F.SilkS")
		)
		(fp_line
			(start 15.441168 -2.980944)
			(end 15.42923 -2.911602)
			(stroke
				(width 0.1)
				(type default)
			)
			(layer "F.SilkS")
		)
		(fp_line
			(start 15.441168 -2.980944)
			(end 15.42923 -2.911602)
			(stroke
				(width 0.1)
				(type default)
			)
			(layer "F.SilkS")
		)
		(fp_line
			(start 15.45336 -3.050286)
			(end 14.097254 -1.749044)
			(stroke
				(width 0.1)
				(type default)
			)
			(layer "F.SilkS")
		)
		(fp_line
			(start 15.45336 -3.050286)
			(end 14.097254 -1.749044)
			(stroke
				(width 0.1)
				(type default)
			)
			(layer "F.SilkS")
		)
		(fp_line
			(start 15.45336 -3.050286)
			(end 15.441168 -2.980944)
			(stroke
				(width 0.1)
				(type default)
			)
			(layer "F.SilkS")
		)
		(fp_line
			(start 15.45336 -3.050286)
			(end 15.441168 -2.980944)
			(stroke
				(width 0.1)
				(type default)
			)
			(layer "F.SilkS")
		)
		(fp_line
			(start 15.465552 -3.119882)
			(end 14.109192 -1.81864)
			(stroke
				(width 0.1)
				(type default)
			)
			(layer "F.SilkS")
		)
		(fp_line
			(start 15.465552 -3.119882)
			(end 14.109192 -1.81864)
			(stroke
				(width 0.1)
				(type default)
			)
			(layer "F.SilkS")
		)
		(fp_line
			(start 15.465552 -3.119882)
			(end 15.45336 -3.050286)
			(stroke
				(width 0.1)
				(type default)
			)
			(layer "F.SilkS")
		)
		(fp_line
			(start 15.465552 -3.119882)
			(end 15.45336 -3.050286)
			(stroke
				(width 0.1)
				(type default)
			)
			(layer "F.SilkS")
		)
		(fp_line
			(start 15.477998 -3.189224)
			(end 14.121384 -1.887982)
			(stroke
				(width 0.1)
				(type default)
			)
			(layer "F.SilkS")
		)
		(fp_line
			(start 15.477998 -3.189224)
			(end 14.121384 -1.887982)
			(stroke
				(width 0.1)
				(type default)
			)
			(layer "F.SilkS")
		)
		(fp_line
			(start 15.477998 -3.189224)
			(end 15.465552 -3.119882)
			(stroke
				(width 0.1)
				(type default)
			)
			(layer "F.SilkS")
		)
		(fp_line
			(start 15.477998 -3.189224)
			(end 15.465552 -3.119882)
			(stroke
				(width 0.1)
				(type default)
			)
			(layer "F.SilkS")
		)
		(fp_line
			(start 15.491714 -3.260344)
			(end 14.13383 -1.957324)
			(stroke
				(width 0.1)
				(type default)
			)
			(layer "F.SilkS")
		)
		(fp_line
			(start 15.491714 -3.260344)
			(end 14.13383 -1.957324)
			(stroke
				(width 0.1)
				(type default)
			)
			(layer "F.SilkS")
		)
		(fp_line
			(start 15.49908 -5.171694)
			(end 14.535404 -4.247388)
			(stroke
				(width 0.1)
				(type default)
			)
			(layer "F.SilkS")
		)
		(fp_line
			(start 15.49908 -5.171694)
			(end 14.535404 -4.247388)
			(stroke
				(width 0.1)
				(type default)
			)
			(layer "F.SilkS")
		)
		(fp_line
			(start 15.49908 -5.171694)
			(end 15.438882 -5.171694)
			(stroke
				(width 0.1)
				(type default)
			)
			(layer "F.SilkS")
		)
		(fp_line
			(start 15.49908 -5.171694)
			(end 15.438882 -5.171694)
			(stroke
				(width 0.1)
				(type default)
			)
			(layer "F.SilkS")
		)
		(fp_line
			(start 15.508478 -3.334004)
			(end 14.145768 -2.02692)
			(stroke
				(width 0.1)
				(type default)
			)
			(layer "F.SilkS")
		)
		(fp_line
			(start 15.508478 -3.334004)
			(end 14.145768 -2.02692)
			(stroke
				(width 0.1)
				(type default)
			)
			(layer "F.SilkS")
		)
		(fp_line
			(start 15.524988 -3.40741)
			(end 14.15796 -2.096262)
			(stroke
				(width 0.1)
				(type default)
			)
			(layer "F.SilkS")
		)
		(fp_line
			(start 15.524988 -3.40741)
			(end 14.15796 -2.096262)
			(stroke
				(width 0.1)
				(type default)
			)
			(layer "F.SilkS")
		)
		(fp_line
			(start 15.54099 -3.480562)
			(end 14.170406 -2.165604)
			(stroke
				(width 0.1)
				(type default)
			)
			(layer "F.SilkS")
		)
		(fp_line
			(start 15.54099 -3.480562)
			(end 14.170406 -2.165604)
			(stroke
				(width 0.1)
				(type default)
			)
			(layer "F.SilkS")
		)
		(fp_line
			(start 15.559278 -5.171694)
			(end 14.523466 -4.178046)
			(stroke
				(width 0.1)
				(type default)
			)
			(layer "F.SilkS")
		)
		(fp_line
			(start 15.559278 -5.171694)
			(end 14.523466 -4.178046)
			(stroke
				(width 0.1)
				(type default)
			)
			(layer "F.SilkS")
		)
		(fp_line
			(start 15.559278 -5.171694)
			(end 15.49908 -5.171694)
			(stroke
				(width 0.1)
				(type default)
			)
			(layer "F.SilkS")
		)
		(fp_line
			(start 15.559278 -5.171694)
			(end 15.49908 -5.171694)
			(stroke
				(width 0.1)
				(type default)
			)
			(layer "F.SilkS")
		)
		(fp_line
			(start 15.570962 -3.566922)
			(end 14.182344 -2.234946)
			(stroke
				(width 0.1)
				(type default)
			)
			(layer "F.SilkS")
		)
		(fp_line
			(start 15.570962 -3.566922)
			(end 14.182344 -2.234946)
			(stroke
				(width 0.1)
				(type default)
			)
			(layer "F.SilkS")
		)
		(fp_line
			(start 15.601442 -3.654044)
			(end 14.194282 -2.304288)
			(stroke
				(width 0.1)
				(type default)
			)
			(layer "F.SilkS")
		)
		(fp_line
			(start 15.601442 -3.654044)
			(end 14.194282 -2.304288)
			(stroke
				(width 0.1)
				(type default)
			)
			(layer "F.SilkS")
		)
		(fp_line
			(start 15.619222 -5.171694)
			(end 14.511274 -4.108704)
			(stroke
				(width 0.1)
				(type default)
			)
			(layer "F.SilkS")
		)
		(fp_line
			(start 15.619222 -5.171694)
			(end 14.511274 -4.108704)
			(stroke
				(width 0.1)
				(type default)
			)
			(layer "F.SilkS")
		)
		(fp_line
			(start 15.619222 -5.171694)
			(end 15.559278 -5.171694)
			(stroke
				(width 0.1)
				(type default)
			)
			(layer "F.SilkS")
		)
		(fp_line
			(start 15.619222 -5.171694)
			(end 15.559278 -5.171694)
			(stroke
				(width 0.1)
				(type default)
			)
			(layer "F.SilkS")
		)
		(fp_line
			(start 15.649702 -3.75793)
			(end 14.206728 -2.373884)
			(stroke
				(width 0.1)
				(type default)
			)
			(layer "F.SilkS")
		)
		(fp_line
			(start 15.649702 -3.75793)
			(end 14.206728 -2.373884)
			(stroke
				(width 0.1)
				(type default)
			)
			(layer "F.SilkS")
		)
		(fp_line
			(start 15.679166 -5.171694)
			(end 14.498828 -4.039362)
			(stroke
				(width 0.1)
				(type default)
			)
			(layer "F.SilkS")
		)
		(fp_line
			(start 15.679166 -5.171694)
			(end 14.498828 -4.039362)
			(stroke
				(width 0.1)
				(type default)
			)
			(layer "F.SilkS")
		)
		(fp_line
			(start 15.679166 -5.171694)
			(end 15.619222 -5.171694)
			(stroke
				(width 0.1)
				(type default)
			)
			(layer "F.SilkS")
		)
		(fp_line
			(start 15.679166 -5.171694)
			(end 15.619222 -5.171694)
			(stroke
				(width 0.1)
				(type default)
			)
			(layer "F.SilkS")
		)
		(fp_line
			(start 15.729458 -3.892296)
			(end 14.21892 -2.443226)
			(stroke
				(width 0.1)
				(type default)
			)
			(layer "F.SilkS")
		)
		(fp_line
			(start 15.729458 -3.892296)
			(end 14.21892 -2.443226)
			(stroke
				(width 0.1)
				(type default)
			)
			(layer "F.SilkS")
		)
		(fp_line
			(start 15.739618 -5.171694)
			(end 14.486636 -3.969766)
			(stroke
				(width 0.1)
				(type default)
			)
			(layer "F.SilkS")
		)
		(fp_line
			(start 15.739618 -5.171694)
			(end 14.486636 -3.969766)
			(stroke
				(width 0.1)
				(type default)
			)
			(layer "F.SilkS")
		)
		(fp_line
			(start 15.739618 -5.171694)
			(end 15.679166 -5.171694)
			(stroke
				(width 0.1)
				(type default)
			)
			(layer "F.SilkS")
		)
		(fp_line
			(start 15.739618 -5.171694)
			(end 15.679166 -5.171694)
			(stroke
				(width 0.1)
				(type default)
			)
			(layer "F.SilkS")
		)
		(fp_line
			(start 15.781274 -4.923028)
			(end 14.42593 -3.622802)
			(stroke
				(width 0.1)
				(type default)
			)
			(layer "F.SilkS")
		)
		(fp_line
			(start 15.781274 -4.923028)
			(end 14.42593 -3.622802)
			(stroke
				(width 0.1)
				(type default)
			)
			(layer "F.SilkS")
		)
		(fp_line
			(start 15.781274 -4.923028)
			(end 15.79372 -4.992624)
			(stroke
				(width 0.1)
				(type default)
			)
			(layer "F.SilkS")
		)
		(fp_line
			(start 15.781274 -4.923028)
			(end 15.79372 -4.992624)
			(stroke
				(width 0.1)
				(type default)
			)
			(layer "F.SilkS")
		)
		(fp_line
			(start 15.79372 -4.992624)
			(end 14.438376 -3.692398)
			(stroke
				(width 0.1)
				(type default)
			)
			(layer "F.SilkS")
		)
		(fp_line
			(start 15.79372 -4.992624)
			(end 14.438376 -3.692398)
			(stroke
				(width 0.1)
				(type default)
			)
			(layer "F.SilkS")
		)
		(fp_line
			(start 15.79372 -4.992624)
			(end 15.805658 -5.061966)
			(stroke
				(width 0.1)
				(type default)
			)
			(layer "F.SilkS")
		)
		(fp_line
			(start 15.79372 -4.992624)
			(end 15.805658 -5.061966)
			(stroke
				(width 0.1)
				(type default)
			)
			(layer "F.SilkS")
		)
		(fp_line
			(start 15.799816 -5.171694)
			(end 14.474952 -3.900424)
			(stroke
				(width 0.1)
				(type default)
			)
			(layer "F.SilkS")
		)
		(fp_line
			(start 15.799816 -5.171694)
			(end 14.474952 -3.900424)
			(stroke
				(width 0.1)
				(type default)
			)
			(layer "F.SilkS")
		)
		(fp_line
			(start 15.799816 -5.171694)
			(end 15.739618 -5.171694)
			(stroke
				(width 0.1)
				(type default)
			)
			(layer "F.SilkS")
		)
		(fp_line
			(start 15.799816 -5.171694)
			(end 15.739618 -5.171694)
			(stroke
				(width 0.1)
				(type default)
			)
			(layer "F.SilkS")
		)
		(fp_line
			(start 15.805658 -5.061966)
			(end 14.45006 -3.76174)
			(stroke
				(width 0.1)
				(type default)
			)
			(layer "F.SilkS")
		)
		(fp_line
			(start 15.805658 -5.061966)
			(end 14.45006 -3.76174)
			(stroke
				(width 0.1)
				(type default)
			)
			(layer "F.SilkS")
		)
		(fp_line
			(start 15.805658 -5.061966)
			(end 15.81785 -5.131308)
			(stroke
				(width 0.1)
				(type default)
			)
			(layer "F.SilkS")
		)
		(fp_line
			(start 15.805658 -5.061966)
			(end 15.81785 -5.131308)
			(stroke
				(width 0.1)
				(type default)
			)
			(layer "F.SilkS")
		)
		(fp_line
			(start 15.81785 -5.131308)
			(end 14.462506 -3.831082)
			(stroke
				(width 0.1)
				(type default)
			)
			(layer "F.SilkS")
		)
		(fp_line
			(start 15.81785 -5.131308)
			(end 14.462506 -3.831082)
			(stroke
				(width 0.1)
				(type default)
			)
			(layer "F.SilkS")
		)
		(fp_line
			(start 15.81785 -5.131308)
			(end 15.824962 -5.171694)
			(stroke
				(width 0.1)
				(type default)
			)
			(layer "F.SilkS")
		)
		(fp_line
			(start 15.81785 -5.131308)
			(end 15.824962 -5.171694)
			(stroke
				(width 0.1)
				(type default)
			)
			(layer "F.SilkS")
		)
		(fp_line
			(start 15.824962 -5.171694)
			(end 15.799816 -5.171694)
			(stroke
				(width 0.1)
				(type default)
			)
			(layer "F.SilkS")
		)
		(fp_line
			(start 15.824962 -5.171694)
			(end 15.799816 -5.171694)
			(stroke
				(width 0.1)
				(type default)
			)
			(layer "F.SilkS")
		)
		(fp_line
			(start 15.884652 -4.96443)
			(end 14.413484 -3.55346)
			(stroke
				(width 0.1)
				(type default)
			)
			(layer "F.SilkS")
		)
		(fp_line
			(start 15.884652 -4.96443)
			(end 14.413484 -3.55346)
			(stroke
				(width 0.1)
				(type default)
			)
			(layer "F.SilkS")
		)
		(fp_line
			(start 16.049498 -5.065268)
			(end 14.401546 -3.484118)
			(stroke
				(width 0.1)
				(type default)
			)
			(layer "F.SilkS")
		)
		(fp_line
			(start 16.049498 -5.065268)
			(end 14.401546 -3.484118)
			(stroke
				(width 0.1)
				(type default)
			)
			(layer "F.SilkS")
		)
		(fp_line
			(start 16.169132 -5.12191)
			(end 14.389354 -3.414776)
			(stroke
				(width 0.1)
				(type default)
			)
			(layer "F.SilkS")
		)
		(fp_line
			(start 16.169132 -5.12191)
			(end 14.389354 -3.414776)
			(stroke
				(width 0.1)
				(type default)
			)
			(layer "F.SilkS")
		)
		(fp_line
			(start 16.270986 -5.161788)
			(end 14.376908 -3.34518)
			(stroke
				(width 0.1)
				(type default)
			)
			(layer "F.SilkS")
		)
		(fp_line
			(start 16.270986 -5.161788)
			(end 14.376908 -3.34518)
			(stroke
				(width 0.1)
				(type default)
			)
			(layer "F.SilkS")
		)
		(fp_line
			(start 16.355568 -5.18541)
			(end 14.36497 -3.275838)
			(stroke
				(width 0.1)
				(type default)
			)
			(layer "F.SilkS")
		)
		(fp_line
			(start 16.355568 -5.18541)
			(end 14.36497 -3.275838)
			(stroke
				(width 0.1)
				(type default)
			)
			(layer "F.SilkS")
		)
		(fp_line
			(start 16.439896 -5.208778)
			(end 14.352778 -3.206496)
			(stroke
				(width 0.1)
				(type default)
			)
			(layer "F.SilkS")
		)
		(fp_line
			(start 16.439896 -5.208778)
			(end 14.352778 -3.206496)
			(stroke
				(width 0.1)
				(type default)
			)
			(layer "F.SilkS")
		)
		(fp_line
			(start 16.52397 -5.231638)
			(end 14.340586 -3.137154)
			(stroke
				(width 0.1)
				(type default)
			)
			(layer "F.SilkS")
		)
		(fp_line
			(start 16.52397 -5.231638)
			(end 14.340586 -3.137154)
			(stroke
				(width 0.1)
				(type default)
			)
			(layer "F.SilkS")
		)
		(fp_line
			(start 16.533622 -0.882904)
			(end 16.562832 -0.882904)
			(stroke
				(width 0.1)
				(type default)
			)
			(layer "F.SilkS")
		)
		(fp_line
			(start 16.533622 -0.882904)
			(end 16.562832 -0.882904)
			(stroke
				(width 0.1)
				(type default)
			)
			(layer "F.SilkS")
		)
		(fp_line
			(start 16.539718 -0.918464)
			(end 16.533622 -0.882904)
			(stroke
				(width 0.1)
				(type default)
			)
			(layer "F.SilkS")
		)
		(fp_line
			(start 16.539718 -0.918464)
			(end 16.533622 -0.882904)
			(stroke
				(width 0.1)
				(type default)
			)
			(layer "F.SilkS")
		)
		(fp_line
			(start 16.539718 -0.918464)
			(end 17.896586 -2.21996)
			(stroke
				(width 0.1)
				(type default)
			)
			(layer "F.SilkS")
		)
		(fp_line
			(start 16.539718 -0.918464)
			(end 17.896586 -2.21996)
			(stroke
				(width 0.1)
				(type default)
			)
			(layer "F.SilkS")
		)
		(fp_line
			(start 16.552164 -0.987806)
			(end 16.539718 -0.918464)
			(stroke
				(width 0.1)
				(type default)
			)
			(layer "F.SilkS")
		)
		(fp_line
			(start 16.552164 -0.987806)
			(end 16.539718 -0.918464)
			(stroke
				(width 0.1)
				(type default)
			)
			(layer "F.SilkS")
		)
		(fp_line
			(start 16.552164 -0.987806)
			(end 17.908524 -2.289048)
			(stroke
				(width 0.1)
				(type default)
			)
			(layer "F.SilkS")
		)
		(fp_line
			(start 16.552164 -0.987806)
			(end 17.908524 -2.289048)
			(stroke
				(width 0.1)
				(type default)
			)
			(layer "F.SilkS")
		)
		(fp_line
			(start 16.562832 -0.882904)
			(end 16.623284 -0.882904)
			(stroke
				(width 0.1)
				(type default)
			)
			(layer "F.SilkS")
		)
		(fp_line
			(start 16.562832 -0.882904)
			(end 16.623284 -0.882904)
			(stroke
				(width 0.1)
				(type default)
			)
			(layer "F.SilkS")
		)
		(fp_line
			(start 16.562832 -0.882904)
			(end 17.88414 -2.150364)
			(stroke
				(width 0.1)
				(type default)
			)
			(layer "F.SilkS")
		)
		(fp_line
			(start 16.562832 -0.882904)
			(end 17.88414 -2.150364)
			(stroke
				(width 0.1)
				(type default)
			)
			(layer "F.SilkS")
		)
		(fp_line
			(start 16.564356 -1.057148)
			(end 16.552164 -0.987806)
			(stroke
				(width 0.1)
				(type default)
			)
			(layer "F.SilkS")
		)
		(fp_line
			(start 16.564356 -1.057148)
			(end 16.552164 -0.987806)
			(stroke
				(width 0.1)
				(type default)
			)
			(layer "F.SilkS")
		)
		(fp_line
			(start 16.564356 -1.057148)
			(end 17.920716 -2.35839)
			(stroke
				(width 0.1)
				(type default)
			)
			(layer "F.SilkS")
		)
		(fp_line
			(start 16.564356 -1.057148)
			(end 17.920716 -2.35839)
			(stroke
				(width 0.1)
				(type default)
			)
			(layer "F.SilkS")
		)
		(fp_line
			(start 16.576294 -1.126744)
			(end 16.564356 -1.057148)
			(stroke
				(width 0.1)
				(type default)
			)
			(layer "F.SilkS")
		)
		(fp_line
			(start 16.576294 -1.126744)
			(end 16.564356 -1.057148)
			(stroke
				(width 0.1)
				(type default)
			)
			(layer "F.SilkS")
		)
		(fp_line
			(start 16.576294 -1.126744)
			(end 17.932908 -2.427732)
			(stroke
				(width 0.1)
				(type default)
			)
			(layer "F.SilkS")
		)
		(fp_line
			(start 16.576294 -1.126744)
			(end 17.932908 -2.427732)
			(stroke
				(width 0.1)
				(type default)
			)
			(layer "F.SilkS")
		)
		(fp_line
			(start 16.58874 -1.196086)
			(end 16.576294 -1.126744)
			(stroke
				(width 0.1)
				(type default)
			)
			(layer "F.SilkS")
		)
		(fp_line
			(start 16.58874 -1.196086)
			(end 16.576294 -1.126744)
			(stroke
				(width 0.1)
				(type default)
			)
			(layer "F.SilkS")
		)
		(fp_line
			(start 16.58874 -1.196086)
			(end 17.9451 -2.497328)
			(stroke
				(width 0.1)
				(type default)
			)
			(layer "F.SilkS")
		)
		(fp_line
			(start 16.58874 -1.196086)
			(end 17.9451 -2.497328)
			(stroke
				(width 0.1)
				(type default)
			)
			(layer "F.SilkS")
		)
		(fp_line
			(start 16.590772 -5.237734)
			(end 14.328394 -3.067558)
			(stroke
				(width 0.1)
				(type default)
			)
			(layer "F.SilkS")
		)
		(fp_line
			(start 16.590772 -5.237734)
			(end 14.328394 -3.067558)
			(stroke
				(width 0.1)
				(type default)
			)
			(layer "F.SilkS")
		)
		(fp_line
			(start 16.600932 -1.265428)
			(end 16.58874 -1.196086)
			(stroke
				(width 0.1)
				(type default)
			)
			(layer "F.SilkS")
		)
		(fp_line
			(start 16.600932 -1.265428)
			(end 16.58874 -1.196086)
			(stroke
				(width 0.1)
				(type default)
			)
			(layer "F.SilkS")
		)
		(fp_line
			(start 16.600932 -1.265428)
			(end 17.957038 -2.56667)
			(stroke
				(width 0.1)
				(type default)
			)
			(layer "F.SilkS")
		)
		(fp_line
			(start 16.600932 -1.265428)
			(end 17.957038 -2.56667)
			(stroke
				(width 0.1)
				(type default)
			)
			(layer "F.SilkS")
		)
		(fp_line
			(start 16.61287 -1.33477)
			(end 16.600932 -1.265428)
			(stroke
				(width 0.1)
				(type default)
			)
			(layer "F.SilkS")
		)
		(fp_line
			(start 16.61287 -1.33477)
			(end 16.600932 -1.265428)
			(stroke
				(width 0.1)
				(type default)
			)
			(layer "F.SilkS")
		)
		(fp_line
			(start 16.61287 -1.33477)
			(end 17.969484 -2.636012)
			(stroke
				(width 0.1)
				(type default)
			)
			(layer "F.SilkS")
		)
		(fp_line
			(start 16.61287 -1.33477)
			(end 17.969484 -2.636012)
			(stroke
				(width 0.1)
				(type default)
			)
			(layer "F.SilkS")
		)
		(fp_line
			(start 16.623284 -0.882904)
			(end 16.683228 -0.882904)
			(stroke
				(width 0.1)
				(type default)
			)
			(layer "F.SilkS")
		)
		(fp_line
			(start 16.623284 -0.882904)
			(end 16.683228 -0.882904)
			(stroke
				(width 0.1)
				(type default)
			)
			(layer "F.SilkS")
		)
		(fp_line
			(start 16.623284 -0.882904)
			(end 17.871948 -2.081022)
			(stroke
				(width 0.1)
				(type default)
			)
			(layer "F.SilkS")
		)
		(fp_line
			(start 16.623284 -0.882904)
			(end 17.871948 -2.081022)
			(stroke
				(width 0.1)
				(type default)
			)
			(layer "F.SilkS")
		)
		(fp_line
			(start 16.625316 -1.404366)
			(end 16.61287 -1.33477)
			(stroke
				(width 0.1)
				(type default)
			)
			(layer "F.SilkS")
		)
		(fp_line
			(start 16.625316 -1.404366)
			(end 16.61287 -1.33477)
			(stroke
				(width 0.1)
				(type default)
			)
			(layer "F.SilkS")
		)
		(fp_line
			(start 16.625316 -1.404366)
			(end 17.981676 -2.705608)
			(stroke
				(width 0.1)
				(type default)
			)
			(layer "F.SilkS")
		)
		(fp_line
			(start 16.625316 -1.404366)
			(end 17.981676 -2.705608)
			(stroke
				(width 0.1)
				(type default)
			)
			(layer "F.SilkS")
		)
		(fp_line
			(start 16.637762 -1.473962)
			(end 16.625316 -1.404366)
			(stroke
				(width 0.1)
				(type default)
			)
			(layer "F.SilkS")
		)
		(fp_line
			(start 16.637762 -1.473962)
			(end 16.625316 -1.404366)
			(stroke
				(width 0.1)
				(type default)
			)
			(layer "F.SilkS")
		)
		(fp_line
			(start 16.637762 -1.473962)
			(end 17.993614 -2.77495)
			(stroke
				(width 0.1)
				(type default)
			)
			(layer "F.SilkS")
		)
		(fp_line
			(start 16.637762 -1.473962)
			(end 17.993614 -2.77495)
			(stroke
				(width 0.1)
				(type default)
			)
			(layer "F.SilkS")
		)
		(fp_line
			(start 16.6497 -1.54305)
			(end 16.637762 -1.473962)
			(stroke
				(width 0.1)
				(type default)
			)
			(layer "F.SilkS")
		)
		(fp_line
			(start 16.6497 -1.54305)
			(end 16.637762 -1.473962)
			(stroke
				(width 0.1)
				(type default)
			)
			(layer "F.SilkS")
		)
		(fp_line
			(start 16.6497 -1.54305)
			(end 18.00606 -2.844292)
			(stroke
				(width 0.1)
				(type default)
			)
			(layer "F.SilkS")
		)
		(fp_line
			(start 16.6497 -1.54305)
			(end 18.00606 -2.844292)
			(stroke
				(width 0.1)
				(type default)
			)
			(layer "F.SilkS")
		)
		(fp_line
			(start 16.657066 -5.24383)
			(end 14.316456 -2.998216)
			(stroke
				(width 0.1)
				(type default)
			)
			(layer "F.SilkS")
		)
		(fp_line
			(start 16.657066 -5.24383)
			(end 14.316456 -2.998216)
			(stroke
				(width 0.1)
				(type default)
			)
			(layer "F.SilkS")
		)
		(fp_line
			(start 16.661892 -1.612646)
			(end 16.6497 -1.54305)
			(stroke
				(width 0.1)
				(type default)
			)
			(layer "F.SilkS")
		)
		(fp_line
			(start 16.661892 -1.612646)
			(end 16.6497 -1.54305)
			(stroke
				(width 0.1)
				(type default)
			)
			(layer "F.SilkS")
		)
		(fp_line
			(start 16.661892 -1.612646)
			(end 18.017998 -2.913634)
			(stroke
				(width 0.1)
				(type default)
			)
			(layer "F.SilkS")
		)
		(fp_line
			(start 16.661892 -1.612646)
			(end 18.017998 -2.913634)
			(stroke
				(width 0.1)
				(type default)
			)
			(layer "F.SilkS")
		)
		(fp_line
			(start 16.674084 -1.681988)
			(end 16.661892 -1.612646)
			(stroke
				(width 0.1)
				(type default)
			)
			(layer "F.SilkS")
		)
		(fp_line
			(start 16.674084 -1.681988)
			(end 16.661892 -1.612646)
			(stroke
				(width 0.1)
				(type default)
			)
			(layer "F.SilkS")
		)
		(fp_line
			(start 16.674084 -1.681988)
			(end 18.03019 -2.982976)
			(stroke
				(width 0.1)
				(type default)
			)
			(layer "F.SilkS")
		)
		(fp_line
			(start 16.674084 -1.681988)
			(end 18.03019 -2.982976)
			(stroke
				(width 0.1)
				(type default)
			)
			(layer "F.SilkS")
		)
		(fp_line
			(start 16.683228 -0.882904)
			(end 16.743426 -0.882904)
			(stroke
				(width 0.1)
				(type default)
			)
			(layer "F.SilkS")
		)
		(fp_line
			(start 16.683228 -0.882904)
			(end 16.743426 -0.882904)
			(stroke
				(width 0.1)
				(type default)
			)
			(layer "F.SilkS")
		)
		(fp_line
			(start 16.683228 -0.882904)
			(end 17.86001 -2.011426)
			(stroke
				(width 0.1)
				(type default)
			)
			(layer "F.SilkS")
		)
		(fp_line
			(start 16.683228 -0.882904)
			(end 17.86001 -2.011426)
			(stroke
				(width 0.1)
				(type default)
			)
			(layer "F.SilkS")
		)
		(fp_line
			(start 16.686276 -1.751584)
			(end 16.674084 -1.681988)
			(stroke
				(width 0.1)
				(type default)
			)
			(layer "F.SilkS")
		)
		(fp_line
			(start 16.686276 -1.751584)
			(end 16.674084 -1.681988)
			(stroke
				(width 0.1)
				(type default)
			)
			(layer "F.SilkS")
		)
		(fp_line
			(start 16.686276 -1.751584)
			(end 18.042636 -3.052572)
			(stroke
				(width 0.1)
				(type default)
			)
			(layer "F.SilkS")
		)
		(fp_line
			(start 16.686276 -1.751584)
			(end 18.042636 -3.052572)
			(stroke
				(width 0.1)
				(type default)
			)
			(layer "F.SilkS")
		)
		(fp_line
			(start 16.698214 -1.820926)
			(end 16.686276 -1.751584)
			(stroke
				(width 0.1)
				(type default)
			)
			(layer "F.SilkS")
		)
		(fp_line
			(start 16.698214 -1.820926)
			(end 16.686276 -1.751584)
			(stroke
				(width 0.1)
				(type default)
			)
			(layer "F.SilkS")
		)
		(fp_line
			(start 16.698214 -1.820926)
			(end 18.054574 -3.121914)
			(stroke
				(width 0.1)
				(type default)
			)
			(layer "F.SilkS")
		)
		(fp_line
			(start 16.698214 -1.820926)
			(end 18.054574 -3.121914)
			(stroke
				(width 0.1)
				(type default)
			)
			(layer "F.SilkS")
		)
		(fp_line
			(start 16.71066 -1.890268)
			(end 16.698214 -1.820926)
			(stroke
				(width 0.1)
				(type default)
			)
			(layer "F.SilkS")
		)
		(fp_line
			(start 16.71066 -1.890268)
			(end 16.698214 -1.820926)
			(stroke
				(width 0.1)
				(type default)
			)
			(layer "F.SilkS")
		)
		(fp_line
			(start 16.71066 -1.890268)
			(end 18.066766 -3.191002)
			(stroke
				(width 0.1)
				(type default)
			)
			(layer "F.SilkS")
		)
		(fp_line
			(start 16.71066 -1.890268)
			(end 18.066766 -3.191002)
			(stroke
				(width 0.1)
				(type default)
			)
			(layer "F.SilkS")
		)
		(fp_line
			(start 16.723106 -1.95961)
			(end 16.71066 -1.890268)
			(stroke
				(width 0.1)
				(type default)
			)
			(layer "F.SilkS")
		)
		(fp_line
			(start 16.723106 -1.95961)
			(end 16.71066 -1.890268)
			(stroke
				(width 0.1)
				(type default)
			)
			(layer "F.SilkS")
		)
		(fp_line
			(start 16.723106 -1.95961)
			(end 18.079212 -3.260598)
			(stroke
				(width 0.1)
				(type default)
			)
			(layer "F.SilkS")
		)
		(fp_line
			(start 16.723106 -1.95961)
			(end 18.079212 -3.260598)
			(stroke
				(width 0.1)
				(type default)
			)
			(layer "F.SilkS")
		)
		(fp_line
			(start 16.723868 -5.25018)
			(end 14.30401 -2.928874)
			(stroke
				(width 0.1)
				(type default)
			)
			(layer "F.SilkS")
		)
		(fp_line
			(start 16.723868 -5.25018)
			(end 14.30401 -2.928874)
			(stroke
				(width 0.1)
				(type default)
			)
			(layer "F.SilkS")
		)
		(fp_line
			(start 16.735044 -2.028952)
			(end 16.723106 -1.95961)
			(stroke
				(width 0.1)
				(type default)
			)
			(layer "F.SilkS")
		)
		(fp_line
			(start 16.735044 -2.028952)
			(end 16.723106 -1.95961)
			(stroke
				(width 0.1)
				(type default)
			)
			(layer "F.SilkS")
		)
		(fp_line
			(start 16.735044 -2.028952)
			(end 18.089372 -3.328416)
			(stroke
				(width 0.1)
				(type default)
			)
			(layer "F.SilkS")
		)
		(fp_line
			(start 16.735044 -2.028952)
			(end 18.089372 -3.328416)
			(stroke
				(width 0.1)
				(type default)
			)
			(layer "F.SilkS")
		)
		(fp_line
			(start 16.743426 -0.882904)
			(end 16.803624 -0.882904)
			(stroke
				(width 0.1)
				(type default)
			)
			(layer "F.SilkS")
		)
		(fp_line
			(start 16.743426 -0.882904)
			(end 16.803624 -0.882904)
			(stroke
				(width 0.1)
				(type default)
			)
			(layer "F.SilkS")
		)
		(fp_line
			(start 16.743426 -0.882904)
			(end 17.847564 -1.942338)
			(stroke
				(width 0.1)
				(type default)
			)
			(layer "F.SilkS")
		)
		(fp_line
			(start 16.743426 -0.882904)
			(end 17.847564 -1.942338)
			(stroke
				(width 0.1)
				(type default)
			)
			(layer "F.SilkS")
		)
		(fp_line
			(start 16.747236 -2.098548)
			(end 16.735044 -2.028952)
			(stroke
				(width 0.1)
				(type default)
			)
			(layer "F.SilkS")
		)
		(fp_line
			(start 16.747236 -2.098548)
			(end 16.735044 -2.028952)
			(stroke
				(width 0.1)
				(type default)
			)
			(layer "F.SilkS")
		)
		(fp_line
			(start 16.747236 -2.098548)
			(end 18.097246 -3.393694)
			(stroke
				(width 0.1)
				(type default)
			)
			(layer "F.SilkS")
		)
		(fp_line
			(start 16.747236 -2.098548)
			(end 18.097246 -3.393694)
			(stroke
				(width 0.1)
				(type default)
			)
			(layer "F.SilkS")
		)
		(fp_line
			(start 16.759682 -2.16789)
			(end 16.747236 -2.098548)
			(stroke
				(width 0.1)
				(type default)
			)
			(layer "F.SilkS")
		)
		(fp_line
			(start 16.759682 -2.16789)
			(end 16.747236 -2.098548)
			(stroke
				(width 0.1)
				(type default)
			)
			(layer "F.SilkS")
		)
		(fp_line
			(start 16.759682 -2.16789)
			(end 18.105374 -3.458718)
			(stroke
				(width 0.1)
				(type default)
			)
			(layer "F.SilkS")
		)
		(fp_line
			(start 16.759682 -2.16789)
			(end 18.105374 -3.458718)
			(stroke
				(width 0.1)
				(type default)
			)
			(layer "F.SilkS")
		)
		(fp_line
			(start 16.77162 -2.237232)
			(end 16.759682 -2.16789)
			(stroke
				(width 0.1)
				(type default)
			)
			(layer "F.SilkS")
		)
		(fp_line
			(start 16.77162 -2.237232)
			(end 16.759682 -2.16789)
			(stroke
				(width 0.1)
				(type default)
			)
			(layer "F.SilkS")
		)
		(fp_line
			(start 16.77162 -2.237232)
			(end 18.113248 -3.52425)
			(stroke
				(width 0.1)
				(type default)
			)
			(layer "F.SilkS")
		)
		(fp_line
			(start 16.77162 -2.237232)
			(end 18.113248 -3.52425)
			(stroke
				(width 0.1)
				(type default)
			)
			(layer "F.SilkS")
		)
		(fp_line
			(start 16.783812 -2.306828)
			(end 16.77162 -2.237232)
			(stroke
				(width 0.1)
				(type default)
			)
			(layer "F.SilkS")
		)
		(fp_line
			(start 16.783812 -2.306828)
			(end 16.77162 -2.237232)
			(stroke
				(width 0.1)
				(type default)
			)
			(layer "F.SilkS")
		)
		(fp_line
			(start 16.783812 -2.306828)
			(end 18.121122 -3.589782)
			(stroke
				(width 0.1)
				(type default)
			)
			(layer "F.SilkS")
		)
		(fp_line
			(start 16.783812 -2.306828)
			(end 18.121122 -3.589782)
			(stroke
				(width 0.1)
				(type default)
			)
			(layer "F.SilkS")
		)
		(fp_line
			(start 16.790162 -5.256022)
			(end 14.291818 -2.859532)
			(stroke
				(width 0.1)
				(type default)
			)
			(layer "F.SilkS")
		)
		(fp_line
			(start 16.790162 -5.256022)
			(end 14.291818 -2.859532)
			(stroke
				(width 0.1)
				(type default)
			)
			(layer "F.SilkS")
		)
		(fp_line
			(start 16.796258 -2.37617)
			(end 16.783812 -2.306828)
			(stroke
				(width 0.1)
				(type default)
			)
			(layer "F.SilkS")
		)
		(fp_line
			(start 16.796258 -2.37617)
			(end 16.783812 -2.306828)
			(stroke
				(width 0.1)
				(type default)
			)
			(layer "F.SilkS")
		)
		(fp_line
			(start 16.796258 -2.37617)
			(end 18.129504 -3.65506)
			(stroke
				(width 0.1)
				(type default)
			)
			(layer "F.SilkS")
		)
		(fp_line
			(start 16.796258 -2.37617)
			(end 18.129504 -3.65506)
			(stroke
				(width 0.1)
				(type default)
			)
			(layer "F.SilkS")
		)
		(fp_line
			(start 16.803624 -0.882904)
			(end 16.863568 -0.882904)
			(stroke
				(width 0.1)
				(type default)
			)
			(layer "F.SilkS")
		)
		(fp_line
			(start 16.803624 -0.882904)
			(end 16.863568 -0.882904)
			(stroke
				(width 0.1)
				(type default)
			)
			(layer "F.SilkS")
		)
		(fp_line
			(start 16.803624 -0.882904)
			(end 17.835626 -1.872742)
			(stroke
				(width 0.1)
				(type default)
			)
			(layer "F.SilkS")
		)
		(fp_line
			(start 16.803624 -0.882904)
			(end 17.835626 -1.872742)
			(stroke
				(width 0.1)
				(type default)
			)
			(layer "F.SilkS")
		)
		(fp_line
			(start 16.808196 -2.445512)
			(end 16.796258 -2.37617)
			(stroke
				(width 0.1)
				(type default)
			)
			(layer "F.SilkS")
		)
		(fp_line
			(start 16.808196 -2.445512)
			(end 16.796258 -2.37617)
			(stroke
				(width 0.1)
				(type default)
			)
			(layer "F.SilkS")
		)
		(fp_line
			(start 16.808196 -2.445512)
			(end 18.13687 -3.720338)
			(stroke
				(width 0.1)
				(type default)
			)
			(layer "F.SilkS")
		)
		(fp_line
			(start 16.808196 -2.445512)
			(end 18.13687 -3.720338)
			(stroke
				(width 0.1)
				(type default)
			)
			(layer "F.SilkS")
		)
		(fp_line
			(start 16.820134 -2.515108)
			(end 16.808196 -2.445512)
			(stroke
				(width 0.1)
				(type default)
			)
			(layer "F.SilkS")
		)
		(fp_line
			(start 16.820134 -2.515108)
			(end 16.808196 -2.445512)
			(stroke
				(width 0.1)
				(type default)
			)
			(layer "F.SilkS")
		)
		(fp_line
			(start 16.820134 -2.515108)
			(end 16.83258 -2.58445)
			(stroke
				(width 0.1)
				(type default)
			)
			(layer "F.SilkS")
		)
		(fp_line
			(start 16.820134 -2.515108)
			(end 16.83258 -2.58445)
			(stroke
				(width 0.1)
				(type default)
			)
			(layer "F.SilkS")
		)
		(fp_line
			(start 16.820134 -2.515108)
			(end 18.138394 -3.779266)
			(stroke
				(width 0.1)
				(type default)
			)
			(layer "F.SilkS")
		)
		(fp_line
			(start 16.820134 -2.515108)
			(end 18.138394 -3.779266)
			(stroke
				(width 0.1)
				(type default)
			)
			(layer "F.SilkS")
		)
		(fp_line
			(start 16.845026 -2.653792)
			(end 16.83258 -2.58445)
			(stroke
				(width 0.1)
				(type default)
			)
			(layer "F.SilkS")
		)
		(fp_line
			(start 16.845026 -2.653792)
			(end 16.83258 -2.58445)
			(stroke
				(width 0.1)
				(type default)
			)
			(layer "F.SilkS")
		)
		(fp_line
			(start 16.845026 -2.653792)
			(end 18.137378 -3.89382)
			(stroke
				(width 0.1)
				(type default)
			)
			(layer "F.SilkS")
		)
		(fp_line
			(start 16.845026 -2.653792)
			(end 18.137378 -3.89382)
			(stroke
				(width 0.1)
				(type default)
			)
			(layer "F.SilkS")
		)
		(fp_line
			(start 16.854678 -5.26034)
			(end 14.27988 -2.79019)
			(stroke
				(width 0.1)
				(type default)
			)
			(layer "F.SilkS")
		)
		(fp_line
			(start 16.854678 -5.26034)
			(end 14.27988 -2.79019)
			(stroke
				(width 0.1)
				(type default)
			)
			(layer "F.SilkS")
		)
		(fp_line
			(start 16.857218 -2.723134)
			(end 16.845026 -2.653792)
			(stroke
				(width 0.1)
				(type default)
			)
			(layer "F.SilkS")
		)
		(fp_line
			(start 16.857218 -2.723134)
			(end 16.845026 -2.653792)
			(stroke
				(width 0.1)
				(type default)
			)
			(layer "F.SilkS")
		)
		(fp_line
			(start 16.857218 -2.723134)
			(end 18.13687 -3.95097)
			(stroke
				(width 0.1)
				(type default)
			)
			(layer "F.SilkS")
		)
		(fp_line
			(start 16.857218 -2.723134)
			(end 18.13687 -3.95097)
			(stroke
				(width 0.1)
				(type default)
			)
			(layer "F.SilkS")
		)
		(fp_line
			(start 16.863568 -0.882904)
			(end 16.92402 -0.882904)
			(stroke
				(width 0.1)
				(type default)
			)
			(layer "F.SilkS")
		)
		(fp_line
			(start 16.863568 -0.882904)
			(end 16.92402 -0.882904)
			(stroke
				(width 0.1)
				(type default)
			)
			(layer "F.SilkS")
		)
		(fp_line
			(start 16.863568 -0.882904)
			(end 17.823434 -1.8034)
			(stroke
				(width 0.1)
				(type default)
			)
			(layer "F.SilkS")
		)
		(fp_line
			(start 16.863568 -0.882904)
			(end 17.823434 -1.8034)
			(stroke
				(width 0.1)
				(type default)
			)
			(layer "F.SilkS")
		)
		(fp_line
			(start 16.869156 -2.79273)
			(end 16.857218 -2.723134)
			(stroke
				(width 0.1)
				(type default)
			)
			(layer "F.SilkS")
		)
		(fp_line
			(start 16.869156 -2.79273)
			(end 16.857218 -2.723134)
			(stroke
				(width 0.1)
				(type default)
			)
			(layer "F.SilkS")
		)
		(fp_line
			(start 16.869156 -2.79273)
			(end 18.136362 -4.008374)
			(stroke
				(width 0.1)
				(type default)
			)
			(layer "F.SilkS")
		)
		(fp_line
			(start 16.869156 -2.79273)
			(end 18.136362 -4.008374)
			(stroke
				(width 0.1)
				(type default)
			)
			(layer "F.SilkS")
		)
		(fp_line
			(start 16.881602 -2.862072)
			(end 16.869156 -2.79273)
			(stroke
				(width 0.1)
				(type default)
			)
			(layer "F.SilkS")
		)
		(fp_line
			(start 16.881602 -2.862072)
			(end 16.869156 -2.79273)
			(stroke
				(width 0.1)
				(type default)
			)
			(layer "F.SilkS")
		)
		(fp_line
			(start 16.881602 -2.862072)
			(end 18.136362 -4.065524)
			(stroke
				(width 0.1)
				(type default)
			)
			(layer "F.SilkS")
		)
		(fp_line
			(start 16.881602 -2.862072)
			(end 18.136362 -4.065524)
			(stroke
				(width 0.1)
				(type default)
			)
			(layer "F.SilkS")
		)
		(fp_line
			(start 16.89354 -2.931414)
			(end 16.881602 -2.862072)
			(stroke
				(width 0.1)
				(type default)
			)
			(layer "F.SilkS")
		)
		(fp_line
			(start 16.89354 -2.931414)
			(end 16.881602 -2.862072)
			(stroke
				(width 0.1)
				(type default)
			)
			(layer "F.SilkS")
		)
		(fp_line
			(start 16.89354 -2.931414)
			(end 18.134838 -4.121912)
			(stroke
				(width 0.1)
				(type default)
			)
			(layer "F.SilkS")
		)
		(fp_line
			(start 16.89354 -2.931414)
			(end 18.134838 -4.121912)
			(stroke
				(width 0.1)
				(type default)
			)
			(layer "F.SilkS")
		)
		(fp_line
			(start 16.905732 -3.000756)
			(end 16.89354 -2.931414)
			(stroke
				(width 0.1)
				(type default)
			)
			(layer "F.SilkS")
		)
		(fp_line
			(start 16.905732 -3.000756)
			(end 16.89354 -2.931414)
			(stroke
				(width 0.1)
				(type default)
			)
			(layer "F.SilkS")
		)
		(fp_line
			(start 16.905732 -3.000756)
			(end 18.125948 -4.171188)
			(stroke
				(width 0.1)
				(type default)
			)
			(layer "F.SilkS")
		)
		(fp_line
			(start 16.905732 -3.000756)
			(end 18.125948 -4.171188)
			(stroke
				(width 0.1)
				(type default)
			)
			(layer "F.SilkS")
		)
		(fp_line
			(start 16.909796 -5.255514)
			(end 14.267434 -2.720594)
			(stroke
				(width 0.1)
				(type default)
			)
			(layer "F.SilkS")
		)
		(fp_line
			(start 16.909796 -5.255514)
			(end 14.267434 -2.720594)
			(stroke
				(width 0.1)
				(type default)
			)
			(layer "F.SilkS")
		)
		(fp_line
			(start 16.918178 -3.070352)
			(end 16.905732 -3.000756)
			(stroke
				(width 0.1)
				(type default)
			)
			(layer "F.SilkS")
		)
		(fp_line
			(start 16.918178 -3.070352)
			(end 16.905732 -3.000756)
			(stroke
				(width 0.1)
				(type default)
			)
			(layer "F.SilkS")
		)
		(fp_line
			(start 16.918178 -3.070352)
			(end 18.117058 -4.220464)
			(stroke
				(width 0.1)
				(type default)
			)
			(layer "F.SilkS")
		)
		(fp_line
			(start 16.918178 -3.070352)
			(end 18.117058 -4.220464)
			(stroke
				(width 0.1)
				(type default)
			)
			(layer "F.SilkS")
		)
		(fp_line
			(start 16.92402 -0.882904)
			(end 16.984218 -0.882904)
			(stroke
				(width 0.1)
				(type default)
			)
			(layer "F.SilkS")
		)
		(fp_line
			(start 16.92402 -0.882904)
			(end 16.984218 -0.882904)
			(stroke
				(width 0.1)
				(type default)
			)
			(layer "F.SilkS")
		)
		(fp_line
			(start 16.92402 -0.882904)
			(end 17.810988 -1.734058)
			(stroke
				(width 0.1)
				(type default)
			)
			(layer "F.SilkS")
		)
		(fp_line
			(start 16.92402 -0.882904)
			(end 17.810988 -1.734058)
			(stroke
				(width 0.1)
				(type default)
			)
			(layer "F.SilkS")
		)
		(fp_line
			(start 16.930624 -3.139694)
			(end 16.918178 -3.070352)
			(stroke
				(width 0.1)
				(type default)
			)
			(layer "F.SilkS")
		)
		(fp_line
			(start 16.930624 -3.139694)
			(end 16.918178 -3.070352)
			(stroke
				(width 0.1)
				(type default)
			)
			(layer "F.SilkS")
		)
		(fp_line
			(start 16.96466 -5.25018)
			(end 14.255496 -2.651506)
			(stroke
				(width 0.1)
				(type default)
			)
			(layer "F.SilkS")
		)
		(fp_line
			(start 16.96466 -5.25018)
			(end 14.255496 -2.651506)
			(stroke
				(width 0.1)
				(type default)
			)
			(layer "F.SilkS")
		)
		(fp_line
			(start 16.984218 -0.882904)
			(end 17.044162 -0.882904)
			(stroke
				(width 0.1)
				(type default)
			)
			(layer "F.SilkS")
		)
		(fp_line
			(start 16.984218 -0.882904)
			(end 17.044162 -0.882904)
			(stroke
				(width 0.1)
				(type default)
			)
			(layer "F.SilkS")
		)
		(fp_line
			(start 16.984218 -0.882904)
			(end 17.79905 -1.664716)
			(stroke
				(width 0.1)
				(type default)
			)
			(layer "F.SilkS")
		)
		(fp_line
			(start 16.984218 -0.882904)
			(end 17.79905 -1.664716)
			(stroke
				(width 0.1)
				(type default)
			)
			(layer "F.SilkS")
		)
		(fp_line
			(start 17.01927 -5.245354)
			(end 14.243304 -2.58191)
			(stroke
				(width 0.1)
				(type default)
			)
			(layer "F.SilkS")
		)
		(fp_line
			(start 17.01927 -5.245354)
			(end 14.243304 -2.58191)
			(stroke
				(width 0.1)
				(type default)
			)
			(layer "F.SilkS")
		)
		(fp_line
			(start 17.044162 -0.882904)
			(end 17.10436 -0.882904)
			(stroke
				(width 0.1)
				(type default)
			)
			(layer "F.SilkS")
		)
		(fp_line
			(start 17.044162 -0.882904)
			(end 17.10436 -0.882904)
			(stroke
				(width 0.1)
				(type default)
			)
			(layer "F.SilkS")
		)
		(fp_line
			(start 17.044162 -0.882904)
			(end 17.786858 -1.595374)
			(stroke
				(width 0.1)
				(type default)
			)
			(layer "F.SilkS")
		)
		(fp_line
			(start 17.044162 -0.882904)
			(end 17.786858 -1.595374)
			(stroke
				(width 0.1)
				(type default)
			)
			(layer "F.SilkS")
		)
		(fp_line
			(start 17.074388 -5.240274)
			(end 14.230858 -2.512314)
			(stroke
				(width 0.1)
				(type default)
			)
			(layer "F.SilkS")
		)
		(fp_line
			(start 17.074388 -5.240274)
			(end 14.230858 -2.512314)
			(stroke
				(width 0.1)
				(type default)
			)
			(layer "F.SilkS")
		)
		(fp_line
			(start 17.10436 -0.882904)
			(end 17.164812 -0.882904)
			(stroke
				(width 0.1)
				(type default)
			)
			(layer "F.SilkS")
		)
		(fp_line
			(start 17.10436 -0.882904)
			(end 17.164812 -0.882904)
			(stroke
				(width 0.1)
				(type default)
			)
			(layer "F.SilkS")
		)
		(fp_line
			(start 17.10436 -0.882904)
			(end 17.774666 -1.525778)
			(stroke
				(width 0.1)
				(type default)
			)
			(layer "F.SilkS")
		)
		(fp_line
			(start 17.10436 -0.882904)
			(end 17.774666 -1.525778)
			(stroke
				(width 0.1)
				(type default)
			)
			(layer "F.SilkS")
		)
		(fp_line
			(start 17.129252 -5.235194)
			(end 15.934944 -4.0894)
			(stroke
				(width 0.1)
				(type default)
			)
			(layer "F.SilkS")
		)
		(fp_line
			(start 17.129252 -5.235194)
			(end 15.934944 -4.0894)
			(stroke
				(width 0.1)
				(type default)
			)
			(layer "F.SilkS")
		)
		(fp_line
			(start 17.164812 -0.882904)
			(end 17.224756 -0.882904)
			(stroke
				(width 0.1)
				(type default)
			)
			(layer "F.SilkS")
		)
		(fp_line
			(start 17.164812 -0.882904)
			(end 17.224756 -0.882904)
			(stroke
				(width 0.1)
				(type default)
			)
			(layer "F.SilkS")
		)
		(fp_line
			(start 17.164812 -0.882904)
			(end 17.762474 -1.456436)
			(stroke
				(width 0.1)
				(type default)
			)
			(layer "F.SilkS")
		)
		(fp_line
			(start 17.164812 -0.882904)
			(end 17.762474 -1.456436)
			(stroke
				(width 0.1)
				(type default)
			)
			(layer "F.SilkS")
		)
		(fp_line
			(start 17.184116 -5.230114)
			(end 16.052292 -4.144264)
			(stroke
				(width 0.1)
				(type default)
			)
			(layer "F.SilkS")
		)
		(fp_line
			(start 17.184116 -5.230114)
			(end 16.052292 -4.144264)
			(stroke
				(width 0.1)
				(type default)
			)
			(layer "F.SilkS")
		)
		(fp_line
			(start 17.224756 -0.882904)
			(end 17.284954 -0.882904)
			(stroke
				(width 0.1)
				(type default)
			)
			(layer "F.SilkS")
		)
		(fp_line
			(start 17.224756 -0.882904)
			(end 17.284954 -0.882904)
			(stroke
				(width 0.1)
				(type default)
			)
			(layer "F.SilkS")
		)
		(fp_line
			(start 17.224756 -0.882904)
			(end 17.750536 -1.387348)
			(stroke
				(width 0.1)
				(type default)
			)
			(layer "F.SilkS")
		)
		(fp_line
			(start 17.224756 -0.882904)
			(end 17.750536 -1.387348)
			(stroke
				(width 0.1)
				(type default)
			)
			(layer "F.SilkS")
		)
		(fp_line
			(start 17.235678 -5.221986)
			(end 16.13789 -4.168648)
			(stroke
				(width 0.1)
				(type default)
			)
			(layer "F.SilkS")
		)
		(fp_line
			(start 17.235678 -5.221986)
			(end 16.13789 -4.168648)
			(stroke
				(width 0.1)
				(type default)
			)
			(layer "F.SilkS")
		)
		(fp_line
			(start 17.280636 -5.207254)
			(end 16.218154 -4.187698)
			(stroke
				(width 0.1)
				(type default)
			)
			(layer "F.SilkS")
		)
		(fp_line
			(start 17.280636 -5.207254)
			(end 16.218154 -4.187698)
			(stroke
				(width 0.1)
				(type default)
			)
			(layer "F.SilkS")
		)
		(fp_line
			(start 17.284954 -0.882904)
			(end 17.345406 -0.882904)
			(stroke
				(width 0.1)
				(type default)
			)
			(layer "F.SilkS")
		)
		(fp_line
			(start 17.284954 -0.882904)
			(end 17.345406 -0.882904)
			(stroke
				(width 0.1)
				(type default)
			)
			(layer "F.SilkS")
		)
		(fp_line
			(start 17.284954 -0.882904)
			(end 17.73809 -1.317752)
			(stroke
				(width 0.1)
				(type default)
			)
			(layer "F.SilkS")
		)
		(fp_line
			(start 17.284954 -0.882904)
			(end 17.73809 -1.317752)
			(stroke
				(width 0.1)
				(type default)
			)
			(layer "F.SilkS")
		)
		(fp_line
			(start 17.32534 -5.192522)
			(end 16.283178 -4.192524)
			(stroke
				(width 0.1)
				(type default)
			)
			(layer "F.SilkS")
		)
		(fp_line
			(start 17.32534 -5.192522)
			(end 16.283178 -4.192524)
			(stroke
				(width 0.1)
				(type default)
			)
			(layer "F.SilkS")
		)
		(fp_line
			(start 17.345406 -0.882904)
			(end 17.40535 -0.882904)
			(stroke
				(width 0.1)
				(type default)
			)
			(layer "F.SilkS")
		)
		(fp_line
			(start 17.345406 -0.882904)
			(end 17.40535 -0.882904)
			(stroke
				(width 0.1)
				(type default)
			)
			(layer "F.SilkS")
		)
		(fp_line
			(start 17.345406 -0.882904)
			(end 17.725898 -1.248156)
			(stroke
				(width 0.1)
				(type default)
			)
			(layer "F.SilkS")
		)
		(fp_line
			(start 17.345406 -0.882904)
			(end 17.725898 -1.248156)
			(stroke
				(width 0.1)
				(type default)
			)
			(layer "F.SilkS")
		)
		(fp_line
			(start 17.370044 -5.17779)
			(end 16.347948 -4.197096)
			(stroke
				(width 0.1)
				(type default)
			)
			(layer "F.SilkS")
		)
		(fp_line
			(start 17.370044 -5.17779)
			(end 16.347948 -4.197096)
			(stroke
				(width 0.1)
				(type default)
			)
			(layer "F.SilkS")
		)
		(fp_line
			(start 17.40535 -0.882904)
			(end 17.465294 -0.882904)
			(stroke
				(width 0.1)
				(type default)
			)
			(layer "F.SilkS")
		)
		(fp_line
			(start 17.40535 -0.882904)
			(end 17.465294 -0.882904)
			(stroke
				(width 0.1)
				(type default)
			)
			(layer "F.SilkS")
		)
		(fp_line
			(start 17.40535 -0.882904)
			(end 17.71396 -1.178814)
			(stroke
				(width 0.1)
				(type default)
			)
			(layer "F.SilkS")
		)
		(fp_line
			(start 17.40535 -0.882904)
			(end 17.71396 -1.178814)
			(stroke
				(width 0.1)
				(type default)
			)
			(layer "F.SilkS")
		)
		(fp_line
			(start 17.415002 -5.163058)
			(end 16.40967 -4.198366)
			(stroke
				(width 0.1)
				(type default)
			)
			(layer "F.SilkS")
		)
		(fp_line
			(start 17.415002 -5.163058)
			(end 16.40967 -4.198366)
			(stroke
				(width 0.1)
				(type default)
			)
			(layer "F.SilkS")
		)
		(fp_line
			(start 17.45996 -5.148326)
			(end 16.465804 -4.194556)
			(stroke
				(width 0.1)
				(type default)
			)
			(layer "F.SilkS")
		)
		(fp_line
			(start 17.45996 -5.148326)
			(end 16.465804 -4.194556)
			(stroke
				(width 0.1)
				(type default)
			)
			(layer "F.SilkS")
		)
		(fp_line
			(start 17.465294 -0.882904)
			(end 17.525746 -0.882904)
			(stroke
				(width 0.1)
				(type default)
			)
			(layer "F.SilkS")
		)
		(fp_line
			(start 17.465294 -0.882904)
			(end 17.525746 -0.882904)
			(stroke
				(width 0.1)
				(type default)
			)
			(layer "F.SilkS")
		)
		(fp_line
			(start 17.465294 -0.882904)
			(end 17.701514 -1.109472)
			(stroke
				(width 0.1)
				(type default)
			)
			(layer "F.SilkS")
		)
		(fp_line
			(start 17.465294 -0.882904)
			(end 17.701514 -1.109472)
			(stroke
				(width 0.1)
				(type default)
			)
			(layer "F.SilkS")
		)
		(fp_line
			(start 17.50441 -5.13334)
			(end 16.521938 -4.190746)
			(stroke
				(width 0.1)
				(type default)
			)
			(layer "F.SilkS")
		)
		(fp_line
			(start 17.50441 -5.13334)
			(end 16.521938 -4.190746)
			(stroke
				(width 0.1)
				(type default)
			)
			(layer "F.SilkS")
		)
		(fp_line
			(start 17.525746 -0.882904)
			(end 17.58569 -0.882904)
			(stroke
				(width 0.1)
				(type default)
			)
			(layer "F.SilkS")
		)
		(fp_line
			(start 17.525746 -0.882904)
			(end 17.58569 -0.882904)
			(stroke
				(width 0.1)
				(type default)
			)
			(layer "F.SilkS")
		)
		(fp_line
			(start 17.525746 -0.882904)
			(end 17.689576 -1.04013)
			(stroke
				(width 0.1)
				(type default)
			)
			(layer "F.SilkS")
		)
		(fp_line
			(start 17.525746 -0.882904)
			(end 17.689576 -1.04013)
			(stroke
				(width 0.1)
				(type default)
			)
			(layer "F.SilkS")
		)
		(fp_line
			(start 17.545558 -5.115052)
			(end 16.5735 -4.182872)
			(stroke
				(width 0.1)
				(type default)
			)
			(layer "F.SilkS")
		)
		(fp_line
			(start 17.545558 -5.115052)
			(end 16.5735 -4.182872)
			(stroke
				(width 0.1)
				(type default)
			)
			(layer "F.SilkS")
		)
		(fp_line
			(start 17.580864 -5.091176)
			(end 16.621252 -4.170426)
			(stroke
				(width 0.1)
				(type default)
			)
			(layer "F.SilkS")
		)
		(fp_line
			(start 17.580864 -5.091176)
			(end 16.621252 -4.170426)
			(stroke
				(width 0.1)
				(type default)
			)
			(layer "F.SilkS")
		)
		(fp_line
			(start 17.58569 -0.882904)
			(end 17.645634 -0.882904)
			(stroke
				(width 0.1)
				(type default)
			)
			(layer "F.SilkS")
		)
		(fp_line
			(start 17.58569 -0.882904)
			(end 17.645634 -0.882904)
			(stroke
				(width 0.1)
				(type default)
			)
			(layer "F.SilkS")
		)
		(fp_line
			(start 17.58569 -0.882904)
			(end 17.677384 -0.970788)
			(stroke
				(width 0.1)
				(type default)
			)
			(layer "F.SilkS")
		)
		(fp_line
			(start 17.58569 -0.882904)
			(end 17.677384 -0.970788)
			(stroke
				(width 0.1)
				(type default)
			)
			(layer "F.SilkS")
		)
		(fp_line
			(start 17.61617 -5.067046)
			(end 16.668242 -4.15798)
			(stroke
				(width 0.1)
				(type default)
			)
			(layer "F.SilkS")
		)
		(fp_line
			(start 17.61617 -5.067046)
			(end 16.668242 -4.15798)
			(stroke
				(width 0.1)
				(type default)
			)
			(layer "F.SilkS")
		)
		(fp_line
			(start 17.645634 -0.882904)
			(end 17.66189 -0.882904)
			(stroke
				(width 0.1)
				(type default)
			)
			(layer "F.SilkS")
		)
		(fp_line
			(start 17.645634 -0.882904)
			(end 17.66189 -0.882904)
			(stroke
				(width 0.1)
				(type default)
			)
			(layer "F.SilkS")
		)
		(fp_line
			(start 17.645634 -0.882904)
			(end 17.664938 -0.901192)
			(stroke
				(width 0.1)
				(type default)
			)
			(layer "F.SilkS")
		)
		(fp_line
			(start 17.645634 -0.882904)
			(end 17.664938 -0.901192)
			(stroke
				(width 0.1)
				(type default)
			)
			(layer "F.SilkS")
		)
		(fp_line
			(start 17.651222 -5.043424)
			(end 16.71066 -4.140962)
			(stroke
				(width 0.1)
				(type default)
			)
			(layer "F.SilkS")
		)
		(fp_line
			(start 17.651222 -5.043424)
			(end 16.71066 -4.140962)
			(stroke
				(width 0.1)
				(type default)
			)
			(layer "F.SilkS")
		)
		(fp_line
			(start 17.66189 -0.882904)
			(end 17.664938 -0.901192)
			(stroke
				(width 0.1)
				(type default)
			)
			(layer "F.SilkS")
		)
		(fp_line
			(start 17.66189 -0.882904)
			(end 17.664938 -0.901192)
			(stroke
				(width 0.1)
				(type default)
			)
			(layer "F.SilkS")
		)
		(fp_line
			(start 17.677384 -0.970788)
			(end 17.664938 -0.901192)
			(stroke
				(width 0.1)
				(type default)
			)
			(layer "F.SilkS")
		)
		(fp_line
			(start 17.677384 -0.970788)
			(end 17.664938 -0.901192)
			(stroke
				(width 0.1)
				(type default)
			)
			(layer "F.SilkS")
		)
		(fp_line
			(start 17.686274 -5.019294)
			(end 16.747998 -4.119118)
			(stroke
				(width 0.1)
				(type default)
			)
			(layer "F.SilkS")
		)
		(fp_line
			(start 17.686274 -5.019294)
			(end 16.747998 -4.119118)
			(stroke
				(width 0.1)
				(type default)
			)
			(layer "F.SilkS")
		)
		(fp_line
			(start 17.689576 -1.04013)
			(end 17.677384 -0.970788)
			(stroke
				(width 0.1)
				(type default)
			)
			(layer "F.SilkS")
		)
		(fp_line
			(start 17.689576 -1.04013)
			(end 17.677384 -0.970788)
			(stroke
				(width 0.1)
				(type default)
			)
			(layer "F.SilkS")
		)
		(fp_line
			(start 17.701514 -1.109472)
			(end 17.689576 -1.04013)
			(stroke
				(width 0.1)
				(type default)
			)
			(layer "F.SilkS")
		)
		(fp_line
			(start 17.701514 -1.109472)
			(end 17.689576 -1.04013)
			(stroke
				(width 0.1)
				(type default)
			)
			(layer "F.SilkS")
		)
		(fp_line
			(start 17.71396 -1.178814)
			(end 17.701514 -1.109472)
			(stroke
				(width 0.1)
				(type default)
			)
			(layer "F.SilkS")
		)
		(fp_line
			(start 17.71396 -1.178814)
			(end 17.701514 -1.109472)
			(stroke
				(width 0.1)
				(type default)
			)
			(layer "F.SilkS")
		)
		(fp_line
			(start 17.721834 -4.995672)
			(end 16.785844 -4.097782)
			(stroke
				(width 0.1)
				(type default)
			)
			(layer "F.SilkS")
		)
		(fp_line
			(start 17.721834 -4.995672)
			(end 16.785844 -4.097782)
			(stroke
				(width 0.1)
				(type default)
			)
			(layer "F.SilkS")
		)
		(fp_line
			(start 17.725898 -1.248156)
			(end 17.71396 -1.178814)
			(stroke
				(width 0.1)
				(type default)
			)
			(layer "F.SilkS")
		)
		(fp_line
			(start 17.725898 -1.248156)
			(end 17.71396 -1.178814)
			(stroke
				(width 0.1)
				(type default)
			)
			(layer "F.SilkS")
		)
		(fp_line
			(start 17.73809 -1.317752)
			(end 17.725898 -1.248156)
			(stroke
				(width 0.1)
				(type default)
			)
			(layer "F.SilkS")
		)
		(fp_line
			(start 17.73809 -1.317752)
			(end 17.725898 -1.248156)
			(stroke
				(width 0.1)
				(type default)
			)
			(layer "F.SilkS")
		)
		(fp_line
			(start 17.750536 -1.387348)
			(end 17.73809 -1.317752)
			(stroke
				(width 0.1)
				(type default)
			)
			(layer "F.SilkS")
		)
		(fp_line
			(start 17.750536 -1.387348)
			(end 17.73809 -1.317752)
			(stroke
				(width 0.1)
				(type default)
			)
			(layer "F.SilkS")
		)
		(fp_line
			(start 17.757394 -4.971796)
			(end 16.818102 -4.071112)
			(stroke
				(width 0.1)
				(type default)
			)
			(layer "F.SilkS")
		)
		(fp_line
			(start 17.757394 -4.971796)
			(end 16.818102 -4.071112)
			(stroke
				(width 0.1)
				(type default)
			)
			(layer "F.SilkS")
		)
		(fp_line
			(start 17.762474 -1.456436)
			(end 17.750536 -1.387348)
			(stroke
				(width 0.1)
				(type default)
			)
			(layer "F.SilkS")
		)
		(fp_line
			(start 17.762474 -1.456436)
			(end 17.750536 -1.387348)
			(stroke
				(width 0.1)
				(type default)
			)
			(layer "F.SilkS")
		)
		(fp_line
			(start 17.774666 -1.525778)
			(end 17.762474 -1.456436)
			(stroke
				(width 0.1)
				(type default)
			)
			(layer "F.SilkS")
		)
		(fp_line
			(start 17.774666 -1.525778)
			(end 17.762474 -1.456436)
			(stroke
				(width 0.1)
				(type default)
			)
			(layer "F.SilkS")
		)
		(fp_line
			(start 17.786858 -1.595374)
			(end 17.774666 -1.525778)
			(stroke
				(width 0.1)
				(type default)
			)
			(layer "F.SilkS")
		)
		(fp_line
			(start 17.786858 -1.595374)
			(end 17.774666 -1.525778)
			(stroke
				(width 0.1)
				(type default)
			)
			(layer "F.SilkS")
		)
		(fp_line
			(start 17.78762 -4.943348)
			(end 16.845788 -4.03987)
			(stroke
				(width 0.1)
				(type default)
			)
			(layer "F.SilkS")
		)
		(fp_line
			(start 17.78762 -4.943348)
			(end 16.845788 -4.03987)
			(stroke
				(width 0.1)
				(type default)
			)
			(layer "F.SilkS")
		)
		(fp_line
			(start 17.79905 -1.664716)
			(end 17.786858 -1.595374)
			(stroke
				(width 0.1)
				(type default)
			)
			(layer "F.SilkS")
		)
		(fp_line
			(start 17.79905 -1.664716)
			(end 17.786858 -1.595374)
			(stroke
				(width 0.1)
				(type default)
			)
			(layer "F.SilkS")
		)
		(fp_line
			(start 17.810988 -1.734058)
			(end 17.79905 -1.664716)
			(stroke
				(width 0.1)
				(type default)
			)
			(layer "F.SilkS")
		)
		(fp_line
			(start 17.810988 -1.734058)
			(end 17.79905 -1.664716)
			(stroke
				(width 0.1)
				(type default)
			)
			(layer "F.SilkS")
		)
		(fp_line
			(start 17.813782 -4.910836)
			(end 16.87322 -4.008882)
			(stroke
				(width 0.1)
				(type default)
			)
			(layer "F.SilkS")
		)
		(fp_line
			(start 17.813782 -4.910836)
			(end 16.87322 -4.008882)
			(stroke
				(width 0.1)
				(type default)
			)
			(layer "F.SilkS")
		)
		(fp_line
			(start 17.823434 -1.8034)
			(end 17.810988 -1.734058)
			(stroke
				(width 0.1)
				(type default)
			)
			(layer "F.SilkS")
		)
		(fp_line
			(start 17.823434 -1.8034)
			(end 17.810988 -1.734058)
			(stroke
				(width 0.1)
				(type default)
			)
			(layer "F.SilkS")
		)
		(fp_line
			(start 17.835626 -1.872742)
			(end 17.823434 -1.8034)
			(stroke
				(width 0.1)
				(type default)
			)
			(layer "F.SilkS")
		)
		(fp_line
			(start 17.835626 -1.872742)
			(end 17.823434 -1.8034)
			(stroke
				(width 0.1)
				(type default)
			)
			(layer "F.SilkS")
		)
		(fp_line
			(start 17.839944 -4.878324)
			(end 16.89735 -3.97383)
			(stroke
				(width 0.1)
				(type default)
			)
			(layer "F.SilkS")
		)
		(fp_line
			(start 17.839944 -4.878324)
			(end 16.89735 -3.97383)
			(stroke
				(width 0.1)
				(type default)
			)
			(layer "F.SilkS")
		)
		(fp_line
			(start 17.847564 -1.942338)
			(end 17.835626 -1.872742)
			(stroke
				(width 0.1)
				(type default)
			)
			(layer "F.SilkS")
		)
		(fp_line
			(start 17.847564 -1.942338)
			(end 17.835626 -1.872742)
			(stroke
				(width 0.1)
				(type default)
			)
			(layer "F.SilkS")
		)
		(fp_line
			(start 17.86001 -2.011426)
			(end 17.847564 -1.942338)
			(stroke
				(width 0.1)
				(type default)
			)
			(layer "F.SilkS")
		)
		(fp_line
			(start 17.86001 -2.011426)
			(end 17.847564 -1.942338)
			(stroke
				(width 0.1)
				(type default)
			)
			(layer "F.SilkS")
		)
		(fp_line
			(start 17.866106 -4.845558)
			(end 16.915384 -3.93319)
			(stroke
				(width 0.1)
				(type default)
			)
			(layer "F.SilkS")
		)
		(fp_line
			(start 17.866106 -4.845558)
			(end 16.915384 -3.93319)
			(stroke
				(width 0.1)
				(type default)
			)
			(layer "F.SilkS")
		)
		(fp_line
			(start 17.871948 -2.081022)
			(end 17.86001 -2.011426)
			(stroke
				(width 0.1)
				(type default)
			)
			(layer "F.SilkS")
		)
		(fp_line
			(start 17.871948 -2.081022)
			(end 17.86001 -2.011426)
			(stroke
				(width 0.1)
				(type default)
			)
			(layer "F.SilkS")
		)
		(fp_line
			(start 17.88414 -2.150364)
			(end 17.871948 -2.081022)
			(stroke
				(width 0.1)
				(type default)
			)
			(layer "F.SilkS")
		)
		(fp_line
			(start 17.88414 -2.150364)
			(end 17.871948 -2.081022)
			(stroke
				(width 0.1)
				(type default)
			)
			(layer "F.SilkS")
		)
		(fp_line
			(start 17.892268 -4.813046)
			(end 16.93291 -3.89255)
			(stroke
				(width 0.1)
				(type default)
			)
			(layer "F.SilkS")
		)
		(fp_line
			(start 17.892268 -4.813046)
			(end 16.93291 -3.89255)
			(stroke
				(width 0.1)
				(type default)
			)
			(layer "F.SilkS")
		)
		(fp_line
			(start 17.896586 -2.21996)
			(end 17.88414 -2.150364)
			(stroke
				(width 0.1)
				(type default)
			)
			(layer "F.SilkS")
		)
		(fp_line
			(start 17.896586 -2.21996)
			(end 17.88414 -2.150364)
			(stroke
				(width 0.1)
				(type default)
			)
			(layer "F.SilkS")
		)
		(fp_line
			(start 17.908524 -2.289048)
			(end 17.896586 -2.21996)
			(stroke
				(width 0.1)
				(type default)
			)
			(layer "F.SilkS")
		)
		(fp_line
			(start 17.908524 -2.289048)
			(end 17.896586 -2.21996)
			(stroke
				(width 0.1)
				(type default)
			)
			(layer "F.SilkS")
		)
		(fp_line
			(start 17.91843 -4.780534)
			(end 16.949674 -3.850894)
			(stroke
				(width 0.1)
				(type default)
			)
			(layer "F.SilkS")
		)
		(fp_line
			(start 17.91843 -4.780534)
			(end 16.949674 -3.850894)
			(stroke
				(width 0.1)
				(type default)
			)
			(layer "F.SilkS")
		)
		(fp_line
			(start 17.920716 -2.35839)
			(end 17.908524 -2.289048)
			(stroke
				(width 0.1)
				(type default)
			)
			(layer "F.SilkS")
		)
		(fp_line
			(start 17.920716 -2.35839)
			(end 17.908524 -2.289048)
			(stroke
				(width 0.1)
				(type default)
			)
			(layer "F.SilkS")
		)
		(fp_line
			(start 17.932908 -2.427732)
			(end 17.920716 -2.35839)
			(stroke
				(width 0.1)
				(type default)
			)
			(layer "F.SilkS")
		)
		(fp_line
			(start 17.932908 -2.427732)
			(end 17.920716 -2.35839)
			(stroke
				(width 0.1)
				(type default)
			)
			(layer "F.SilkS")
		)
		(fp_line
			(start 17.944846 -4.748022)
			(end 16.958056 -3.80111)
			(stroke
				(width 0.1)
				(type default)
			)
			(layer "F.SilkS")
		)
		(fp_line
			(start 17.944846 -4.748022)
			(end 16.958056 -3.80111)
			(stroke
				(width 0.1)
				(type default)
			)
			(layer "F.SilkS")
		)
		(fp_line
			(start 17.9451 -2.497328)
			(end 17.932908 -2.427732)
			(stroke
				(width 0.1)
				(type default)
			)
			(layer "F.SilkS")
		)
		(fp_line
			(start 17.9451 -2.497328)
			(end 17.932908 -2.427732)
			(stroke
				(width 0.1)
				(type default)
			)
			(layer "F.SilkS")
		)
		(fp_line
			(start 17.957038 -2.56667)
			(end 17.9451 -2.497328)
			(stroke
				(width 0.1)
				(type default)
			)
			(layer "F.SilkS")
		)
		(fp_line
			(start 17.957038 -2.56667)
			(end 17.9451 -2.497328)
			(stroke
				(width 0.1)
				(type default)
			)
			(layer "F.SilkS")
		)
		(fp_line
			(start 17.966182 -4.710176)
			(end 16.966438 -3.751326)
			(stroke
				(width 0.1)
				(type default)
			)
			(layer "F.SilkS")
		)
		(fp_line
			(start 17.966182 -4.710176)
			(end 16.966438 -3.751326)
			(stroke
				(width 0.1)
				(type default)
			)
			(layer "F.SilkS")
		)
		(fp_line
			(start 17.969484 -2.636012)
			(end 17.957038 -2.56667)
			(stroke
				(width 0.1)
				(type default)
			)
			(layer "F.SilkS")
		)
		(fp_line
			(start 17.969484 -2.636012)
			(end 17.957038 -2.56667)
			(stroke
				(width 0.1)
				(type default)
			)
			(layer "F.SilkS")
		)
		(fp_line
			(start 17.981676 -2.705608)
			(end 17.969484 -2.636012)
			(stroke
				(width 0.1)
				(type default)
			)
			(layer "F.SilkS")
		)
		(fp_line
			(start 17.981676 -2.705608)
			(end 17.969484 -2.636012)
			(stroke
				(width 0.1)
				(type default)
			)
			(layer "F.SilkS")
		)
		(fp_line
			(start 17.9832 -4.669282)
			(end 16.974566 -3.701542)
			(stroke
				(width 0.1)
				(type default)
			)
			(layer "F.SilkS")
		)
		(fp_line
			(start 17.9832 -4.669282)
			(end 16.974566 -3.701542)
			(stroke
				(width 0.1)
				(type default)
			)
			(layer "F.SilkS")
		)
		(fp_line
			(start 17.993614 -2.77495)
			(end 17.981676 -2.705608)
			(stroke
				(width 0.1)
				(type default)
			)
			(layer "F.SilkS")
		)
		(fp_line
			(start 17.993614 -2.77495)
			(end 17.981676 -2.705608)
			(stroke
				(width 0.1)
				(type default)
			)
			(layer "F.SilkS")
		)
		(fp_line
			(start 18.000472 -4.628388)
			(end 16.97736 -3.646424)
			(stroke
				(width 0.1)
				(type default)
			)
			(layer "F.SilkS")
		)
		(fp_line
			(start 18.000472 -4.628388)
			(end 16.97736 -3.646424)
			(stroke
				(width 0.1)
				(type default)
			)
			(layer "F.SilkS")
		)
		(fp_line
			(start 18.00606 -2.844292)
			(end 17.993614 -2.77495)
			(stroke
				(width 0.1)
				(type default)
			)
			(layer "F.SilkS")
		)
		(fp_line
			(start 18.00606 -2.844292)
			(end 17.993614 -2.77495)
			(stroke
				(width 0.1)
				(type default)
			)
			(layer "F.SilkS")
		)
		(fp_line
			(start 18.017998 -4.58724)
			(end 16.976598 -3.588258)
			(stroke
				(width 0.1)
				(type default)
			)
			(layer "F.SilkS")
		)
		(fp_line
			(start 18.017998 -4.58724)
			(end 16.976598 -3.588258)
			(stroke
				(width 0.1)
				(type default)
			)
			(layer "F.SilkS")
		)
		(fp_line
			(start 18.017998 -2.913634)
			(end 18.00606 -2.844292)
			(stroke
				(width 0.1)
				(type default)
			)
			(layer "F.SilkS")
		)
		(fp_line
			(start 18.017998 -2.913634)
			(end 18.00606 -2.844292)
			(stroke
				(width 0.1)
				(type default)
			)
			(layer "F.SilkS")
		)
		(fp_line
			(start 18.03019 -2.982976)
			(end 18.017998 -2.913634)
			(stroke
				(width 0.1)
				(type default)
			)
			(layer "F.SilkS")
		)
		(fp_line
			(start 18.03019 -2.982976)
			(end 18.017998 -2.913634)
			(stroke
				(width 0.1)
				(type default)
			)
			(layer "F.SilkS")
		)
		(fp_line
			(start 18.035778 -4.546346)
			(end 16.97609 -3.529838)
			(stroke
				(width 0.1)
				(type default)
			)
			(layer "F.SilkS")
		)
		(fp_line
			(start 18.035778 -4.546346)
			(end 16.97609 -3.529838)
			(stroke
				(width 0.1)
				(type default)
			)
			(layer "F.SilkS")
		)
		(fp_line
			(start 18.042636 -3.052572)
			(end 18.03019 -2.982976)
			(stroke
				(width 0.1)
				(type default)
			)
			(layer "F.SilkS")
		)
		(fp_line
			(start 18.042636 -3.052572)
			(end 18.03019 -2.982976)
			(stroke
				(width 0.1)
				(type default)
			)
			(layer "F.SilkS")
		)
		(fp_line
			(start 18.052796 -4.505198)
			(end 16.975582 -3.471672)
			(stroke
				(width 0.1)
				(type default)
			)
			(layer "F.SilkS")
		)
		(fp_line
			(start 18.052796 -4.505198)
			(end 16.975582 -3.471672)
			(stroke
				(width 0.1)
				(type default)
			)
			(layer "F.SilkS")
		)
		(fp_line
			(start 18.054574 -3.121914)
			(end 18.042636 -3.052572)
			(stroke
				(width 0.1)
				(type default)
			)
			(layer "F.SilkS")
		)
		(fp_line
			(start 18.054574 -3.121914)
			(end 18.042636 -3.052572)
			(stroke
				(width 0.1)
				(type default)
			)
			(layer "F.SilkS")
		)
		(fp_line
			(start 18.066766 -3.191002)
			(end 18.054574 -3.121914)
			(stroke
				(width 0.1)
				(type default)
			)
			(layer "F.SilkS")
		)
		(fp_line
			(start 18.066766 -3.191002)
			(end 18.054574 -3.121914)
			(stroke
				(width 0.1)
				(type default)
			)
			(layer "F.SilkS")
		)
		(fp_line
			(start 18.070068 -4.464304)
			(end 16.967708 -3.406648)
			(stroke
				(width 0.1)
				(type default)
			)
			(layer "F.SilkS")
		)
		(fp_line
			(start 18.070068 -4.464304)
			(end 16.967708 -3.406648)
			(stroke
				(width 0.1)
				(type default)
			)
			(layer "F.SilkS")
		)
		(fp_line
			(start 18.079212 -3.260598)
			(end 18.066766 -3.191002)
			(stroke
				(width 0.1)
				(type default)
			)
			(layer "F.SilkS")
		)
		(fp_line
			(start 18.079212 -3.260598)
			(end 18.066766 -3.191002)
			(stroke
				(width 0.1)
				(type default)
			)
			(layer "F.SilkS")
		)
		(fp_line
			(start 18.081752 -4.417314)
			(end 16.959326 -3.340608)
			(stroke
				(width 0.1)
				(type default)
			)
			(layer "F.SilkS")
		)
		(fp_line
			(start 18.081752 -4.417314)
			(end 16.959326 -3.340608)
			(stroke
				(width 0.1)
				(type default)
			)
			(layer "F.SilkS")
		)
		(fp_line
			(start 18.090388 -4.368038)
			(end 16.950436 -3.274568)
			(stroke
				(width 0.1)
				(type default)
			)
			(layer "F.SilkS")
		)
		(fp_line
			(start 18.090388 -4.368038)
			(end 16.950436 -3.274568)
			(stroke
				(width 0.1)
				(type default)
			)
			(layer "F.SilkS")
		)
		(fp_line
			(start 18.099532 -4.318762)
			(end 16.942308 -3.208782)
			(stroke
				(width 0.1)
				(type default)
			)
			(layer "F.SilkS")
		)
		(fp_line
			(start 18.099532 -4.318762)
			(end 16.942308 -3.208782)
			(stroke
				(width 0.1)
				(type default)
			)
			(layer "F.SilkS")
		)
		(fp_line
			(start 18.107914 -4.26974)
			(end 16.930624 -3.139694)
			(stroke
				(width 0.1)
				(type default)
			)
			(layer "F.SilkS")
		)
		(fp_line
			(start 18.107914 -4.26974)
			(end 16.930624 -3.139694)
			(stroke
				(width 0.1)
				(type default)
			)
			(layer "F.SilkS")
		)
		(fp_line
			(start 18.137632 -3.836416)
			(end 16.83258 -2.58445)
			(stroke
				(width 0.1)
				(type default)
			)
			(layer "F.SilkS")
		)
		(fp_line
			(start 18.137632 -3.836416)
			(end 16.83258 -2.58445)
			(stroke
				(width 0.1)
				(type default)
			)
			(layer "F.SilkS")
		)
		(fp_line
			(start 18.736818 -4.109466)
			(end 18.783554 -4.109466)
			(stroke
				(width 0.1)
				(type default)
			)
			(layer "F.SilkS")
		)
		(fp_line
			(start 18.736818 -4.109466)
			(end 18.783554 -4.109466)
			(stroke
				(width 0.1)
				(type default)
			)
			(layer "F.SilkS")
		)
		(fp_line
			(start 18.739612 -4.12496)
			(end 18.736818 -4.109466)
			(stroke
				(width 0.1)
				(type default)
			)
			(layer "F.SilkS")
		)
		(fp_line
			(start 18.739612 -4.12496)
			(end 18.736818 -4.109466)
			(stroke
				(width 0.1)
				(type default)
			)
			(layer "F.SilkS")
		)
		(fp_line
			(start 18.739612 -4.12496)
			(end 20.959318 -6.254496)
			(stroke
				(width 0.1)
				(type default)
			)
			(layer "F.SilkS")
		)
		(fp_line
			(start 18.739612 -4.12496)
			(end 20.959318 -6.254496)
			(stroke
				(width 0.1)
				(type default)
			)
			(layer "F.SilkS")
		)
		(fp_line
			(start 18.75155 -4.194556)
			(end 18.739612 -4.12496)
			(stroke
				(width 0.1)
				(type default)
			)
			(layer "F.SilkS")
		)
		(fp_line
			(start 18.75155 -4.194556)
			(end 18.739612 -4.12496)
			(stroke
				(width 0.1)
				(type default)
			)
			(layer "F.SilkS")
		)
		(fp_line
			(start 18.763996 -4.263898)
			(end 18.75155 -4.194556)
			(stroke
				(width 0.1)
				(type default)
			)
			(layer "F.SilkS")
		)
		(fp_line
			(start 18.763996 -4.263898)
			(end 18.75155 -4.194556)
			(stroke
				(width 0.1)
				(type default)
			)
			(layer "F.SilkS")
		)
		(fp_line
			(start 18.775934 -4.33324)
			(end 18.763996 -4.263898)
			(stroke
				(width 0.1)
				(type default)
			)
			(layer "F.SilkS")
		)
		(fp_line
			(start 18.775934 -4.33324)
			(end 18.763996 -4.263898)
			(stroke
				(width 0.1)
				(type default)
			)
			(layer "F.SilkS")
		)
		(fp_line
			(start 18.775934 -4.33324)
			(end 18.78838 -4.402836)
			(stroke
				(width 0.1)
				(type default)
			)
			(layer "F.SilkS")
		)
		(fp_line
			(start 18.775934 -4.33324)
			(end 18.78838 -4.402836)
			(stroke
				(width 0.1)
				(type default)
			)
			(layer "F.SilkS")
		)
		(fp_line
			(start 18.783554 -4.109466)
			(end 18.843498 -4.109466)
			(stroke
				(width 0.1)
				(type default)
			)
			(layer "F.SilkS")
		)
		(fp_line
			(start 18.783554 -4.109466)
			(end 18.843498 -4.109466)
			(stroke
				(width 0.1)
				(type default)
			)
			(layer "F.SilkS")
		)
		(fp_line
			(start 18.783554 -4.109466)
			(end 20.947126 -6.1849)
			(stroke
				(width 0.1)
				(type default)
			)
			(layer "F.SilkS")
		)
		(fp_line
			(start 18.783554 -4.109466)
			(end 20.947126 -6.1849)
			(stroke
				(width 0.1)
				(type default)
			)
			(layer "F.SilkS")
		)
		(fp_line
			(start 18.78838 -4.402836)
			(end 18.800572 -4.472178)
			(stroke
				(width 0.1)
				(type default)
			)
			(layer "F.SilkS")
		)
		(fp_line
			(start 18.78838 -4.402836)
			(end 18.800572 -4.472178)
			(stroke
				(width 0.1)
				(type default)
			)
			(layer "F.SilkS")
		)
		(fp_line
			(start 18.78838 -4.402836)
			(end 19.58975 -5.171694)
			(stroke
				(width 0.1)
				(type default)
			)
			(layer "F.SilkS")
		)
		(fp_line
			(start 18.78838 -4.402836)
			(end 19.58975 -5.171694)
			(stroke
				(width 0.1)
				(type default)
			)
			(layer "F.SilkS")
		)
		(fp_line
			(start 18.800572 -4.472178)
			(end 18.81251 -4.54152)
			(stroke
				(width 0.1)
				(type default)
			)
			(layer "F.SilkS")
		)
		(fp_line
			(start 18.800572 -4.472178)
			(end 18.81251 -4.54152)
			(stroke
				(width 0.1)
				(type default)
			)
			(layer "F.SilkS")
		)
		(fp_line
			(start 18.800572 -4.472178)
			(end 19.529806 -5.171694)
			(stroke
				(width 0.1)
				(type default)
			)
			(layer "F.SilkS")
		)
		(fp_line
			(start 18.800572 -4.472178)
			(end 19.529806 -5.171694)
			(stroke
				(width 0.1)
				(type default)
			)
			(layer "F.SilkS")
		)
		(fp_line
			(start 18.81251 -4.54152)
			(end 18.824956 -4.610862)
			(stroke
				(width 0.1)
				(type default)
			)
			(layer "F.SilkS")
		)
		(fp_line
			(start 18.81251 -4.54152)
			(end 18.824956 -4.610862)
			(stroke
				(width 0.1)
				(type default)
			)
			(layer "F.SilkS")
		)
		(fp_line
			(start 18.81251 -4.54152)
			(end 19.469608 -5.171694)
			(stroke
				(width 0.1)
				(type default)
			)
			(layer "F.SilkS")
		)
		(fp_line
			(start 18.81251 -4.54152)
			(end 19.469608 -5.171694)
			(stroke
				(width 0.1)
				(type default)
			)
			(layer "F.SilkS")
		)
		(fp_line
			(start 18.824956 -4.610862)
			(end 18.836894 -4.680458)
			(stroke
				(width 0.1)
				(type default)
			)
			(layer "F.SilkS")
		)
		(fp_line
			(start 18.824956 -4.610862)
			(end 18.836894 -4.680458)
			(stroke
				(width 0.1)
				(type default)
			)
			(layer "F.SilkS")
		)
		(fp_line
			(start 18.824956 -4.610862)
			(end 19.409664 -5.171694)
			(stroke
				(width 0.1)
				(type default)
			)
			(layer "F.SilkS")
		)
		(fp_line
			(start 18.824956 -4.610862)
			(end 19.409664 -5.171694)
			(stroke
				(width 0.1)
				(type default)
			)
			(layer "F.SilkS")
		)
		(fp_line
			(start 18.836894 -4.680458)
			(end 18.84934 -4.7498)
			(stroke
				(width 0.1)
				(type default)
			)
			(layer "F.SilkS")
		)
		(fp_line
			(start 18.836894 -4.680458)
			(end 18.84934 -4.7498)
			(stroke
				(width 0.1)
				(type default)
			)
			(layer "F.SilkS")
		)
		(fp_line
			(start 18.836894 -4.680458)
			(end 19.349212 -5.171694)
			(stroke
				(width 0.1)
				(type default)
			)
			(layer "F.SilkS")
		)
		(fp_line
			(start 18.836894 -4.680458)
			(end 19.349212 -5.171694)
			(stroke
				(width 0.1)
				(type default)
			)
			(layer "F.SilkS")
		)
		(fp_line
			(start 18.843498 -4.109466)
			(end 18.90395 -4.109466)
			(stroke
				(width 0.1)
				(type default)
			)
			(layer "F.SilkS")
		)
		(fp_line
			(start 18.843498 -4.109466)
			(end 18.90395 -4.109466)
			(stroke
				(width 0.1)
				(type default)
			)
			(layer "F.SilkS")
		)
		(fp_line
			(start 18.843498 -4.109466)
			(end 20.93468 -6.115558)
			(stroke
				(width 0.1)
				(type default)
			)
			(layer "F.SilkS")
		)
		(fp_line
			(start 18.843498 -4.109466)
			(end 20.93468 -6.115558)
			(stroke
				(width 0.1)
				(type default)
			)
			(layer "F.SilkS")
		)
		(fp_line
			(start 18.84934 -4.7498)
			(end 18.861532 -4.819142)
			(stroke
				(width 0.1)
				(type default)
			)
			(layer "F.SilkS")
		)
		(fp_line
			(start 18.84934 -4.7498)
			(end 18.861532 -4.819142)
			(stroke
				(width 0.1)
				(type default)
			)
			(layer "F.SilkS")
		)
		(fp_line
			(start 18.84934 -4.7498)
			(end 19.289014 -5.171694)
			(stroke
				(width 0.1)
				(type default)
			)
			(layer "F.SilkS")
		)
		(fp_line
			(start 18.84934 -4.7498)
			(end 19.289014 -5.171694)
			(stroke
				(width 0.1)
				(type default)
			)
			(layer "F.SilkS")
		)
		(fp_line
			(start 18.861532 -4.819142)
			(end 18.873978 -4.888484)
			(stroke
				(width 0.1)
				(type default)
			)
			(layer "F.SilkS")
		)
		(fp_line
			(start 18.861532 -4.819142)
			(end 18.873978 -4.888484)
			(stroke
				(width 0.1)
				(type default)
			)
			(layer "F.SilkS")
		)
		(fp_line
			(start 18.861532 -4.819142)
			(end 19.22907 -5.171694)
			(stroke
				(width 0.1)
				(type default)
			)
			(layer "F.SilkS")
		)
		(fp_line
			(start 18.861532 -4.819142)
			(end 19.22907 -5.171694)
			(stroke
				(width 0.1)
				(type default)
			)
			(layer "F.SilkS")
		)
		(fp_line
			(start 18.873978 -4.888484)
			(end 19.168872 -5.171694)
			(stroke
				(width 0.1)
				(type default)
			)
			(layer "F.SilkS")
		)
		(fp_line
			(start 18.873978 -4.888484)
			(end 19.168872 -5.171694)
			(stroke
				(width 0.1)
				(type default)
			)
			(layer "F.SilkS")
		)
		(fp_line
			(start 18.885916 -4.95808)
			(end 18.873978 -4.888484)
			(stroke
				(width 0.1)
				(type default)
			)
			(layer "F.SilkS")
		)
		(fp_line
			(start 18.885916 -4.95808)
			(end 18.873978 -4.888484)
			(stroke
				(width 0.1)
				(type default)
			)
			(layer "F.SilkS")
		)
		(fp_line
			(start 18.898108 -5.027422)
			(end 18.885916 -4.95808)
			(stroke
				(width 0.1)
				(type default)
			)
			(layer "F.SilkS")
		)
		(fp_line
			(start 18.898108 -5.027422)
			(end 18.885916 -4.95808)
			(stroke
				(width 0.1)
				(type default)
			)
			(layer "F.SilkS")
		)
		(fp_line
			(start 18.898108 -5.027422)
			(end 18.9103 -5.097018)
			(stroke
				(width 0.1)
				(type default)
			)
			(layer "F.SilkS")
		)
		(fp_line
			(start 18.898108 -5.027422)
			(end 18.9103 -5.097018)
			(stroke
				(width 0.1)
				(type default)
			)
			(layer "F.SilkS")
		)
		(fp_line
			(start 18.898108 -5.027422)
			(end 19.048476 -5.171694)
			(stroke
				(width 0.1)
				(type default)
			)
			(layer "F.SilkS")
		)
		(fp_line
			(start 18.898108 -5.027422)
			(end 19.048476 -5.171694)
			(stroke
				(width 0.1)
				(type default)
			)
			(layer "F.SilkS")
		)
		(fp_line
			(start 18.90395 -4.109466)
			(end 18.964148 -4.109466)
			(stroke
				(width 0.1)
				(type default)
			)
			(layer "F.SilkS")
		)
		(fp_line
			(start 18.90395 -4.109466)
			(end 18.964148 -4.109466)
			(stroke
				(width 0.1)
				(type default)
			)
			(layer "F.SilkS")
		)
		(fp_line
			(start 18.90395 -4.109466)
			(end 20.922742 -6.04647)
			(stroke
				(width 0.1)
				(type default)
			)
			(layer "F.SilkS")
		)
		(fp_line
			(start 18.90395 -4.109466)
			(end 20.922742 -6.04647)
			(stroke
				(width 0.1)
				(type default)
			)
			(layer "F.SilkS")
		)
		(fp_line
			(start 18.9103 -5.097018)
			(end 18.922492 -5.166106)
			(stroke
				(width 0.1)
				(type default)
			)
			(layer "F.SilkS")
		)
		(fp_line
			(start 18.9103 -5.097018)
			(end 18.922492 -5.166106)
			(stroke
				(width 0.1)
				(type default)
			)
			(layer "F.SilkS")
		)
		(fp_line
			(start 18.9103 -5.097018)
			(end 18.988278 -5.171694)
			(stroke
				(width 0.1)
				(type default)
			)
			(layer "F.SilkS")
		)
		(fp_line
			(start 18.9103 -5.097018)
			(end 18.988278 -5.171694)
			(stroke
				(width 0.1)
				(type default)
			)
			(layer "F.SilkS")
		)
		(fp_line
			(start 18.922492 -5.166106)
			(end 18.923508 -5.171694)
			(stroke
				(width 0.1)
				(type default)
			)
			(layer "F.SilkS")
		)
		(fp_line
			(start 18.922492 -5.166106)
			(end 18.923508 -5.171694)
			(stroke
				(width 0.1)
				(type default)
			)
			(layer "F.SilkS")
		)
		(fp_line
			(start 18.922492 -5.166106)
			(end 18.928334 -5.171694)
			(stroke
				(width 0.1)
				(type default)
			)
			(layer "F.SilkS")
		)
		(fp_line
			(start 18.922492 -5.166106)
			(end 18.928334 -5.171694)
			(stroke
				(width 0.1)
				(type default)
			)
			(layer "F.SilkS")
		)
		(fp_line
			(start 18.923508 -5.171694)
			(end 18.928334 -5.171694)
			(stroke
				(width 0.1)
				(type default)
			)
			(layer "F.SilkS")
		)
		(fp_line
			(start 18.923508 -5.171694)
			(end 18.928334 -5.171694)
			(stroke
				(width 0.1)
				(type default)
			)
			(layer "F.SilkS")
		)
		(fp_line
			(start 18.964148 -4.109466)
			(end 19.024092 -4.109466)
			(stroke
				(width 0.1)
				(type default)
			)
			(layer "F.SilkS")
		)
		(fp_line
			(start 18.964148 -4.109466)
			(end 19.024092 -4.109466)
			(stroke
				(width 0.1)
				(type default)
			)
			(layer "F.SilkS")
		)
		(fp_line
			(start 18.964148 -4.109466)
			(end 20.91055 -5.976874)
			(stroke
				(width 0.1)
				(type default)
			)
			(layer "F.SilkS")
		)
		(fp_line
			(start 18.964148 -4.109466)
			(end 20.91055 -5.976874)
			(stroke
				(width 0.1)
				(type default)
			)
			(layer "F.SilkS")
		)
		(fp_line
			(start 18.988278 -5.171694)
			(end 18.928334 -5.171694)
			(stroke
				(width 0.1)
				(type default)
			)
			(layer "F.SilkS")
		)
		(fp_line
			(start 18.988278 -5.171694)
			(end 18.928334 -5.171694)
			(stroke
				(width 0.1)
				(type default)
			)
			(layer "F.SilkS")
		)
		(fp_line
			(start 19.024092 -4.109466)
			(end 19.08429 -4.109466)
			(stroke
				(width 0.1)
				(type default)
			)
			(layer "F.SilkS")
		)
		(fp_line
			(start 19.024092 -4.109466)
			(end 19.08429 -4.109466)
			(stroke
				(width 0.1)
				(type default)
			)
			(layer "F.SilkS")
		)
		(fp_line
			(start 19.024092 -4.109466)
			(end 20.898104 -5.907278)
			(stroke
				(width 0.1)
				(type default)
			)
			(layer "F.SilkS")
		)
		(fp_line
			(start 19.024092 -4.109466)
			(end 20.898104 -5.907278)
			(stroke
				(width 0.1)
				(type default)
			)
			(layer "F.SilkS")
		)
		(fp_line
			(start 19.048476 -5.171694)
			(end 18.988278 -5.171694)
			(stroke
				(width 0.1)
				(type default)
			)
			(layer "F.SilkS")
		)
		(fp_line
			(start 19.048476 -5.171694)
			(end 18.988278 -5.171694)
			(stroke
				(width 0.1)
				(type default)
			)
			(layer "F.SilkS")
		)
		(fp_line
			(start 19.048476 -5.171694)
			(end 19.10842 -5.171694)
			(stroke
				(width 0.1)
				(type default)
			)
			(layer "F.SilkS")
		)
		(fp_line
			(start 19.048476 -5.171694)
			(end 19.10842 -5.171694)
			(stroke
				(width 0.1)
				(type default)
			)
			(layer "F.SilkS")
		)
		(fp_line
			(start 19.074638 -1.79197)
			(end 20.399248 -3.062478)
			(stroke
				(width 0.1)
				(type default)
			)
			(layer "F.SilkS")
		)
		(fp_line
			(start 19.074638 -1.79197)
			(end 20.399248 -3.062478)
			(stroke
				(width 0.1)
				(type default)
			)
			(layer "F.SilkS")
		)
		(fp_line
			(start 19.077178 -1.851914)
			(end 20.41144 -3.13182)
			(stroke
				(width 0.1)
				(type default)
			)
			(layer "F.SilkS")
		)
		(fp_line
			(start 19.077178 -1.851914)
			(end 20.41144 -3.13182)
			(stroke
				(width 0.1)
				(type default)
			)
			(layer "F.SilkS")
		)
		(fp_line
			(start 19.078448 -1.737868)
			(end 20.38731 -2.99339)
			(stroke
				(width 0.1)
				(type default)
			)
			(layer "F.SilkS")
		)
		(fp_line
			(start 19.078448 -1.737868)
			(end 20.38731 -2.99339)
			(stroke
				(width 0.1)
				(type default)
			)
			(layer "F.SilkS")
		)
		(fp_line
			(start 19.082258 -1.683512)
			(end 20.374864 -2.923794)
			(stroke
				(width 0.1)
				(type default)
			)
			(layer "F.SilkS")
		)
		(fp_line
			(start 19.082258 -1.683512)
			(end 20.374864 -2.923794)
			(stroke
				(width 0.1)
				(type default)
			)
			(layer "F.SilkS")
		)
		(fp_line
			(start 19.083274 -1.915668)
			(end 20.423886 -3.201416)
			(stroke
				(width 0.1)
				(type default)
			)
			(layer "F.SilkS")
		)
		(fp_line
			(start 19.083274 -1.915668)
			(end 20.423886 -3.201416)
			(stroke
				(width 0.1)
				(type default)
			)
			(layer "F.SilkS")
		)
		(fp_line
			(start 19.08429 -4.109466)
			(end 19.144234 -4.109466)
			(stroke
				(width 0.1)
				(type default)
			)
			(layer "F.SilkS")
		)
		(fp_line
			(start 19.08429 -4.109466)
			(end 19.144234 -4.109466)
			(stroke
				(width 0.1)
				(type default)
			)
			(layer "F.SilkS")
		)
		(fp_line
			(start 19.08429 -4.109466)
			(end 20.886166 -5.837936)
			(stroke
				(width 0.1)
				(type default)
			)
			(layer "F.SilkS")
		)
		(fp_line
			(start 19.08429 -4.109466)
			(end 20.886166 -5.837936)
			(stroke
				(width 0.1)
				(type default)
			)
			(layer "F.SilkS")
		)
		(fp_line
			(start 19.086068 -1.62941)
			(end 20.362926 -2.854198)
			(stroke
				(width 0.1)
				(type default)
			)
			(layer "F.SilkS")
		)
		(fp_line
			(start 19.086068 -1.62941)
			(end 20.362926 -2.854198)
			(stroke
				(width 0.1)
				(type default)
			)
			(layer "F.SilkS")
		)
		(fp_line
			(start 19.089624 -1.575308)
			(end 20.35048 -2.784856)
			(stroke
				(width 0.1)
				(type default)
			)
			(layer "F.SilkS")
		)
		(fp_line
			(start 19.089624 -1.575308)
			(end 20.35048 -2.784856)
			(stroke
				(width 0.1)
				(type default)
			)
			(layer "F.SilkS")
		)
		(fp_line
			(start 19.089878 -1.979676)
			(end 20.435824 -3.270758)
			(stroke
				(width 0.1)
				(type default)
			)
			(layer "F.SilkS")
		)
		(fp_line
			(start 19.089878 -1.979676)
			(end 20.435824 -3.270758)
			(stroke
				(width 0.1)
				(type default)
			)
			(layer "F.SilkS")
		)
		(fp_line
			(start 19.095974 -2.043176)
			(end 20.44827 -3.340354)
			(stroke
				(width 0.1)
				(type default)
			)
			(layer "F.SilkS")
		)
		(fp_line
			(start 19.095974 -2.043176)
			(end 20.44827 -3.340354)
			(stroke
				(width 0.1)
				(type default)
			)
			(layer "F.SilkS")
		)
		(fp_line
			(start 19.100292 -1.528064)
			(end 20.338288 -2.715768)
			(stroke
				(width 0.1)
				(type default)
			)
			(layer "F.SilkS")
		)
		(fp_line
			(start 19.100292 -1.528064)
			(end 20.338288 -2.715768)
			(stroke
				(width 0.1)
				(type default)
			)
			(layer "F.SilkS")
		)
		(fp_line
			(start 19.10461 -2.108962)
			(end 20.460462 -3.409442)
			(stroke
				(width 0.1)
				(type default)
			)
			(layer "F.SilkS")
		)
		(fp_line
			(start 19.10461 -2.108962)
			(end 20.460462 -3.409442)
			(stroke
				(width 0.1)
				(type default)
			)
			(layer "F.SilkS")
		)
		(fp_line
			(start 19.10842 -5.171694)
			(end 18.885916 -4.95808)
			(stroke
				(width 0.1)
				(type default)
			)
			(layer "F.SilkS")
		)
		(fp_line
			(start 19.10842 -5.171694)
			(end 18.885916 -4.95808)
			(stroke
				(width 0.1)
				(type default)
			)
			(layer "F.SilkS")
		)
		(fp_line
			(start 19.10842 -5.171694)
			(end 19.168872 -5.171694)
			(stroke
				(width 0.1)
				(type default)
			)
			(layer "F.SilkS")
		)
		(fp_line
			(start 19.10842 -5.171694)
			(end 19.168872 -5.171694)
			(stroke
				(width 0.1)
				(type default)
			)
			(layer "F.SilkS")
		)
		(fp_line
			(start 19.112738 -1.48209)
			(end 20.32635 -2.646172)
			(stroke
				(width 0.1)
				(type default)
			)
			(layer "F.SilkS")
		)
		(fp_line
			(start 19.112738 -1.48209)
			(end 20.32635 -2.646172)
			(stroke
				(width 0.1)
				(type default)
			)
			(layer "F.SilkS")
		)
		(fp_line
			(start 19.116802 -2.178304)
			(end 19.10461 -2.108962)
			(stroke
				(width 0.1)
				(type default)
			)
			(layer "F.SilkS")
		)
		(fp_line
			(start 19.116802 -2.178304)
			(end 19.10461 -2.108962)
			(stroke
				(width 0.1)
				(type default)
			)
			(layer "F.SilkS")
		)
		(fp_line
			(start 19.116802 -2.178304)
			(end 20.4724 -3.479038)
			(stroke
				(width 0.1)
				(type default)
			)
			(layer "F.SilkS")
		)
		(fp_line
			(start 19.116802 -2.178304)
			(end 20.4724 -3.479038)
			(stroke
				(width 0.1)
				(type default)
			)
			(layer "F.SilkS")
		)
		(fp_line
			(start 19.12493 -1.436116)
			(end 20.313904 -2.576576)
			(stroke
				(width 0.1)
				(type default)
			)
			(layer "F.SilkS")
		)
		(fp_line
			(start 19.12493 -1.436116)
			(end 20.313904 -2.576576)
			(stroke
				(width 0.1)
				(type default)
			)
			(layer "F.SilkS")
		)
		(fp_line
			(start 19.12874 -2.2479)
			(end 19.116802 -2.178304)
			(stroke
				(width 0.1)
				(type default)
			)
			(layer "F.SilkS")
		)
		(fp_line
			(start 19.12874 -2.2479)
			(end 19.116802 -2.178304)
			(stroke
				(width 0.1)
				(type default)
			)
			(layer "F.SilkS")
		)
		(fp_line
			(start 19.12874 -2.2479)
			(end 19.141186 -2.317242)
			(stroke
				(width 0.1)
				(type default)
			)
			(layer "F.SilkS")
		)
		(fp_line
			(start 19.12874 -2.2479)
			(end 19.141186 -2.317242)
			(stroke
				(width 0.1)
				(type default)
			)
			(layer "F.SilkS")
		)
		(fp_line
			(start 19.12874 -2.2479)
			(end 20.484846 -3.548634)
			(stroke
				(width 0.1)
				(type default)
			)
			(layer "F.SilkS")
		)
		(fp_line
			(start 19.12874 -2.2479)
			(end 20.484846 -3.548634)
			(stroke
				(width 0.1)
				(type default)
			)
			(layer "F.SilkS")
		)
		(fp_line
			(start 19.137376 -1.390396)
			(end 20.301966 -2.507234)
			(stroke
				(width 0.1)
				(type default)
			)
			(layer "F.SilkS")
		)
		(fp_line
			(start 19.137376 -1.390396)
			(end 20.301966 -2.507234)
			(stroke
				(width 0.1)
				(type default)
			)
			(layer "F.SilkS")
		)
		(fp_line
			(start 19.144234 -4.109466)
			(end 19.204686 -4.109466)
			(stroke
				(width 0.1)
				(type default)
			)
			(layer "F.SilkS")
		)
		(fp_line
			(start 19.144234 -4.109466)
			(end 19.204686 -4.109466)
			(stroke
				(width 0.1)
				(type default)
			)
			(layer "F.SilkS")
		)
		(fp_line
			(start 19.144234 -4.109466)
			(end 20.874228 -5.768594)
			(stroke
				(width 0.1)
				(type default)
			)
			(layer "F.SilkS")
		)
		(fp_line
			(start 19.144234 -4.109466)
			(end 20.874228 -5.768594)
			(stroke
				(width 0.1)
				(type default)
			)
			(layer "F.SilkS")
		)
		(fp_line
			(start 19.149822 -1.344676)
			(end 20.28952 -2.437892)
			(stroke
				(width 0.1)
				(type default)
			)
			(layer "F.SilkS")
		)
		(fp_line
			(start 19.149822 -1.344676)
			(end 20.28952 -2.437892)
			(stroke
				(width 0.1)
				(type default)
			)
			(layer "F.SilkS")
		)
		(fp_line
			(start 19.153378 -2.386584)
			(end 19.141186 -2.317242)
			(stroke
				(width 0.1)
				(type default)
			)
			(layer "F.SilkS")
		)
		(fp_line
			(start 19.153378 -2.386584)
			(end 19.141186 -2.317242)
			(stroke
				(width 0.1)
				(type default)
			)
			(layer "F.SilkS")
		)
		(fp_line
			(start 19.153378 -2.386584)
			(end 20.50923 -3.687064)
			(stroke
				(width 0.1)
				(type default)
			)
			(layer "F.SilkS")
		)
		(fp_line
			(start 19.153378 -2.386584)
			(end 20.50923 -3.687064)
			(stroke
				(width 0.1)
				(type default)
			)
			(layer "F.SilkS")
		)
		(fp_line
			(start 19.165316 -2.455926)
			(end 19.153378 -2.386584)
			(stroke
				(width 0.1)
				(type default)
			)
			(layer "F.SilkS")
		)
		(fp_line
			(start 19.165316 -2.455926)
			(end 19.153378 -2.386584)
			(stroke
				(width 0.1)
				(type default)
			)
			(layer "F.SilkS")
		)
		(fp_line
			(start 19.165316 -2.455926)
			(end 20.521422 -3.75666)
			(stroke
				(width 0.1)
				(type default)
			)
			(layer "F.SilkS")
		)
		(fp_line
			(start 19.165316 -2.455926)
			(end 20.521422 -3.75666)
			(stroke
				(width 0.1)
				(type default)
			)
			(layer "F.SilkS")
		)
		(fp_line
			(start 19.170142 -1.306322)
			(end 20.278344 -2.369312)
			(stroke
				(width 0.1)
				(type default)
			)
			(layer "F.SilkS")
		)
		(fp_line
			(start 19.170142 -1.306322)
			(end 20.278344 -2.369312)
			(stroke
				(width 0.1)
				(type default)
			)
			(layer "F.SilkS")
		)
		(fp_line
			(start 19.177762 -2.525522)
			(end 19.165316 -2.455926)
			(stroke
				(width 0.1)
				(type default)
			)
			(layer "F.SilkS")
		)
		(fp_line
			(start 19.177762 -2.525522)
			(end 19.165316 -2.455926)
			(stroke
				(width 0.1)
				(type default)
			)
			(layer "F.SilkS")
		)
		(fp_line
			(start 19.177762 -2.525522)
			(end 20.533614 -3.826256)
			(stroke
				(width 0.1)
				(type default)
			)
			(layer "F.SilkS")
		)
		(fp_line
			(start 19.177762 -2.525522)
			(end 20.533614 -3.826256)
			(stroke
				(width 0.1)
				(type default)
			)
			(layer "F.SilkS")
		)
		(fp_line
			(start 19.1897 -2.594864)
			(end 19.177762 -2.525522)
			(stroke
				(width 0.1)
				(type default)
			)
			(layer "F.SilkS")
		)
		(fp_line
			(start 19.1897 -2.594864)
			(end 19.177762 -2.525522)
			(stroke
				(width 0.1)
				(type default)
			)
			(layer "F.SilkS")
		)
		(fp_line
			(start 19.1897 -2.594864)
			(end 20.545806 -3.895344)
			(stroke
				(width 0.1)
				(type default)
			)
			(layer "F.SilkS")
		)
		(fp_line
			(start 19.1897 -2.594864)
			(end 20.545806 -3.895344)
			(stroke
				(width 0.1)
				(type default)
			)
			(layer "F.SilkS")
		)
		(fp_line
			(start 19.190462 -1.267968)
			(end 20.270216 -2.303526)
			(stroke
				(width 0.1)
				(type default)
			)
			(layer "F.SilkS")
		)
		(fp_line
			(start 19.190462 -1.267968)
			(end 20.270216 -2.303526)
			(stroke
				(width 0.1)
				(type default)
			)
			(layer "F.SilkS")
		)
		(fp_line
			(start 19.201892 -2.663952)
			(end 19.1897 -2.594864)
			(stroke
				(width 0.1)
				(type default)
			)
			(layer "F.SilkS")
		)
		(fp_line
			(start 19.201892 -2.663952)
			(end 19.1897 -2.594864)
			(stroke
				(width 0.1)
				(type default)
			)
			(layer "F.SilkS")
		)
		(fp_line
			(start 19.201892 -2.663952)
			(end 20.557744 -3.96494)
			(stroke
				(width 0.1)
				(type default)
			)
			(layer "F.SilkS")
		)
		(fp_line
			(start 19.201892 -2.663952)
			(end 20.557744 -3.96494)
			(stroke
				(width 0.1)
				(type default)
			)
			(layer "F.SilkS")
		)
		(fp_line
			(start 19.204686 -4.109466)
			(end 19.264884 -4.109466)
			(stroke
				(width 0.1)
				(type default)
			)
			(layer "F.SilkS")
		)
		(fp_line
			(start 19.204686 -4.109466)
			(end 19.264884 -4.109466)
			(stroke
				(width 0.1)
				(type default)
			)
			(layer "F.SilkS")
		)
		(fp_line
			(start 19.204686 -4.109466)
			(end 20.861782 -5.699252)
			(stroke
				(width 0.1)
				(type default)
			)
			(layer "F.SilkS")
		)
		(fp_line
			(start 19.204686 -4.109466)
			(end 20.861782 -5.699252)
			(stroke
				(width 0.1)
				(type default)
			)
			(layer "F.SilkS")
		)
		(fp_line
			(start 19.210782 -1.229868)
			(end 20.26285 -2.239264)
			(stroke
				(width 0.1)
				(type default)
			)
			(layer "F.SilkS")
		)
		(fp_line
			(start 19.210782 -1.229868)
			(end 20.26285 -2.239264)
			(stroke
				(width 0.1)
				(type default)
			)
			(layer "F.SilkS")
		)
		(fp_line
			(start 19.21383 -2.733548)
			(end 19.201892 -2.663952)
			(stroke
				(width 0.1)
				(type default)
			)
			(layer "F.SilkS")
		)
		(fp_line
			(start 19.21383 -2.733548)
			(end 19.201892 -2.663952)
			(stroke
				(width 0.1)
				(type default)
			)
			(layer "F.SilkS")
		)
		(fp_line
			(start 19.21383 -2.733548)
			(end 20.57019 -4.034282)
			(stroke
				(width 0.1)
				(type default)
			)
			(layer "F.SilkS")
		)
		(fp_line
			(start 19.21383 -2.733548)
			(end 20.57019 -4.034282)
			(stroke
				(width 0.1)
				(type default)
			)
			(layer "F.SilkS")
		)
		(fp_line
			(start 19.226276 -2.80289)
			(end 19.21383 -2.733548)
			(stroke
				(width 0.1)
				(type default)
			)
			(layer "F.SilkS")
		)
		(fp_line
			(start 19.226276 -2.80289)
			(end 19.21383 -2.733548)
			(stroke
				(width 0.1)
				(type default)
			)
			(layer "F.SilkS")
		)
		(fp_line
			(start 19.226276 -2.80289)
			(end 20.582382 -4.103878)
			(stroke
				(width 0.1)
				(type default)
			)
			(layer "F.SilkS")
		)
		(fp_line
			(start 19.226276 -2.80289)
			(end 20.582382 -4.103878)
			(stroke
				(width 0.1)
				(type default)
			)
			(layer "F.SilkS")
		)
		(fp_line
			(start 19.22907 -5.171694)
			(end 19.168872 -5.171694)
			(stroke
				(width 0.1)
				(type default)
			)
			(layer "F.SilkS")
		)
		(fp_line
			(start 19.22907 -5.171694)
			(end 19.168872 -5.171694)
			(stroke
				(width 0.1)
				(type default)
			)
			(layer "F.SilkS")
		)
		(fp_line
			(start 19.230848 -1.191514)
			(end 20.263358 -2.181606)
			(stroke
				(width 0.1)
				(type default)
			)
			(layer "F.SilkS")
		)
		(fp_line
			(start 19.230848 -1.191514)
			(end 20.263358 -2.181606)
			(stroke
				(width 0.1)
				(type default)
			)
			(layer "F.SilkS")
		)
		(fp_line
			(start 19.238468 -2.872232)
			(end 19.226276 -2.80289)
			(stroke
				(width 0.1)
				(type default)
			)
			(layer "F.SilkS")
		)
		(fp_line
			(start 19.238468 -2.872232)
			(end 19.226276 -2.80289)
			(stroke
				(width 0.1)
				(type default)
			)
			(layer "F.SilkS")
		)
		(fp_line
			(start 19.238468 -2.872232)
			(end 21.635466 -5.171694)
			(stroke
				(width 0.1)
				(type default)
			)
			(layer "F.SilkS")
		)
		(fp_line
			(start 19.238468 -2.872232)
			(end 21.635466 -5.171694)
			(stroke
				(width 0.1)
				(type default)
			)
			(layer "F.SilkS")
		)
		(fp_line
			(start 19.250406 -2.941574)
			(end 19.238468 -2.872232)
			(stroke
				(width 0.1)
				(type default)
			)
			(layer "F.SilkS")
		)
		(fp_line
			(start 19.250406 -2.941574)
			(end 19.238468 -2.872232)
			(stroke
				(width 0.1)
				(type default)
			)
			(layer "F.SilkS")
		)
		(fp_line
			(start 19.25193 -1.153922)
			(end 20.265136 -2.125726)
			(stroke
				(width 0.1)
				(type default)
			)
			(layer "F.SilkS")
		)
		(fp_line
			(start 19.25193 -1.153922)
			(end 20.265136 -2.125726)
			(stroke
				(width 0.1)
				(type default)
			)
			(layer "F.SilkS")
		)
		(fp_line
			(start 19.262852 -3.01117)
			(end 19.250406 -2.941574)
			(stroke
				(width 0.1)
				(type default)
			)
			(layer "F.SilkS")
		)
		(fp_line
			(start 19.262852 -3.01117)
			(end 19.250406 -2.941574)
			(stroke
				(width 0.1)
				(type default)
			)
			(layer "F.SilkS")
		)
		(fp_line
			(start 19.264884 -4.109466)
			(end 19.324828 -4.109466)
			(stroke
				(width 0.1)
				(type default)
			)
			(layer "F.SilkS")
		)
		(fp_line
			(start 19.264884 -4.109466)
			(end 19.324828 -4.109466)
			(stroke
				(width 0.1)
				(type default)
			)
			(layer "F.SilkS")
		)
		(fp_line
			(start 19.264884 -4.109466)
			(end 20.84959 -5.629656)
			(stroke
				(width 0.1)
				(type default)
			)
			(layer "F.SilkS")
		)
		(fp_line
			(start 19.264884 -4.109466)
			(end 20.84959 -5.629656)
			(stroke
				(width 0.1)
				(type default)
			)
			(layer "F.SilkS")
		)
		(fp_line
			(start 19.27479 -3.080512)
			(end 19.262852 -3.01117)
			(stroke
				(width 0.1)
				(type default)
			)
			(layer "F.SilkS")
		)
		(fp_line
			(start 19.27479 -3.080512)
			(end 19.262852 -3.01117)
			(stroke
				(width 0.1)
				(type default)
			)
			(layer "F.SilkS")
		)
		(fp_line
			(start 19.279616 -1.122934)
			(end 20.274534 -2.077212)
			(stroke
				(width 0.1)
				(type default)
			)
			(layer "F.SilkS")
		)
		(fp_line
			(start 19.279616 -1.122934)
			(end 20.274534 -2.077212)
			(stroke
				(width 0.1)
				(type default)
			)
			(layer "F.SilkS")
		)
		(fp_line
			(start 19.286982 -3.149854)
			(end 19.27479 -3.080512)
			(stroke
				(width 0.1)
				(type default)
			)
			(layer "F.SilkS")
		)
		(fp_line
			(start 19.286982 -3.149854)
			(end 19.27479 -3.080512)
			(stroke
				(width 0.1)
				(type default)
			)
			(layer "F.SilkS")
		)
		(fp_line
			(start 19.289014 -5.171694)
			(end 19.22907 -5.171694)
			(stroke
				(width 0.1)
				(type default)
			)
			(layer "F.SilkS")
		)
		(fp_line
			(start 19.289014 -5.171694)
			(end 19.22907 -5.171694)
			(stroke
				(width 0.1)
				(type default)
			)
			(layer "F.SilkS")
		)
		(fp_line
			(start 19.299428 -3.218942)
			(end 19.286982 -3.149854)
			(stroke
				(width 0.1)
				(type default)
			)
			(layer "F.SilkS")
		)
		(fp_line
			(start 19.299428 -3.218942)
			(end 19.286982 -3.149854)
			(stroke
				(width 0.1)
				(type default)
			)
			(layer "F.SilkS")
		)
		(fp_line
			(start 19.307556 -1.091946)
			(end 20.287488 -2.031746)
			(stroke
				(width 0.1)
				(type default)
			)
			(layer "F.SilkS")
		)
		(fp_line
			(start 19.307556 -1.091946)
			(end 20.287488 -2.031746)
			(stroke
				(width 0.1)
				(type default)
			)
			(layer "F.SilkS")
		)
		(fp_line
			(start 19.311366 -3.288538)
			(end 19.299428 -3.218942)
			(stroke
				(width 0.1)
				(type default)
			)
			(layer "F.SilkS")
		)
		(fp_line
			(start 19.311366 -3.288538)
			(end 19.299428 -3.218942)
			(stroke
				(width 0.1)
				(type default)
			)
			(layer "F.SilkS")
		)
		(fp_line
			(start 19.323558 -3.358134)
			(end 19.311366 -3.288538)
			(stroke
				(width 0.1)
				(type default)
			)
			(layer "F.SilkS")
		)
		(fp_line
			(start 19.323558 -3.358134)
			(end 19.311366 -3.288538)
			(stroke
				(width 0.1)
				(type default)
			)
			(layer "F.SilkS")
		)
		(fp_line
			(start 19.324828 -4.109466)
			(end 19.385026 -4.109466)
			(stroke
				(width 0.1)
				(type default)
			)
			(layer "F.SilkS")
		)
		(fp_line
			(start 19.324828 -4.109466)
			(end 19.385026 -4.109466)
			(stroke
				(width 0.1)
				(type default)
			)
			(layer "F.SilkS")
		)
		(fp_line
			(start 19.324828 -4.109466)
			(end 20.837144 -5.560314)
			(stroke
				(width 0.1)
				(type default)
			)
			(layer "F.SilkS")
		)
		(fp_line
			(start 19.324828 -4.109466)
			(end 20.837144 -5.560314)
			(stroke
				(width 0.1)
				(type default)
			)
			(layer "F.SilkS")
		)
		(fp_line
			(start 19.335496 -1.061212)
			(end 20.307046 -1.992884)
			(stroke
				(width 0.1)
				(type default)
			)
			(layer "F.SilkS")
		)
		(fp_line
			(start 19.335496 -1.061212)
			(end 20.307046 -1.992884)
			(stroke
				(width 0.1)
				(type default)
			)
			(layer "F.SilkS")
		)
		(fp_line
			(start 19.33575 -3.427476)
			(end 19.323558 -3.358134)
			(stroke
				(width 0.1)
				(type default)
			)
			(layer "F.SilkS")
		)
		(fp_line
			(start 19.33575 -3.427476)
			(end 19.323558 -3.358134)
			(stroke
				(width 0.1)
				(type default)
			)
			(layer "F.SilkS")
		)
		(fp_line
			(start 19.347942 -3.496564)
			(end 19.33575 -3.427476)
			(stroke
				(width 0.1)
				(type default)
			)
			(layer "F.SilkS")
		)
		(fp_line
			(start 19.347942 -3.496564)
			(end 19.33575 -3.427476)
			(stroke
				(width 0.1)
				(type default)
			)
			(layer "F.SilkS")
		)
		(fp_line
			(start 19.349212 -5.171694)
			(end 19.289014 -5.171694)
			(stroke
				(width 0.1)
				(type default)
			)
			(layer "F.SilkS")
		)
		(fp_line
			(start 19.349212 -5.171694)
			(end 19.289014 -5.171694)
			(stroke
				(width 0.1)
				(type default)
			)
			(layer "F.SilkS")
		)
		(fp_line
			(start 19.35988 -3.56616)
			(end 19.347942 -3.496564)
			(stroke
				(width 0.1)
				(type default)
			)
			(layer "F.SilkS")
		)
		(fp_line
			(start 19.35988 -3.56616)
			(end 19.347942 -3.496564)
			(stroke
				(width 0.1)
				(type default)
			)
			(layer "F.SilkS")
		)
		(fp_line
			(start 19.363436 -1.030224)
			(end 20.332446 -1.959356)
			(stroke
				(width 0.1)
				(type default)
			)
			(layer "F.SilkS")
		)
		(fp_line
			(start 19.363436 -1.030224)
			(end 20.332446 -1.959356)
			(stroke
				(width 0.1)
				(type default)
			)
			(layer "F.SilkS")
		)
		(fp_line
			(start 19.372326 -3.635502)
			(end 19.35988 -3.56616)
			(stroke
				(width 0.1)
				(type default)
			)
			(layer "F.SilkS")
		)
		(fp_line
			(start 19.372326 -3.635502)
			(end 19.35988 -3.56616)
			(stroke
				(width 0.1)
				(type default)
			)
			(layer "F.SilkS")
		)
		(fp_line
			(start 19.384518 -3.704844)
			(end 19.372326 -3.635502)
			(stroke
				(width 0.1)
				(type default)
			)
			(layer "F.SilkS")
		)
		(fp_line
			(start 19.384518 -3.704844)
			(end 19.372326 -3.635502)
			(stroke
				(width 0.1)
				(type default)
			)
			(layer "F.SilkS")
		)
		(fp_line
			(start 19.385026 -4.109466)
			(end 19.445478 -4.109466)
			(stroke
				(width 0.1)
				(type default)
			)
			(layer "F.SilkS")
		)
		(fp_line
			(start 19.385026 -4.109466)
			(end 19.445478 -4.109466)
			(stroke
				(width 0.1)
				(type default)
			)
			(layer "F.SilkS")
		)
		(fp_line
			(start 19.385026 -4.109466)
			(end 20.825206 -5.490972)
			(stroke
				(width 0.1)
				(type default)
			)
			(layer "F.SilkS")
		)
		(fp_line
			(start 19.385026 -4.109466)
			(end 20.825206 -5.490972)
			(stroke
				(width 0.1)
				(type default)
			)
			(layer "F.SilkS")
		)
		(fp_line
			(start 19.392646 -1.000252)
			(end 20.362164 -1.9304)
			(stroke
				(width 0.1)
				(type default)
			)
			(layer "F.SilkS")
		)
		(fp_line
			(start 19.392646 -1.000252)
			(end 20.362164 -1.9304)
			(stroke
				(width 0.1)
				(type default)
			)
			(layer "F.SilkS")
		)
		(fp_line
			(start 19.396456 -3.774186)
			(end 19.384518 -3.704844)
			(stroke
				(width 0.1)
				(type default)
			)
			(layer "F.SilkS")
		)
		(fp_line
			(start 19.396456 -3.774186)
			(end 19.384518 -3.704844)
			(stroke
				(width 0.1)
				(type default)
			)
			(layer "F.SilkS")
		)
		(fp_line
			(start 19.408902 -3.843528)
			(end 19.396456 -3.774186)
			(stroke
				(width 0.1)
				(type default)
			)
			(layer "F.SilkS")
		)
		(fp_line
			(start 19.408902 -3.843528)
			(end 19.396456 -3.774186)
			(stroke
				(width 0.1)
				(type default)
			)
			(layer "F.SilkS")
		)
		(fp_line
			(start 19.409664 -5.171694)
			(end 19.349212 -5.171694)
			(stroke
				(width 0.1)
				(type default)
			)
			(layer "F.SilkS")
		)
		(fp_line
			(start 19.409664 -5.171694)
			(end 19.349212 -5.171694)
			(stroke
				(width 0.1)
				(type default)
			)
			(layer "F.SilkS")
		)
		(fp_line
			(start 19.42084 -3.913124)
			(end 19.408902 -3.843528)
			(stroke
				(width 0.1)
				(type default)
			)
			(layer "F.SilkS")
		)
		(fp_line
			(start 19.42084 -3.913124)
			(end 19.408902 -3.843528)
			(stroke
				(width 0.1)
				(type default)
			)
			(layer "F.SilkS")
		)
		(fp_line
			(start 19.42084 -3.913124)
			(end 20.776184 -5.21335)
			(stroke
				(width 0.1)
				(type default)
			)
			(layer "F.SilkS")
		)
		(fp_line
			(start 19.42084 -3.913124)
			(end 20.776184 -5.21335)
			(stroke
				(width 0.1)
				(type default)
			)
			(layer "F.SilkS")
		)
		(fp_line
			(start 19.42846 -0.976884)
			(end 20.400772 -1.909572)
			(stroke
				(width 0.1)
				(type default)
			)
			(layer "F.SilkS")
		)
		(fp_line
			(start 19.42846 -0.976884)
			(end 20.400772 -1.909572)
			(stroke
				(width 0.1)
				(type default)
			)
			(layer "F.SilkS")
		)
		(fp_line
			(start 19.433032 -3.982466)
			(end 19.42084 -3.913124)
			(stroke
				(width 0.1)
				(type default)
			)
			(layer "F.SilkS")
		)
		(fp_line
			(start 19.433032 -3.982466)
			(end 19.42084 -3.913124)
			(stroke
				(width 0.1)
				(type default)
			)
			(layer "F.SilkS")
		)
		(fp_line
			(start 19.445478 -4.109466)
			(end 19.455384 -4.109466)
			(stroke
				(width 0.1)
				(type default)
			)
			(layer "F.SilkS")
		)
		(fp_line
			(start 19.445478 -4.109466)
			(end 19.455384 -4.109466)
			(stroke
				(width 0.1)
				(type default)
			)
			(layer "F.SilkS")
		)
		(fp_line
			(start 19.445478 -4.109466)
			(end 20.81276 -5.421376)
			(stroke
				(width 0.1)
				(type default)
			)
			(layer "F.SilkS")
		)
		(fp_line
			(start 19.445478 -4.109466)
			(end 20.81276 -5.421376)
			(stroke
				(width 0.1)
				(type default)
			)
			(layer "F.SilkS")
		)
		(fp_line
			(start 19.445478 -4.051554)
			(end 19.433032 -3.982466)
			(stroke
				(width 0.1)
				(type default)
			)
			(layer "F.SilkS")
		)
		(fp_line
			(start 19.445478 -4.051554)
			(end 19.433032 -3.982466)
			(stroke
				(width 0.1)
				(type default)
			)
			(layer "F.SilkS")
		)
		(fp_line
			(start 19.455384 -4.109466)
			(end 19.445478 -4.051554)
			(stroke
				(width 0.1)
				(type default)
			)
			(layer "F.SilkS")
		)
		(fp_line
			(start 19.455384 -4.109466)
			(end 19.445478 -4.051554)
			(stroke
				(width 0.1)
				(type default)
			)
			(layer "F.SilkS")
		)
		(fp_line
			(start 19.46402 -0.953516)
			(end 20.442428 -1.892046)
			(stroke
				(width 0.1)
				(type default)
			)
			(layer "F.SilkS")
		)
		(fp_line
			(start 19.46402 -0.953516)
			(end 20.442428 -1.892046)
			(stroke
				(width 0.1)
				(type default)
			)
			(layer "F.SilkS")
		)
		(fp_line
			(start 19.469608 -5.171694)
			(end 19.409664 -5.171694)
			(stroke
				(width 0.1)
				(type default)
			)
			(layer "F.SilkS")
		)
		(fp_line
			(start 19.469608 -5.171694)
			(end 19.409664 -5.171694)
			(stroke
				(width 0.1)
				(type default)
			)
			(layer "F.SilkS")
		)
		(fp_line
			(start 19.500088 -0.930148)
			(end 20.491704 -1.881378)
			(stroke
				(width 0.1)
				(type default)
			)
			(layer "F.SilkS")
		)
		(fp_line
			(start 19.500088 -0.930148)
			(end 20.491704 -1.881378)
			(stroke
				(width 0.1)
				(type default)
			)
			(layer "F.SilkS")
		)
		(fp_line
			(start 19.529806 -5.171694)
			(end 19.469608 -5.171694)
			(stroke
				(width 0.1)
				(type default)
			)
			(layer "F.SilkS")
		)
		(fp_line
			(start 19.529806 -5.171694)
			(end 19.469608 -5.171694)
			(stroke
				(width 0.1)
				(type default)
			)
			(layer "F.SilkS")
		)
		(fp_line
			(start 19.536156 -0.906526)
			(end 20.545044 -1.874774)
			(stroke
				(width 0.1)
				(type default)
			)
			(layer "F.SilkS")
		)
		(fp_line
			(start 19.536156 -0.906526)
			(end 20.545044 -1.874774)
			(stroke
				(width 0.1)
				(type default)
			)
			(layer "F.SilkS")
		)
		(fp_line
			(start 19.574002 -0.88519)
			(end 20.60194 -1.871726)
			(stroke
				(width 0.1)
				(type default)
			)
			(layer "F.SilkS")
		)
		(fp_line
			(start 19.574002 -0.88519)
			(end 20.60194 -1.871726)
			(stroke
				(width 0.1)
				(type default)
			)
			(layer "F.SilkS")
		)
		(fp_line
			(start 19.58975 -5.171694)
			(end 19.529806 -5.171694)
			(stroke
				(width 0.1)
				(type default)
			)
			(layer "F.SilkS")
		)
		(fp_line
			(start 19.58975 -5.171694)
			(end 19.529806 -5.171694)
			(stroke
				(width 0.1)
				(type default)
			)
			(layer "F.SilkS")
		)
		(fp_line
			(start 19.58975 -5.171694)
			(end 19.641566 -5.171694)
			(stroke
				(width 0.1)
				(type default)
			)
			(layer "F.SilkS")
		)
		(fp_line
			(start 19.58975 -5.171694)
			(end 19.641566 -5.171694)
			(stroke
				(width 0.1)
				(type default)
			)
			(layer "F.SilkS")
		)
		(fp_line
			(start 19.617944 -0.870458)
			(end 20.669504 -1.878838)
			(stroke
				(width 0.1)
				(type default)
			)
			(layer "F.SilkS")
		)
		(fp_line
			(start 19.617944 -0.870458)
			(end 20.669504 -1.878838)
			(stroke
				(width 0.1)
				(type default)
			)
			(layer "F.SilkS")
		)
		(fp_line
			(start 19.641566 -5.171694)
			(end 19.651726 -5.23113)
			(stroke
				(width 0.1)
				(type default)
			)
			(layer "F.SilkS")
		)
		(fp_line
			(start 19.641566 -5.171694)
			(end 19.651726 -5.23113)
			(stroke
				(width 0.1)
				(type default)
			)
			(layer "F.SilkS")
		)
		(fp_line
			(start 19.662902 -0.855218)
			(end 20.738084 -1.886966)
			(stroke
				(width 0.1)
				(type default)
			)
			(layer "F.SilkS")
		)
		(fp_line
			(start 19.662902 -0.855218)
			(end 20.738084 -1.886966)
			(stroke
				(width 0.1)
				(type default)
			)
			(layer "F.SilkS")
		)
		(fp_line
			(start 19.664172 -5.300472)
			(end 19.651726 -5.23113)
			(stroke
				(width 0.1)
				(type default)
			)
			(layer "F.SilkS")
		)
		(fp_line
			(start 19.664172 -5.300472)
			(end 19.651726 -5.23113)
			(stroke
				(width 0.1)
				(type default)
			)
			(layer "F.SilkS")
		)
		(fp_line
			(start 19.676364 -5.370068)
			(end 19.664172 -5.300472)
			(stroke
				(width 0.1)
				(type default)
			)
			(layer "F.SilkS")
		)
		(fp_line
			(start 19.676364 -5.370068)
			(end 19.664172 -5.300472)
			(stroke
				(width 0.1)
				(type default)
			)
			(layer "F.SilkS")
		)
		(fp_line
			(start 19.688302 -5.439156)
			(end 19.676364 -5.370068)
			(stroke
				(width 0.1)
				(type default)
			)
			(layer "F.SilkS")
		)
		(fp_line
			(start 19.688302 -5.439156)
			(end 19.676364 -5.370068)
			(stroke
				(width 0.1)
				(type default)
			)
			(layer "F.SilkS")
		)
		(fp_line
			(start 19.700748 -5.508752)
			(end 19.688302 -5.439156)
			(stroke
				(width 0.1)
				(type default)
			)
			(layer "F.SilkS")
		)
		(fp_line
			(start 19.700748 -5.508752)
			(end 19.688302 -5.439156)
			(stroke
				(width 0.1)
				(type default)
			)
			(layer "F.SilkS")
		)
		(fp_line
			(start 19.707352 -0.840486)
			(end 20.828 -1.915414)
			(stroke
				(width 0.1)
				(type default)
			)
			(layer "F.SilkS")
		)
		(fp_line
			(start 19.707352 -0.840486)
			(end 20.828 -1.915414)
			(stroke
				(width 0.1)
				(type default)
			)
			(layer "F.SilkS")
		)
		(fp_line
			(start 19.712686 -5.578094)
			(end 19.700748 -5.508752)
			(stroke
				(width 0.1)
				(type default)
			)
			(layer "F.SilkS")
		)
		(fp_line
			(start 19.712686 -5.578094)
			(end 19.700748 -5.508752)
			(stroke
				(width 0.1)
				(type default)
			)
			(layer "F.SilkS")
		)
		(fp_line
			(start 19.725132 -5.647436)
			(end 19.712686 -5.578094)
			(stroke
				(width 0.1)
				(type default)
			)
			(layer "F.SilkS")
		)
		(fp_line
			(start 19.725132 -5.647436)
			(end 19.712686 -5.578094)
			(stroke
				(width 0.1)
				(type default)
			)
			(layer "F.SilkS")
		)
		(fp_line
			(start 19.737324 -5.716778)
			(end 19.725132 -5.647436)
			(stroke
				(width 0.1)
				(type default)
			)
			(layer "F.SilkS")
		)
		(fp_line
			(start 19.737324 -5.716778)
			(end 19.725132 -5.647436)
			(stroke
				(width 0.1)
				(type default)
			)
			(layer "F.SilkS")
		)
		(fp_line
			(start 19.749262 -5.786374)
			(end 19.737324 -5.716778)
			(stroke
				(width 0.1)
				(type default)
			)
			(layer "F.SilkS")
		)
		(fp_line
			(start 19.749262 -5.786374)
			(end 19.737324 -5.716778)
			(stroke
				(width 0.1)
				(type default)
			)
			(layer "F.SilkS")
		)
		(fp_line
			(start 19.751802 -0.825246)
			(end 20.932902 -1.95834)
			(stroke
				(width 0.1)
				(type default)
			)
			(layer "F.SilkS")
		)
		(fp_line
			(start 19.751802 -0.825246)
			(end 20.932902 -1.95834)
			(stroke
				(width 0.1)
				(type default)
			)
			(layer "F.SilkS")
		)
		(fp_line
			(start 19.761708 -5.85597)
			(end 19.749262 -5.786374)
			(stroke
				(width 0.1)
				(type default)
			)
			(layer "F.SilkS")
		)
		(fp_line
			(start 19.761708 -5.85597)
			(end 19.749262 -5.786374)
			(stroke
				(width 0.1)
				(type default)
			)
			(layer "F.SilkS")
		)
		(fp_line
			(start 19.773646 -5.925058)
			(end 19.761708 -5.85597)
			(stroke
				(width 0.1)
				(type default)
			)
			(layer "F.SilkS")
		)
		(fp_line
			(start 19.773646 -5.925058)
			(end 19.761708 -5.85597)
			(stroke
				(width 0.1)
				(type default)
			)
			(layer "F.SilkS")
		)
		(fp_line
			(start 19.785838 -5.9944)
			(end 19.773646 -5.925058)
			(stroke
				(width 0.1)
				(type default)
			)
			(layer "F.SilkS")
		)
		(fp_line
			(start 19.785838 -5.9944)
			(end 19.773646 -5.925058)
			(stroke
				(width 0.1)
				(type default)
			)
			(layer "F.SilkS")
		)
		(fp_line
			(start 19.798284 -6.063996)
			(end 19.785838 -5.9944)
			(stroke
				(width 0.1)
				(type default)
			)
			(layer "F.SilkS")
		)
		(fp_line
			(start 19.798284 -6.063996)
			(end 19.785838 -5.9944)
			(stroke
				(width 0.1)
				(type default)
			)
			(layer "F.SilkS")
		)
		(fp_line
			(start 19.798284 -6.063996)
			(end 19.810222 -6.133338)
			(stroke
				(width 0.1)
				(type default)
			)
			(layer "F.SilkS")
		)
		(fp_line
			(start 19.798284 -6.063996)
			(end 19.810222 -6.133338)
			(stroke
				(width 0.1)
				(type default)
			)
			(layer "F.SilkS")
		)
		(fp_line
			(start 19.801078 -0.815086)
			(end 21.08327 -2.044954)
			(stroke
				(width 0.1)
				(type default)
			)
			(layer "F.SilkS")
		)
		(fp_line
			(start 19.801078 -0.815086)
			(end 21.08327 -2.044954)
			(stroke
				(width 0.1)
				(type default)
			)
			(layer "F.SilkS")
		)
		(fp_line
			(start 19.810222 -6.133338)
			(end 19.822668 -6.20268)
			(stroke
				(width 0.1)
				(type default)
			)
			(layer "F.SilkS")
		)
		(fp_line
			(start 19.810222 -6.133338)
			(end 19.822668 -6.20268)
			(stroke
				(width 0.1)
				(type default)
			)
			(layer "F.SilkS")
		)
		(fp_line
			(start 19.822668 -6.20268)
			(end 19.834606 -6.272022)
			(stroke
				(width 0.1)
				(type default)
			)
			(layer "F.SilkS")
		)
		(fp_line
			(start 19.822668 -6.20268)
			(end 19.834606 -6.272022)
			(stroke
				(width 0.1)
				(type default)
			)
			(layer "F.SilkS")
		)
		(fp_line
			(start 19.835114 -6.274308)
			(end 19.834606 -6.272022)
			(stroke
				(width 0.1)
				(type default)
			)
			(layer "F.SilkS")
		)
		(fp_line
			(start 19.835114 -6.274308)
			(end 19.834606 -6.272022)
			(stroke
				(width 0.1)
				(type default)
			)
			(layer "F.SilkS")
		)
		(fp_line
			(start 19.838924 -6.276086)
			(end 19.834606 -6.272022)
			(stroke
				(width 0.1)
				(type default)
			)
			(layer "F.SilkS")
		)
		(fp_line
			(start 19.838924 -6.276086)
			(end 19.834606 -6.272022)
			(stroke
				(width 0.1)
				(type default)
			)
			(layer "F.SilkS")
		)
		(fp_line
			(start 19.838924 -6.276086)
			(end 19.835114 -6.274308)
			(stroke
				(width 0.1)
				(type default)
			)
			(layer "F.SilkS")
		)
		(fp_line
			(start 19.838924 -6.276086)
			(end 19.835114 -6.274308)
			(stroke
				(width 0.1)
				(type default)
			)
			(layer "F.SilkS")
		)
		(fp_line
			(start 19.855434 -0.809498)
			(end 21.299932 -2.195068)
			(stroke
				(width 0.1)
				(type default)
			)
			(layer "F.SilkS")
		)
		(fp_line
			(start 19.855434 -0.809498)
			(end 21.299932 -2.195068)
			(stroke
				(width 0.1)
				(type default)
			)
			(layer "F.SilkS")
		)
		(fp_line
			(start 19.910044 -0.80391)
			(end 21.273516 -2.11201)
			(stroke
				(width 0.1)
				(type default)
			)
			(layer "F.SilkS")
		)
		(fp_line
			(start 19.910044 -0.80391)
			(end 21.273516 -2.11201)
			(stroke
				(width 0.1)
				(type default)
			)
			(layer "F.SilkS")
		)
		(fp_line
			(start 19.95424 -6.329172)
			(end 19.822668 -6.20268)
			(stroke
				(width 0.1)
				(type default)
			)
			(layer "F.SilkS")
		)
		(fp_line
			(start 19.95424 -6.329172)
			(end 19.822668 -6.20268)
			(stroke
				(width 0.1)
				(type default)
			)
			(layer "F.SilkS")
		)
		(fp_line
			(start 19.95424 -6.329172)
			(end 19.838924 -6.276086)
			(stroke
				(width 0.1)
				(type default)
			)
			(layer "F.SilkS")
		)
		(fp_line
			(start 19.95424 -6.329172)
			(end 19.838924 -6.276086)
			(stroke
				(width 0.1)
				(type default)
			)
			(layer "F.SilkS")
		)
		(fp_line
			(start 19.964654 -0.798576)
			(end 21.2471 -2.028952)
			(stroke
				(width 0.1)
				(type default)
			)
			(layer "F.SilkS")
		)
		(fp_line
			(start 19.964654 -0.798576)
			(end 21.2471 -2.028952)
			(stroke
				(width 0.1)
				(type default)
			)
			(layer "F.SilkS")
		)
		(fp_line
			(start 20.01901 -0.792988)
			(end 21.220684 -1.946148)
			(stroke
				(width 0.1)
				(type default)
			)
			(layer "F.SilkS")
		)
		(fp_line
			(start 20.01901 -0.792988)
			(end 21.220684 -1.946148)
			(stroke
				(width 0.1)
				(type default)
			)
			(layer "F.SilkS")
		)
		(fp_line
			(start 20.069302 -6.382004)
			(end 19.810222 -6.133338)
			(stroke
				(width 0.1)
				(type default)
			)
			(layer "F.SilkS")
		)
		(fp_line
			(start 20.069302 -6.382004)
			(end 19.810222 -6.133338)
			(stroke
				(width 0.1)
				(type default)
			)
			(layer "F.SilkS")
		)
		(fp_line
			(start 20.069302 -6.382004)
			(end 19.95424 -6.329172)
			(stroke
				(width 0.1)
				(type default)
			)
			(layer "F.SilkS")
		)
		(fp_line
			(start 20.069302 -6.382004)
			(end 19.95424 -6.329172)
			(stroke
				(width 0.1)
				(type default)
			)
			(layer "F.SilkS")
		)
		(fp_line
			(start 20.084542 -0.798576)
			(end 21.194268 -1.862836)
			(stroke
				(width 0.1)
				(type default)
			)
			(layer "F.SilkS")
		)
		(fp_line
			(start 20.084542 -0.798576)
			(end 21.194268 -1.862836)
			(stroke
				(width 0.1)
				(type default)
			)
			(layer "F.SilkS")
		)
		(fp_line
			(start 20.14982 -0.803402)
			(end 21.167852 -1.779778)
			(stroke
				(width 0.1)
				(type default)
			)
			(layer "F.SilkS")
		)
		(fp_line
			(start 20.14982 -0.803402)
			(end 21.167852 -1.779778)
			(stroke
				(width 0.1)
				(type default)
			)
			(layer "F.SilkS")
		)
		(fp_line
			(start 20.185126 -6.43509)
			(end 19.798284 -6.063996)
			(stroke
				(width 0.1)
				(type default)
			)
			(layer "F.SilkS")
		)
		(fp_line
			(start 20.185126 -6.43509)
			(end 19.798284 -6.063996)
			(stroke
				(width 0.1)
				(type default)
			)
			(layer "F.SilkS")
		)
		(fp_line
			(start 20.185126 -6.43509)
			(end 20.069302 -6.382004)
			(stroke
				(width 0.1)
				(type default)
			)
			(layer "F.SilkS")
		)
		(fp_line
			(start 20.185126 -6.43509)
			(end 20.069302 -6.382004)
			(stroke
				(width 0.1)
				(type default)
			)
			(layer "F.SilkS")
		)
		(fp_line
			(start 20.215352 -0.808228)
			(end 21.141436 -1.69672)
			(stroke
				(width 0.1)
				(type default)
			)
			(layer "F.SilkS")
		)
		(fp_line
			(start 20.215352 -0.808228)
			(end 21.141436 -1.69672)
			(stroke
				(width 0.1)
				(type default)
			)
			(layer "F.SilkS")
		)
		(fp_line
			(start 20.280884 -0.813562)
			(end 21.115274 -1.613916)
			(stroke
				(width 0.1)
				(type default)
			)
			(layer "F.SilkS")
		)
		(fp_line
			(start 20.280884 -0.813562)
			(end 21.115274 -1.613916)
			(stroke
				(width 0.1)
				(type default)
			)
			(layer "F.SilkS")
		)
		(fp_line
			(start 20.30095 -6.488176)
			(end 19.785838 -5.9944)
			(stroke
				(width 0.1)
				(type default)
			)
			(layer "F.SilkS")
		)
		(fp_line
			(start 20.30095 -6.488176)
			(end 19.785838 -5.9944)
			(stroke
				(width 0.1)
				(type default)
			)
			(layer "F.SilkS")
		)
		(fp_line
			(start 20.30095 -6.488176)
			(end 20.185126 -6.43509)
			(stroke
				(width 0.1)
				(type default)
			)
			(layer "F.SilkS")
		)
		(fp_line
			(start 20.30095 -6.488176)
			(end 20.185126 -6.43509)
			(stroke
				(width 0.1)
				(type default)
			)
			(layer "F.SilkS")
		)
		(fp_line
			(start 20.301966 -2.507234)
			(end 20.28952 -2.437892)
			(stroke
				(width 0.1)
				(type default)
			)
			(layer "F.SilkS")
		)
		(fp_line
			(start 20.301966 -2.507234)
			(end 20.28952 -2.437892)
			(stroke
				(width 0.1)
				(type default)
			)
			(layer "F.SilkS")
		)
		(fp_line
			(start 20.313904 -2.576576)
			(end 20.301966 -2.507234)
			(stroke
				(width 0.1)
				(type default)
			)
			(layer "F.SilkS")
		)
		(fp_line
			(start 20.313904 -2.576576)
			(end 20.301966 -2.507234)
			(stroke
				(width 0.1)
				(type default)
			)
			(layer "F.SilkS")
		)
		(fp_line
			(start 20.32635 -2.646172)
			(end 20.313904 -2.576576)
			(stroke
				(width 0.1)
				(type default)
			)
			(layer "F.SilkS")
		)
		(fp_line
			(start 20.32635 -2.646172)
			(end 20.313904 -2.576576)
			(stroke
				(width 0.1)
				(type default)
			)
			(layer "F.SilkS")
		)
		(fp_line
			(start 20.32635 -2.646172)
			(end 20.338288 -2.715768)
			(stroke
				(width 0.1)
				(type default)
			)
			(layer "F.SilkS")
		)
		(fp_line
			(start 20.32635 -2.646172)
			(end 20.338288 -2.715768)
			(stroke
				(width 0.1)
				(type default)
			)
			(layer "F.SilkS")
		)
		(fp_line
			(start 20.338288 -2.715768)
			(end 20.35048 -2.784856)
			(stroke
				(width 0.1)
				(type default)
			)
			(layer "F.SilkS")
		)
		(fp_line
			(start 20.338288 -2.715768)
			(end 20.35048 -2.784856)
			(stroke
				(width 0.1)
				(type default)
			)
			(layer "F.SilkS")
		)
		(fp_line
			(start 20.35048 -2.784856)
			(end 20.362926 -2.854198)
			(stroke
				(width 0.1)
				(type default)
			)
			(layer "F.SilkS")
		)
		(fp_line
			(start 20.35048 -2.784856)
			(end 20.362926 -2.854198)
			(stroke
				(width 0.1)
				(type default)
			)
			(layer "F.SilkS")
		)
		(fp_line
			(start 20.359116 -0.830834)
			(end 21.088858 -1.530604)
			(stroke
				(width 0.1)
				(type default)
			)
			(layer "F.SilkS")
		)
		(fp_line
			(start 20.359116 -0.830834)
			(end 21.088858 -1.530604)
			(stroke
				(width 0.1)
				(type default)
			)
			(layer "F.SilkS")
		)
		(fp_line
			(start 20.362926 -2.854198)
			(end 20.374864 -2.923794)
			(stroke
				(width 0.1)
				(type default)
			)
			(layer "F.SilkS")
		)
		(fp_line
			(start 20.362926 -2.854198)
			(end 20.374864 -2.923794)
			(stroke
				(width 0.1)
				(type default)
			)
			(layer "F.SilkS")
		)
		(fp_line
			(start 20.374864 -2.923794)
			(end 20.38731 -2.99339)
			(stroke
				(width 0.1)
				(type default)
			)
			(layer "F.SilkS")
		)
		(fp_line
			(start 20.374864 -2.923794)
			(end 20.38731 -2.99339)
			(stroke
				(width 0.1)
				(type default)
			)
			(layer "F.SilkS")
		)
		(fp_line
			(start 20.38731 -2.99339)
			(end 20.399248 -3.062478)
			(stroke
				(width 0.1)
				(type default)
			)
			(layer "F.SilkS")
		)
		(fp_line
			(start 20.38731 -2.99339)
			(end 20.399248 -3.062478)
			(stroke
				(width 0.1)
				(type default)
			)
			(layer "F.SilkS")
		)
		(fp_line
			(start 20.399248 -3.062478)
			(end 20.41144 -3.13182)
			(stroke
				(width 0.1)
				(type default)
			)
			(layer "F.SilkS")
		)
		(fp_line
			(start 20.399248 -3.062478)
			(end 20.41144 -3.13182)
			(stroke
				(width 0.1)
				(type default)
			)
			(layer "F.SilkS")
		)
		(fp_line
			(start 20.41144 -3.13182)
			(end 20.423886 -3.201416)
			(stroke
				(width 0.1)
				(type default)
			)
			(layer "F.SilkS")
		)
		(fp_line
			(start 20.41144 -3.13182)
			(end 20.423886 -3.201416)
			(stroke
				(width 0.1)
				(type default)
			)
			(layer "F.SilkS")
		)
		(fp_line
			(start 20.416012 -6.541262)
			(end 19.773646 -5.925058)
			(stroke
				(width 0.1)
				(type default)
			)
			(layer "F.SilkS")
		)
		(fp_line
			(start 20.416012 -6.541262)
			(end 19.773646 -5.925058)
			(stroke
				(width 0.1)
				(type default)
			)
			(layer "F.SilkS")
		)
		(fp_line
			(start 20.416012 -6.541262)
			(end 20.30095 -6.488176)
			(stroke
				(width 0.1)
				(type default)
			)
			(layer "F.SilkS")
		)
		(fp_line
			(start 20.416012 -6.541262)
			(end 20.30095 -6.488176)
			(stroke
				(width 0.1)
				(type default)
			)
			(layer "F.SilkS")
		)
		(fp_line
			(start 20.423886 -3.201416)
			(end 20.435824 -3.270758)
			(stroke
				(width 0.1)
				(type default)
			)
			(layer "F.SilkS")
		)
		(fp_line
			(start 20.423886 -3.201416)
			(end 20.435824 -3.270758)
			(stroke
				(width 0.1)
				(type default)
			)
			(layer "F.SilkS")
		)
		(fp_line
			(start 20.435824 -3.270758)
			(end 20.44827 -3.340354)
			(stroke
				(width 0.1)
				(type default)
			)
			(layer "F.SilkS")
		)
		(fp_line
			(start 20.435824 -3.270758)
			(end 20.44827 -3.340354)
			(stroke
				(width 0.1)
				(type default)
			)
			(layer "F.SilkS")
		)
		(fp_line
			(start 20.437602 -0.848106)
			(end 21.062188 -1.447546)
			(stroke
				(width 0.1)
				(type default)
			)
			(layer "F.SilkS")
		)
		(fp_line
			(start 20.437602 -0.848106)
			(end 21.062188 -1.447546)
			(stroke
				(width 0.1)
				(type default)
			)
			(layer "F.SilkS")
		)
		(fp_line
			(start 20.44827 -3.340354)
			(end 20.460462 -3.409442)
			(stroke
				(width 0.1)
				(type default)
			)
			(layer "F.SilkS")
		)
		(fp_line
			(start 20.44827 -3.340354)
			(end 20.460462 -3.409442)
			(stroke
				(width 0.1)
				(type default)
			)
			(layer "F.SilkS")
		)
		(fp_line
			(start 20.460462 -3.409442)
			(end 20.4724 -3.479038)
			(stroke
				(width 0.1)
				(type default)
			)
			(layer "F.SilkS")
		)
		(fp_line
			(start 20.460462 -3.409442)
			(end 20.4724 -3.479038)
			(stroke
				(width 0.1)
				(type default)
			)
			(layer "F.SilkS")
		)
		(fp_line
			(start 20.484846 -3.548634)
			(end 20.4724 -3.479038)
			(stroke
				(width 0.1)
				(type default)
			)
			(layer "F.SilkS")
		)
		(fp_line
			(start 20.484846 -3.548634)
			(end 20.4724 -3.479038)
			(stroke
				(width 0.1)
				(type default)
			)
			(layer "F.SilkS")
		)
		(fp_line
			(start 20.496784 -3.617976)
			(end 19.141186 -2.317242)
			(stroke
				(width 0.1)
				(type default)
			)
			(layer "F.SilkS")
		)
		(fp_line
			(start 20.496784 -3.617976)
			(end 19.141186 -2.317242)
			(stroke
				(width 0.1)
				(type default)
			)
			(layer "F.SilkS")
		)
		(fp_line
			(start 20.496784 -3.617976)
			(end 20.484846 -3.548634)
			(stroke
				(width 0.1)
				(type default)
			)
			(layer "F.SilkS")
		)
		(fp_line
			(start 20.496784 -3.617976)
			(end 20.484846 -3.548634)
			(stroke
				(width 0.1)
				(type default)
			)
			(layer "F.SilkS")
		)
		(fp_line
			(start 20.496784 -3.617976)
			(end 20.50923 -3.687064)
			(stroke
				(width 0.1)
				(type default)
			)
			(layer "F.SilkS")
		)
		(fp_line
			(start 20.496784 -3.617976)
			(end 20.50923 -3.687064)
			(stroke
				(width 0.1)
				(type default)
			)
			(layer "F.SilkS")
		)
		(fp_line
			(start 20.50923 -3.687064)
			(end 20.521422 -3.75666)
			(stroke
				(width 0.1)
				(type default)
			)
			(layer "F.SilkS")
		)
		(fp_line
			(start 20.50923 -3.687064)
			(end 20.521422 -3.75666)
			(stroke
				(width 0.1)
				(type default)
			)
			(layer "F.SilkS")
		)
		(fp_line
			(start 20.515834 -0.865632)
			(end 21.035772 -1.364742)
			(stroke
				(width 0.1)
				(type default)
			)
			(layer "F.SilkS")
		)
		(fp_line
			(start 20.515834 -0.865632)
			(end 21.035772 -1.364742)
			(stroke
				(width 0.1)
				(type default)
			)
			(layer "F.SilkS")
		)
		(fp_line
			(start 20.521422 -3.75666)
			(end 20.533614 -3.826256)
			(stroke
				(width 0.1)
				(type default)
			)
			(layer "F.SilkS")
		)
		(fp_line
			(start 20.521422 -3.75666)
			(end 20.533614 -3.826256)
			(stroke
				(width 0.1)
				(type default)
			)
			(layer "F.SilkS")
		)
		(fp_line
			(start 20.531328 -6.594348)
			(end 19.761708 -5.85597)
			(stroke
				(width 0.1)
				(type default)
			)
			(layer "F.SilkS")
		)
		(fp_line
			(start 20.531328 -6.594348)
			(end 19.761708 -5.85597)
			(stroke
				(width 0.1)
				(type default)
			)
			(layer "F.SilkS")
		)
		(fp_line
			(start 20.531328 -6.594348)
			(end 20.416012 -6.541262)
			(stroke
				(width 0.1)
				(type default)
			)
			(layer "F.SilkS")
		)
		(fp_line
			(start 20.531328 -6.594348)
			(end 20.416012 -6.541262)
			(stroke
				(width 0.1)
				(type default)
			)
			(layer "F.SilkS")
		)
		(fp_line
			(start 20.533614 -3.826256)
			(end 20.545806 -3.895344)
			(stroke
				(width 0.1)
				(type default)
			)
			(layer "F.SilkS")
		)
		(fp_line
			(start 20.533614 -3.826256)
			(end 20.545806 -3.895344)
			(stroke
				(width 0.1)
				(type default)
			)
			(layer "F.SilkS")
		)
		(fp_line
			(start 20.545806 -3.895344)
			(end 20.557744 -3.96494)
			(stroke
				(width 0.1)
				(type default)
			)
			(layer "F.SilkS")
		)
		(fp_line
			(start 20.545806 -3.895344)
			(end 20.557744 -3.96494)
			(stroke
				(width 0.1)
				(type default)
			)
			(layer "F.SilkS")
		)
		(fp_line
			(start 20.557744 -3.96494)
			(end 20.57019 -4.034282)
			(stroke
				(width 0.1)
				(type default)
			)
			(layer "F.SilkS")
		)
		(fp_line
			(start 20.557744 -3.96494)
			(end 20.57019 -4.034282)
			(stroke
				(width 0.1)
				(type default)
			)
			(layer "F.SilkS")
		)
		(fp_line
			(start 20.57019 -4.034282)
			(end 20.582382 -4.103878)
			(stroke
				(width 0.1)
				(type default)
			)
			(layer "F.SilkS")
		)
		(fp_line
			(start 20.57019 -4.034282)
			(end 20.582382 -4.103878)
			(stroke
				(width 0.1)
				(type default)
			)
			(layer "F.SilkS")
		)
		(fp_line
			(start 20.582382 -4.103878)
			(end 20.583398 -4.109466)
			(stroke
				(width 0.1)
				(type default)
			)
			(layer "F.SilkS")
		)
		(fp_line
			(start 20.582382 -4.103878)
			(end 20.583398 -4.109466)
			(stroke
				(width 0.1)
				(type default)
			)
			(layer "F.SilkS")
		)
		(fp_line
			(start 20.582382 -4.103878)
			(end 20.588224 -4.109466)
			(stroke
				(width 0.1)
				(type default)
			)
			(layer "F.SilkS")
		)
		(fp_line
			(start 20.582382 -4.103878)
			(end 20.588224 -4.109466)
			(stroke
				(width 0.1)
				(type default)
			)
			(layer "F.SilkS")
		)
		(fp_line
			(start 20.583398 -4.109466)
			(end 20.588224 -4.109466)
			(stroke
				(width 0.1)
				(type default)
			)
			(layer "F.SilkS")
		)
		(fp_line
			(start 20.583398 -4.109466)
			(end 20.588224 -4.109466)
			(stroke
				(width 0.1)
				(type default)
			)
			(layer "F.SilkS")
		)
		(fp_line
			(start 20.610322 -0.898652)
			(end 21.00961 -1.281684)
			(stroke
				(width 0.1)
				(type default)
			)
			(layer "F.SilkS")
		)
		(fp_line
			(start 20.610322 -0.898652)
			(end 21.00961 -1.281684)
			(stroke
				(width 0.1)
				(type default)
			)
			(layer "F.SilkS")
		)
		(fp_line
			(start 20.647152 -6.647434)
			(end 19.749262 -5.786374)
			(stroke
				(width 0.1)
				(type default)
			)
			(layer "F.SilkS")
		)
		(fp_line
			(start 20.647152 -6.647434)
			(end 19.749262 -5.786374)
			(stroke
				(width 0.1)
				(type default)
			)
			(layer "F.SilkS")
		)
		(fp_line
			(start 20.647152 -6.647434)
			(end 20.531328 -6.594348)
			(stroke
				(width 0.1)
				(type default)
			)
			(layer "F.SilkS")
		)
		(fp_line
			(start 20.647152 -6.647434)
			(end 20.531328 -6.594348)
			(stroke
				(width 0.1)
				(type default)
			)
			(layer "F.SilkS")
		)
		(fp_line
			(start 20.648422 -4.109466)
			(end 20.588224 -4.109466)
			(stroke
				(width 0.1)
				(type default)
			)
			(layer "F.SilkS")
		)
		(fp_line
			(start 20.648422 -4.109466)
			(end 20.588224 -4.109466)
			(stroke
				(width 0.1)
				(type default)
			)
			(layer "F.SilkS")
		)
		(fp_line
			(start 20.708366 -0.934974)
			(end 20.98294 -1.198626)
			(stroke
				(width 0.1)
				(type default)
			)
			(layer "F.SilkS")
		)
		(fp_line
			(start 20.708366 -0.934974)
			(end 20.98294 -1.198626)
			(stroke
				(width 0.1)
				(type default)
			)
			(layer "F.SilkS")
		)
		(fp_line
			(start 20.70862 -4.109466)
			(end 20.648422 -4.109466)
			(stroke
				(width 0.1)
				(type default)
			)
			(layer "F.SilkS")
		)
		(fp_line
			(start 20.70862 -4.109466)
			(end 20.648422 -4.109466)
			(stroke
				(width 0.1)
				(type default)
			)
			(layer "F.SilkS")
		)
		(fp_line
			(start 20.762722 -6.70052)
			(end 19.737324 -5.716778)
			(stroke
				(width 0.1)
				(type default)
			)
			(layer "F.SilkS")
		)
		(fp_line
			(start 20.762722 -6.70052)
			(end 19.737324 -5.716778)
			(stroke
				(width 0.1)
				(type default)
			)
			(layer "F.SilkS")
		)
		(fp_line
			(start 20.762722 -6.70052)
			(end 20.647152 -6.647434)
			(stroke
				(width 0.1)
				(type default)
			)
			(layer "F.SilkS")
		)
		(fp_line
			(start 20.762722 -6.70052)
			(end 20.647152 -6.647434)
			(stroke
				(width 0.1)
				(type default)
			)
			(layer "F.SilkS")
		)
		(fp_line
			(start 20.768564 -4.109466)
			(end 20.70862 -4.109466)
			(stroke
				(width 0.1)
				(type default)
			)
			(layer "F.SilkS")
		)
		(fp_line
			(start 20.768564 -4.109466)
			(end 20.70862 -4.109466)
			(stroke
				(width 0.1)
				(type default)
			)
			(layer "F.SilkS")
		)
		(fp_line
			(start 20.769072 -5.171694)
			(end 20.793202 -5.171694)
			(stroke
				(width 0.1)
				(type default)
			)
			(layer "F.SilkS")
		)
		(fp_line
			(start 20.769072 -5.171694)
			(end 20.793202 -5.171694)
			(stroke
				(width 0.1)
				(type default)
			)
			(layer "F.SilkS")
		)
		(fp_line
			(start 20.776184 -5.21335)
			(end 20.769072 -5.171694)
			(stroke
				(width 0.1)
				(type default)
			)
			(layer "F.SilkS")
		)
		(fp_line
			(start 20.776184 -5.21335)
			(end 20.769072 -5.171694)
			(stroke
				(width 0.1)
				(type default)
			)
			(layer "F.SilkS")
		)
		(fp_line
			(start 20.776184 -5.21335)
			(end 20.78863 -5.282692)
			(stroke
				(width 0.1)
				(type default)
			)
			(layer "F.SilkS")
		)
		(fp_line
			(start 20.776184 -5.21335)
			(end 20.78863 -5.282692)
			(stroke
				(width 0.1)
				(type default)
			)
			(layer "F.SilkS")
		)
		(fp_line
			(start 20.78863 -5.282692)
			(end 19.433032 -3.982466)
			(stroke
				(width 0.1)
				(type default)
			)
			(layer "F.SilkS")
		)
		(fp_line
			(start 20.78863 -5.282692)
			(end 19.433032 -3.982466)
			(stroke
				(width 0.1)
				(type default)
			)
			(layer "F.SilkS")
		)
		(fp_line
			(start 20.78863 -5.282692)
			(end 20.800822 -5.352034)
			(stroke
				(width 0.1)
				(type default)
			)
			(layer "F.SilkS")
		)
		(fp_line
			(start 20.78863 -5.282692)
			(end 20.800822 -5.352034)
			(stroke
				(width 0.1)
				(type default)
			)
			(layer "F.SilkS")
		)
		(fp_line
			(start 20.793202 -5.171694)
			(end 19.408902 -3.843528)
			(stroke
				(width 0.1)
				(type default)
			)
			(layer "F.SilkS")
		)
		(fp_line
			(start 20.793202 -5.171694)
			(end 19.408902 -3.843528)
			(stroke
				(width 0.1)
				(type default)
			)
			(layer "F.SilkS")
		)
		(fp_line
			(start 20.800822 -5.352034)
			(end 19.445478 -4.051554)
			(stroke
				(width 0.1)
				(type default)
			)
			(layer "F.SilkS")
		)
		(fp_line
			(start 20.800822 -5.352034)
			(end 19.445478 -4.051554)
			(stroke
				(width 0.1)
				(type default)
			)
			(layer "F.SilkS")
		)
		(fp_line
			(start 20.800822 -5.352034)
			(end 20.81276 -5.421376)
			(stroke
				(width 0.1)
				(type default)
			)
			(layer "F.SilkS")
		)
		(fp_line
			(start 20.800822 -5.352034)
			(end 20.81276 -5.421376)
			(stroke
				(width 0.1)
				(type default)
			)
			(layer "F.SilkS")
		)
		(fp_line
			(start 20.81276 -5.421376)
			(end 20.825206 -5.490972)
			(stroke
				(width 0.1)
				(type default)
			)
			(layer "F.SilkS")
		)
		(fp_line
			(start 20.81276 -5.421376)
			(end 20.825206 -5.490972)
			(stroke
				(width 0.1)
				(type default)
			)
			(layer "F.SilkS")
		)
		(fp_line
			(start 20.825206 -5.490972)
			(end 20.837144 -5.560314)
			(stroke
				(width 0.1)
				(type default)
			)
			(layer "F.SilkS")
		)
		(fp_line
			(start 20.825206 -5.490972)
			(end 20.837144 -5.560314)
			(stroke
				(width 0.1)
				(type default)
			)
			(layer "F.SilkS")
		)
		(fp_line
			(start 20.829016 -4.109466)
			(end 20.768564 -4.109466)
			(stroke
				(width 0.1)
				(type default)
			)
			(layer "F.SilkS")
		)
		(fp_line
			(start 20.829016 -4.109466)
			(end 20.768564 -4.109466)
			(stroke
				(width 0.1)
				(type default)
			)
			(layer "F.SilkS")
		)
		(fp_line
			(start 20.831302 -0.995426)
			(end 20.956524 -1.115314)
			(stroke
				(width 0.1)
				(type default)
			)
			(layer "F.SilkS")
		)
		(fp_line
			(start 20.831302 -0.995426)
			(end 20.956524 -1.115314)
			(stroke
				(width 0.1)
				(type default)
			)
			(layer "F.SilkS")
		)
		(fp_line
			(start 20.837144 -5.560314)
			(end 20.84959 -5.629656)
			(stroke
				(width 0.1)
				(type default)
			)
			(layer "F.SilkS")
		)
		(fp_line
			(start 20.837144 -5.560314)
			(end 20.84959 -5.629656)
			(stroke
				(width 0.1)
				(type default)
			)
			(layer "F.SilkS")
		)
		(fp_line
			(start 20.84959 -5.629656)
			(end 20.861782 -5.699252)
			(stroke
				(width 0.1)
				(type default)
			)
			(layer "F.SilkS")
		)
		(fp_line
			(start 20.84959 -5.629656)
			(end 20.861782 -5.699252)
			(stroke
				(width 0.1)
				(type default)
			)
			(layer "F.SilkS")
		)
		(fp_line
			(start 20.8534 -5.171694)
			(end 19.396456 -3.774186)
			(stroke
				(width 0.1)
				(type default)
			)
			(layer "F.SilkS")
		)
		(fp_line
			(start 20.8534 -5.171694)
			(end 19.396456 -3.774186)
			(stroke
				(width 0.1)
				(type default)
			)
			(layer "F.SilkS")
		)
		(fp_line
			(start 20.8534 -5.171694)
			(end 20.793202 -5.171694)
			(stroke
				(width 0.1)
				(type default)
			)
			(layer "F.SilkS")
		)
		(fp_line
			(start 20.8534 -5.171694)
			(end 20.793202 -5.171694)
			(stroke
				(width 0.1)
				(type default)
			)
			(layer "F.SilkS")
		)
		(fp_line
			(start 20.861782 -5.699252)
			(end 20.874228 -5.768594)
			(stroke
				(width 0.1)
				(type default)
			)
			(layer "F.SilkS")
		)
		(fp_line
			(start 20.861782 -5.699252)
			(end 20.874228 -5.768594)
			(stroke
				(width 0.1)
				(type default)
			)
			(layer "F.SilkS")
		)
		(fp_line
			(start 20.874228 -5.768594)
			(end 20.886166 -5.837936)
			(stroke
				(width 0.1)
				(type default)
			)
			(layer "F.SilkS")
		)
		(fp_line
			(start 20.874228 -5.768594)
			(end 20.886166 -5.837936)
			(stroke
				(width 0.1)
				(type default)
			)
			(layer "F.SilkS")
		)
		(fp_line
			(start 20.877784 -6.753606)
			(end 19.725132 -5.647436)
			(stroke
				(width 0.1)
				(type default)
			)
			(layer "F.SilkS")
		)
		(fp_line
			(start 20.877784 -6.753606)
			(end 19.725132 -5.647436)
			(stroke
				(width 0.1)
				(type default)
			)
			(layer "F.SilkS")
		)
		(fp_line
			(start 20.877784 -6.753606)
			(end 20.762722 -6.70052)
			(stroke
				(width 0.1)
				(type default)
			)
			(layer "F.SilkS")
		)
		(fp_line
			(start 20.877784 -6.753606)
			(end 20.762722 -6.70052)
			(stroke
				(width 0.1)
				(type default)
			)
			(layer "F.SilkS")
		)
		(fp_line
			(start 20.886166 -5.837936)
			(end 20.898104 -5.907278)
			(stroke
				(width 0.1)
				(type default)
			)
			(layer "F.SilkS")
		)
		(fp_line
			(start 20.886166 -5.837936)
			(end 20.898104 -5.907278)
			(stroke
				(width 0.1)
				(type default)
			)
			(layer "F.SilkS")
		)
		(fp_line
			(start 20.889214 -4.109466)
			(end 20.829016 -4.109466)
			(stroke
				(width 0.1)
				(type default)
			)
			(layer "F.SilkS")
		)
		(fp_line
			(start 20.889214 -4.109466)
			(end 20.829016 -4.109466)
			(stroke
				(width 0.1)
				(type default)
			)
			(layer "F.SilkS")
		)
		(fp_line
			(start 20.898104 -5.907278)
			(end 20.91055 -5.976874)
			(stroke
				(width 0.1)
				(type default)
			)
			(layer "F.SilkS")
		)
		(fp_line
			(start 20.898104 -5.907278)
			(end 20.91055 -5.976874)
			(stroke
				(width 0.1)
				(type default)
			)
			(layer "F.SilkS")
		)
		(fp_line
			(start 20.91055 -5.976874)
			(end 20.922742 -6.04647)
			(stroke
				(width 0.1)
				(type default)
			)
			(layer "F.SilkS")
		)
		(fp_line
			(start 20.91055 -5.976874)
			(end 20.922742 -6.04647)
			(stroke
				(width 0.1)
				(type default)
			)
			(layer "F.SilkS")
		)
		(fp_line
			(start 20.913344 -5.171694)
			(end 19.384518 -3.704844)
			(stroke
				(width 0.1)
				(type default)
			)
			(layer "F.SilkS")
		)
		(fp_line
			(start 20.913344 -5.171694)
			(end 19.384518 -3.704844)
			(stroke
				(width 0.1)
				(type default)
			)
			(layer "F.SilkS")
		)
		(fp_line
			(start 20.913344 -5.171694)
			(end 20.8534 -5.171694)
			(stroke
				(width 0.1)
				(type default)
			)
			(layer "F.SilkS")
		)
		(fp_line
			(start 20.913344 -5.171694)
			(end 20.8534 -5.171694)
			(stroke
				(width 0.1)
				(type default)
			)
			(layer "F.SilkS")
		)
		(fp_line
			(start 20.922742 -6.04647)
			(end 20.93468 -6.115558)
			(stroke
				(width 0.1)
				(type default)
			)
			(layer "F.SilkS")
		)
		(fp_line
			(start 20.922742 -6.04647)
			(end 20.93468 -6.115558)
			(stroke
				(width 0.1)
				(type default)
			)
			(layer "F.SilkS")
		)
		(fp_line
			(start 20.93468 -6.115558)
			(end 20.947126 -6.1849)
			(stroke
				(width 0.1)
				(type default)
			)
			(layer "F.SilkS")
		)
		(fp_line
			(start 20.93468 -6.115558)
			(end 20.947126 -6.1849)
			(stroke
				(width 0.1)
				(type default)
			)
			(layer "F.SilkS")
		)
		(fp_line
			(start 20.947126 -6.1849)
			(end 20.959318 -6.254496)
			(stroke
				(width 0.1)
				(type default)
			)
			(layer "F.SilkS")
		)
		(fp_line
			(start 20.947126 -6.1849)
			(end 20.959318 -6.254496)
			(stroke
				(width 0.1)
				(type default)
			)
			(layer "F.SilkS")
		)
		(fp_line
			(start 20.949666 -4.109466)
			(end 20.889214 -4.109466)
			(stroke
				(width 0.1)
				(type default)
			)
			(layer "F.SilkS")
		)
		(fp_line
			(start 20.949666 -4.109466)
			(end 20.889214 -4.109466)
			(stroke
				(width 0.1)
				(type default)
			)
			(layer "F.SilkS")
		)
		(fp_line
			(start 20.959318 -6.254496)
			(end 20.97151 -6.324092)
			(stroke
				(width 0.1)
				(type default)
			)
			(layer "F.SilkS")
		)
		(fp_line
			(start 20.959318 -6.254496)
			(end 20.97151 -6.324092)
			(stroke
				(width 0.1)
				(type default)
			)
			(layer "F.SilkS")
		)
		(fp_line
			(start 20.97151 -6.324092)
			(end 18.75155 -4.194556)
			(stroke
				(width 0.1)
				(type default)
			)
			(layer "F.SilkS")
		)
		(fp_line
			(start 20.97151 -6.324092)
			(end 18.75155 -4.194556)
			(stroke
				(width 0.1)
				(type default)
			)
			(layer "F.SilkS")
		)
		(fp_line
			(start 20.97151 -6.324092)
			(end 20.983702 -6.393434)
			(stroke
				(width 0.1)
				(type default)
			)
			(layer "F.SilkS")
		)
		(fp_line
			(start 20.97151 -6.324092)
			(end 20.983702 -6.393434)
			(stroke
				(width 0.1)
				(type default)
			)
			(layer "F.SilkS")
		)
		(fp_line
			(start 20.973542 -5.171694)
			(end 19.372326 -3.635502)
			(stroke
				(width 0.1)
				(type default)
			)
			(layer "F.SilkS")
		)
		(fp_line
			(start 20.973542 -5.171694)
			(end 19.372326 -3.635502)
			(stroke
				(width 0.1)
				(type default)
			)
			(layer "F.SilkS")
		)
		(fp_line
			(start 20.973542 -5.171694)
			(end 20.913344 -5.171694)
			(stroke
				(width 0.1)
				(type default)
			)
			(layer "F.SilkS")
		)
		(fp_line
			(start 20.973542 -5.171694)
			(end 20.913344 -5.171694)
			(stroke
				(width 0.1)
				(type default)
			)
			(layer "F.SilkS")
		)
		(fp_line
			(start 20.98294 -1.198626)
			(end 20.956524 -1.115314)
			(stroke
				(width 0.1)
				(type default)
			)
			(layer "F.SilkS")
		)
		(fp_line
			(start 20.98294 -1.198626)
			(end 20.956524 -1.115314)
			(stroke
				(width 0.1)
				(type default)
			)
			(layer "F.SilkS")
		)
		(fp_line
			(start 20.983702 -6.393434)
			(end 18.763996 -4.263898)
			(stroke
				(width 0.1)
				(type default)
			)
			(layer "F.SilkS")
		)
		(fp_line
			(start 20.983702 -6.393434)
			(end 18.763996 -4.263898)
			(stroke
				(width 0.1)
				(type default)
			)
			(layer "F.SilkS")
		)
		(fp_line
			(start 20.983702 -6.393434)
			(end 20.996148 -6.462522)
			(stroke
				(width 0.1)
				(type default)
			)
			(layer "F.SilkS")
		)
		(fp_line
			(start 20.983702 -6.393434)
			(end 20.996148 -6.462522)
			(stroke
				(width 0.1)
				(type default)
			)
			(layer "F.SilkS")
		)
		(fp_line
			(start 20.993354 -6.806438)
			(end 19.712686 -5.578094)
			(stroke
				(width 0.1)
				(type default)
			)
			(layer "F.SilkS")
		)
		(fp_line
			(start 20.993354 -6.806438)
			(end 19.712686 -5.578094)
			(stroke
				(width 0.1)
				(type default)
			)
			(layer "F.SilkS")
		)
		(fp_line
			(start 20.993354 -6.806438)
			(end 20.877784 -6.753606)
			(stroke
				(width 0.1)
				(type default)
			)
			(layer "F.SilkS")
		)
		(fp_line
			(start 20.993354 -6.806438)
			(end 20.877784 -6.753606)
			(stroke
				(width 0.1)
				(type default)
			)
			(layer "F.SilkS")
		)
		(fp_line
			(start 20.996148 -6.462522)
			(end 18.775934 -4.33324)
			(stroke
				(width 0.1)
				(type default)
			)
			(layer "F.SilkS")
		)
		(fp_line
			(start 20.996148 -6.462522)
			(end 18.775934 -4.33324)
			(stroke
				(width 0.1)
				(type default)
			)
			(layer "F.SilkS")
		)
		(fp_line
			(start 20.996148 -6.462522)
			(end 21.008086 -6.532118)
			(stroke
				(width 0.1)
				(type default)
			)
			(layer "F.SilkS")
		)
		(fp_line
			(start 20.996148 -6.462522)
			(end 21.008086 -6.532118)
			(stroke
				(width 0.1)
				(type default)
			)
			(layer "F.SilkS")
		)
		(fp_line
			(start 21.008086 -6.532118)
			(end 19.651726 -5.23113)
			(stroke
				(width 0.1)
				(type default)
			)
			(layer "F.SilkS")
		)
		(fp_line
			(start 21.008086 -6.532118)
			(end 19.651726 -5.23113)
			(stroke
				(width 0.1)
				(type default)
			)
			(layer "F.SilkS")
		)
		(fp_line
			(start 21.008086 -6.532118)
			(end 21.020278 -6.60146)
			(stroke
				(width 0.1)
				(type default)
			)
			(layer "F.SilkS")
		)
		(fp_line
			(start 21.008086 -6.532118)
			(end 21.020278 -6.60146)
			(stroke
				(width 0.1)
				(type default)
			)
			(layer "F.SilkS")
		)
		(fp_line
			(start 21.00961 -4.109466)
			(end 20.949666 -4.109466)
			(stroke
				(width 0.1)
				(type default)
			)
			(layer "F.SilkS")
		)
		(fp_line
			(start 21.00961 -4.109466)
			(end 20.949666 -4.109466)
			(stroke
				(width 0.1)
				(type default)
			)
			(layer "F.SilkS")
		)
		(fp_line
			(start 21.00961 -4.109466)
			(end 21.069554 -4.109466)
			(stroke
				(width 0.1)
				(type default)
			)
			(layer "F.SilkS")
		)
		(fp_line
			(start 21.00961 -4.109466)
			(end 21.069554 -4.109466)
			(stroke
				(width 0.1)
				(type default)
			)
			(layer "F.SilkS")
		)
		(fp_line
			(start 21.00961 -1.281684)
			(end 20.98294 -1.198626)
			(stroke
				(width 0.1)
				(type default)
			)
			(layer "F.SilkS")
		)
		(fp_line
			(start 21.00961 -1.281684)
			(end 20.98294 -1.198626)
			(stroke
				(width 0.1)
				(type default)
			)
			(layer "F.SilkS")
		)
		(fp_line
			(start 21.020278 -6.60146)
			(end 19.664172 -5.300472)
			(stroke
				(width 0.1)
				(type default)
			)
			(layer "F.SilkS")
		)
		(fp_line
			(start 21.020278 -6.60146)
			(end 19.664172 -5.300472)
			(stroke
				(width 0.1)
				(type default)
			)
			(layer "F.SilkS")
		)
		(fp_line
			(start 21.020278 -6.60146)
			(end 21.03247 -6.671056)
			(stroke
				(width 0.1)
				(type default)
			)
			(layer "F.SilkS")
		)
		(fp_line
			(start 21.020278 -6.60146)
			(end 21.03247 -6.671056)
			(stroke
				(width 0.1)
				(type default)
			)
			(layer "F.SilkS")
		)
		(fp_line
			(start 21.03247 -6.671056)
			(end 19.676364 -5.370068)
			(stroke
				(width 0.1)
				(type default)
			)
			(layer "F.SilkS")
		)
		(fp_line
			(start 21.03247 -6.671056)
			(end 19.676364 -5.370068)
			(stroke
				(width 0.1)
				(type default)
			)
			(layer "F.SilkS")
		)
		(fp_line
			(start 21.03247 -6.671056)
			(end 21.044662 -6.740144)
			(stroke
				(width 0.1)
				(type default)
			)
			(layer "F.SilkS")
		)
		(fp_line
			(start 21.03247 -6.671056)
			(end 21.044662 -6.740144)
			(stroke
				(width 0.1)
				(type default)
			)
			(layer "F.SilkS")
		)
		(fp_line
			(start 21.033994 -5.171694)
			(end 19.35988 -3.56616)
			(stroke
				(width 0.1)
				(type default)
			)
			(layer "F.SilkS")
		)
		(fp_line
			(start 21.033994 -5.171694)
			(end 19.35988 -3.56616)
			(stroke
				(width 0.1)
				(type default)
			)
			(layer "F.SilkS")
		)
		(fp_line
			(start 21.033994 -5.171694)
			(end 20.973542 -5.171694)
			(stroke
				(width 0.1)
				(type default)
			)
			(layer "F.SilkS")
		)
		(fp_line
			(start 21.033994 -5.171694)
			(end 20.973542 -5.171694)
			(stroke
				(width 0.1)
				(type default)
			)
			(layer "F.SilkS")
		)
		(fp_line
			(start 21.035772 -1.364742)
			(end 21.00961 -1.281684)
			(stroke
				(width 0.1)
				(type default)
			)
			(layer "F.SilkS")
		)
		(fp_line
			(start 21.035772 -1.364742)
			(end 21.00961 -1.281684)
			(stroke
				(width 0.1)
				(type default)
			)
			(layer "F.SilkS")
		)
		(fp_line
			(start 21.044662 -6.740144)
			(end 19.688302 -5.439156)
			(stroke
				(width 0.1)
				(type default)
			)
			(layer "F.SilkS")
		)
		(fp_line
			(start 21.044662 -6.740144)
			(end 19.688302 -5.439156)
			(stroke
				(width 0.1)
				(type default)
			)
			(layer "F.SilkS")
		)
		(fp_line
			(start 21.044662 -6.740144)
			(end 21.057108 -6.80974)
			(stroke
				(width 0.1)
				(type default)
			)
			(layer "F.SilkS")
		)
		(fp_line
			(start 21.044662 -6.740144)
			(end 21.057108 -6.80974)
			(stroke
				(width 0.1)
				(type default)
			)
			(layer "F.SilkS")
		)
		(fp_line
			(start 21.057108 -6.80974)
			(end 19.700748 -5.508752)
			(stroke
				(width 0.1)
				(type default)
			)
			(layer "F.SilkS")
		)
		(fp_line
			(start 21.057108 -6.80974)
			(end 19.700748 -5.508752)
			(stroke
				(width 0.1)
				(type default)
			)
			(layer "F.SilkS")
		)
		(fp_line
			(start 21.057108 -6.80974)
			(end 21.061934 -6.838188)
			(stroke
				(width 0.1)
				(type default)
			)
			(layer "F.SilkS")
		)
		(fp_line
			(start 21.057108 -6.80974)
			(end 21.061934 -6.838188)
			(stroke
				(width 0.1)
				(type default)
			)
			(layer "F.SilkS")
		)
		(fp_line
			(start 21.061934 -6.838188)
			(end 20.993354 -6.806438)
			(stroke
				(width 0.1)
				(type default)
			)
			(layer "F.SilkS")
		)
		(fp_line
			(start 21.061934 -6.838188)
			(end 20.993354 -6.806438)
			(stroke
				(width 0.1)
				(type default)
			)
			(layer "F.SilkS")
		)
		(fp_line
			(start 21.062188 -1.447546)
			(end 21.035772 -1.364742)
			(stroke
				(width 0.1)
				(type default)
			)
			(layer "F.SilkS")
		)
		(fp_line
			(start 21.062188 -1.447546)
			(end 21.035772 -1.364742)
			(stroke
				(width 0.1)
				(type default)
			)
			(layer "F.SilkS")
		)
		(fp_line
			(start 21.069554 -4.109466)
			(end 21.129752 -4.109466)
			(stroke
				(width 0.1)
				(type default)
			)
			(layer "F.SilkS")
		)
		(fp_line
			(start 21.069554 -4.109466)
			(end 21.129752 -4.109466)
			(stroke
				(width 0.1)
				(type default)
			)
			(layer "F.SilkS")
		)
		(fp_line
			(start 21.088858 -1.530604)
			(end 21.062188 -1.447546)
			(stroke
				(width 0.1)
				(type default)
			)
			(layer "F.SilkS")
		)
		(fp_line
			(start 21.088858 -1.530604)
			(end 21.062188 -1.447546)
			(stroke
				(width 0.1)
				(type default)
			)
			(layer "F.SilkS")
		)
		(fp_line
			(start 21.093938 -5.171694)
			(end 19.347942 -3.496564)
			(stroke
				(width 0.1)
				(type default)
			)
			(layer "F.SilkS")
		)
		(fp_line
			(start 21.093938 -5.171694)
			(end 19.347942 -3.496564)
			(stroke
				(width 0.1)
				(type default)
			)
			(layer "F.SilkS")
		)
		(fp_line
			(start 21.093938 -5.171694)
			(end 21.033994 -5.171694)
			(stroke
				(width 0.1)
				(type default)
			)
			(layer "F.SilkS")
		)
		(fp_line
			(start 21.093938 -5.171694)
			(end 21.033994 -5.171694)
			(stroke
				(width 0.1)
				(type default)
			)
			(layer "F.SilkS")
		)
		(fp_line
			(start 21.115274 -1.613916)
			(end 21.088858 -1.530604)
			(stroke
				(width 0.1)
				(type default)
			)
			(layer "F.SilkS")
		)
		(fp_line
			(start 21.115274 -1.613916)
			(end 21.088858 -1.530604)
			(stroke
				(width 0.1)
				(type default)
			)
			(layer "F.SilkS")
		)
		(fp_line
			(start 21.129752 -4.109466)
			(end 21.18995 -4.109466)
			(stroke
				(width 0.1)
				(type default)
			)
			(layer "F.SilkS")
		)
		(fp_line
			(start 21.129752 -4.109466)
			(end 21.18995 -4.109466)
			(stroke
				(width 0.1)
				(type default)
			)
			(layer "F.SilkS")
		)
		(fp_line
			(start 21.141436 -1.69672)
			(end 21.115274 -1.613916)
			(stroke
				(width 0.1)
				(type default)
			)
			(layer "F.SilkS")
		)
		(fp_line
			(start 21.141436 -1.69672)
			(end 21.115274 -1.613916)
			(stroke
				(width 0.1)
				(type default)
			)
			(layer "F.SilkS")
		)
		(fp_line
			(start 21.154136 -5.171694)
			(end 19.33575 -3.427476)
			(stroke
				(width 0.1)
				(type default)
			)
			(layer "F.SilkS")
		)
		(fp_line
			(start 21.154136 -5.171694)
			(end 19.33575 -3.427476)
			(stroke
				(width 0.1)
				(type default)
			)
			(layer "F.SilkS")
		)
		(fp_line
			(start 21.154136 -5.171694)
			(end 21.093938 -5.171694)
			(stroke
				(width 0.1)
				(type default)
			)
			(layer "F.SilkS")
		)
		(fp_line
			(start 21.154136 -5.171694)
			(end 21.093938 -5.171694)
			(stroke
				(width 0.1)
				(type default)
			)
			(layer "F.SilkS")
		)
		(fp_line
			(start 21.167852 -1.779778)
			(end 21.141436 -1.69672)
			(stroke
				(width 0.1)
				(type default)
			)
			(layer "F.SilkS")
		)
		(fp_line
			(start 21.167852 -1.779778)
			(end 21.141436 -1.69672)
			(stroke
				(width 0.1)
				(type default)
			)
			(layer "F.SilkS")
		)
		(fp_line
			(start 21.18995 -4.109466)
			(end 21.250402 -4.109466)
			(stroke
				(width 0.1)
				(type default)
			)
			(layer "F.SilkS")
		)
		(fp_line
			(start 21.18995 -4.109466)
			(end 21.250402 -4.109466)
			(stroke
				(width 0.1)
				(type default)
			)
			(layer "F.SilkS")
		)
		(fp_line
			(start 21.194268 -1.862836)
			(end 21.167852 -1.779778)
			(stroke
				(width 0.1)
				(type default)
			)
			(layer "F.SilkS")
		)
		(fp_line
			(start 21.194268 -1.862836)
			(end 21.167852 -1.779778)
			(stroke
				(width 0.1)
				(type default)
			)
			(layer "F.SilkS")
		)
		(fp_line
			(start 21.21408 -5.171694)
			(end 19.323558 -3.358134)
			(stroke
				(width 0.1)
				(type default)
			)
			(layer "F.SilkS")
		)
		(fp_line
			(start 21.21408 -5.171694)
			(end 19.323558 -3.358134)
			(stroke
				(width 0.1)
				(type default)
			)
			(layer "F.SilkS")
		)
		(fp_line
			(start 21.21408 -5.171694)
			(end 21.154136 -5.171694)
			(stroke
				(width 0.1)
				(type default)
			)
			(layer "F.SilkS")
		)
		(fp_line
			(start 21.21408 -5.171694)
			(end 21.154136 -5.171694)
			(stroke
				(width 0.1)
				(type default)
			)
			(layer "F.SilkS")
		)
		(fp_line
			(start 21.220684 -1.946148)
			(end 21.194268 -1.862836)
			(stroke
				(width 0.1)
				(type default)
			)
			(layer "F.SilkS")
		)
		(fp_line
			(start 21.220684 -1.946148)
			(end 21.194268 -1.862836)
			(stroke
				(width 0.1)
				(type default)
			)
			(layer "F.SilkS")
		)
		(fp_line
			(start 21.2471 -2.028952)
			(end 21.220684 -1.946148)
			(stroke
				(width 0.1)
				(type default)
			)
			(layer "F.SilkS")
		)
		(fp_line
			(start 21.2471 -2.028952)
			(end 21.220684 -1.946148)
			(stroke
				(width 0.1)
				(type default)
			)
			(layer "F.SilkS")
		)
		(fp_line
			(start 21.250402 -4.109466)
			(end 21.310346 -4.109466)
			(stroke
				(width 0.1)
				(type default)
			)
			(layer "F.SilkS")
		)
		(fp_line
			(start 21.250402 -4.109466)
			(end 21.310346 -4.109466)
			(stroke
				(width 0.1)
				(type default)
			)
			(layer "F.SilkS")
		)
		(fp_line
			(start 21.273516 -2.11201)
			(end 21.2471 -2.028952)
			(stroke
				(width 0.1)
				(type default)
			)
			(layer "F.SilkS")
		)
		(fp_line
			(start 21.273516 -2.11201)
			(end 21.2471 -2.028952)
			(stroke
				(width 0.1)
				(type default)
			)
			(layer "F.SilkS")
		)
		(fp_line
			(start 21.274532 -5.171694)
			(end 19.311366 -3.288538)
			(stroke
				(width 0.1)
				(type default)
			)
			(layer "F.SilkS")
		)
		(fp_line
			(start 21.274532 -5.171694)
			(end 19.311366 -3.288538)
			(stroke
				(width 0.1)
				(type default)
			)
			(layer "F.SilkS")
		)
		(fp_line
			(start 21.274532 -5.171694)
			(end 21.21408 -5.171694)
			(stroke
				(width 0.1)
				(type default)
			)
			(layer "F.SilkS")
		)
		(fp_line
			(start 21.274532 -5.171694)
			(end 21.21408 -5.171694)
			(stroke
				(width 0.1)
				(type default)
			)
			(layer "F.SilkS")
		)
		(fp_line
			(start 21.299932 -2.195068)
			(end 21.273516 -2.11201)
			(stroke
				(width 0.1)
				(type default)
			)
			(layer "F.SilkS")
		)
		(fp_line
			(start 21.299932 -2.195068)
			(end 21.273516 -2.11201)
			(stroke
				(width 0.1)
				(type default)
			)
			(layer "F.SilkS")
		)
		(fp_line
			(start 21.310346 -4.109466)
			(end 21.370544 -4.109466)
			(stroke
				(width 0.1)
				(type default)
			)
			(layer "F.SilkS")
		)
		(fp_line
			(start 21.310346 -4.109466)
			(end 21.370544 -4.109466)
			(stroke
				(width 0.1)
				(type default)
			)
			(layer "F.SilkS")
		)
		(fp_line
			(start 21.33473 -5.171694)
			(end 19.299428 -3.218942)
			(stroke
				(width 0.1)
				(type default)
			)
			(layer "F.SilkS")
		)
		(fp_line
			(start 21.33473 -5.171694)
			(end 19.299428 -3.218942)
			(stroke
				(width 0.1)
				(type default)
			)
			(layer "F.SilkS")
		)
		(fp_line
			(start 21.33473 -5.171694)
			(end 21.274532 -5.171694)
			(stroke
				(width 0.1)
				(type default)
			)
			(layer "F.SilkS")
		)
		(fp_line
			(start 21.33473 -5.171694)
			(end 21.274532 -5.171694)
			(stroke
				(width 0.1)
				(type default)
			)
			(layer "F.SilkS")
		)
		(fp_line
			(start 21.370544 -4.109466)
			(end 21.430742 -4.109466)
			(stroke
				(width 0.1)
				(type default)
			)
			(layer "F.SilkS")
		)
		(fp_line
			(start 21.370544 -4.109466)
			(end 21.430742 -4.109466)
			(stroke
				(width 0.1)
				(type default)
			)
			(layer "F.SilkS")
		)
		(fp_line
			(start 21.394674 -5.171694)
			(end 19.286982 -3.149854)
			(stroke
				(width 0.1)
				(type default)
			)
			(layer "F.SilkS")
		)
		(fp_line
			(start 21.394674 -5.171694)
			(end 19.286982 -3.149854)
			(stroke
				(width 0.1)
				(type default)
			)
			(layer "F.SilkS")
		)
		(fp_line
			(start 21.394674 -5.171694)
			(end 21.33473 -5.171694)
			(stroke
				(width 0.1)
				(type default)
			)
			(layer "F.SilkS")
		)
		(fp_line
			(start 21.394674 -5.171694)
			(end 21.33473 -5.171694)
			(stroke
				(width 0.1)
				(type default)
			)
			(layer "F.SilkS")
		)
		(fp_line
			(start 21.430742 -4.109466)
			(end 21.490686 -4.109466)
			(stroke
				(width 0.1)
				(type default)
			)
			(layer "F.SilkS")
		)
		(fp_line
			(start 21.430742 -4.109466)
			(end 21.490686 -4.109466)
			(stroke
				(width 0.1)
				(type default)
			)
			(layer "F.SilkS")
		)
		(fp_line
			(start 21.454872 -5.171694)
			(end 19.27479 -3.080512)
			(stroke
				(width 0.1)
				(type default)
			)
			(layer "F.SilkS")
		)
		(fp_line
			(start 21.454872 -5.171694)
			(end 19.27479 -3.080512)
			(stroke
				(width 0.1)
				(type default)
			)
			(layer "F.SilkS")
		)
		(fp_line
			(start 21.454872 -5.171694)
			(end 21.394674 -5.171694)
			(stroke
				(width 0.1)
				(type default)
			)
			(layer "F.SilkS")
		)
		(fp_line
			(start 21.454872 -5.171694)
			(end 21.394674 -5.171694)
			(stroke
				(width 0.1)
				(type default)
			)
			(layer "F.SilkS")
		)
		(fp_line
			(start 21.490686 -4.109466)
			(end 21.55063 -4.109466)
			(stroke
				(width 0.1)
				(type default)
			)
			(layer "F.SilkS")
		)
		(fp_line
			(start 21.490686 -4.109466)
			(end 21.55063 -4.109466)
			(stroke
				(width 0.1)
				(type default)
			)
			(layer "F.SilkS")
		)
		(fp_line
			(start 21.515324 -5.171694)
			(end 19.262852 -3.01117)
			(stroke
				(width 0.1)
				(type default)
			)
			(layer "F.SilkS")
		)
		(fp_line
			(start 21.515324 -5.171694)
			(end 19.262852 -3.01117)
			(stroke
				(width 0.1)
				(type default)
			)
			(layer "F.SilkS")
		)
		(fp_line
			(start 21.515324 -5.171694)
			(end 21.454872 -5.171694)
			(stroke
				(width 0.1)
				(type default)
			)
			(layer "F.SilkS")
		)
		(fp_line
			(start 21.515324 -5.171694)
			(end 21.454872 -5.171694)
			(stroke
				(width 0.1)
				(type default)
			)
			(layer "F.SilkS")
		)
		(fp_line
			(start 21.55063 -4.109466)
			(end 21.611082 -4.109466)
			(stroke
				(width 0.1)
				(type default)
			)
			(layer "F.SilkS")
		)
		(fp_line
			(start 21.55063 -4.109466)
			(end 21.611082 -4.109466)
			(stroke
				(width 0.1)
				(type default)
			)
			(layer "F.SilkS")
		)
		(fp_line
			(start 21.575522 -5.171694)
			(end 19.250406 -2.941574)
			(stroke
				(width 0.1)
				(type default)
			)
			(layer "F.SilkS")
		)
		(fp_line
			(start 21.575522 -5.171694)
			(end 19.250406 -2.941574)
			(stroke
				(width 0.1)
				(type default)
			)
			(layer "F.SilkS")
		)
		(fp_line
			(start 21.575522 -5.171694)
			(end 21.515324 -5.171694)
			(stroke
				(width 0.1)
				(type default)
			)
			(layer "F.SilkS")
		)
		(fp_line
			(start 21.575522 -5.171694)
			(end 21.515324 -5.171694)
			(stroke
				(width 0.1)
				(type default)
			)
			(layer "F.SilkS")
		)
		(fp_line
			(start 21.612352 -4.109466)
			(end 21.611082 -4.109466)
			(stroke
				(width 0.1)
				(type default)
			)
			(layer "F.SilkS")
		)
		(fp_line
			(start 21.612352 -4.109466)
			(end 21.611082 -4.109466)
			(stroke
				(width 0.1)
				(type default)
			)
			(layer "F.SilkS")
		)
		(fp_line
			(start 21.61286 -4.11099)
			(end 21.611082 -4.109466)
			(stroke
				(width 0.1)
				(type default)
			)
			(layer "F.SilkS")
		)
		(fp_line
			(start 21.61286 -4.11099)
			(end 21.611082 -4.109466)
			(stroke
				(width 0.1)
				(type default)
			)
			(layer "F.SilkS")
		)
		(fp_line
			(start 21.61286 -4.11099)
			(end 21.612352 -4.109466)
			(stroke
				(width 0.1)
				(type default)
			)
			(layer "F.SilkS")
		)
		(fp_line
			(start 21.61286 -4.11099)
			(end 21.612352 -4.109466)
			(stroke
				(width 0.1)
				(type default)
			)
			(layer "F.SilkS")
		)
		(fp_line
			(start 21.61286 -4.11099)
			(end 21.624798 -4.180586)
			(stroke
				(width 0.1)
				(type default)
			)
			(layer "F.SilkS")
		)
		(fp_line
			(start 21.61286 -4.11099)
			(end 21.624798 -4.180586)
			(stroke
				(width 0.1)
				(type default)
			)
			(layer "F.SilkS")
		)
		(fp_line
			(start 21.624798 -4.180586)
			(end 21.55063 -4.109466)
			(stroke
				(width 0.1)
				(type default)
			)
			(layer "F.SilkS")
		)
		(fp_line
			(start 21.624798 -4.180586)
			(end 21.55063 -4.109466)
			(stroke
				(width 0.1)
				(type default)
			)
			(layer "F.SilkS")
		)
		(fp_line
			(start 21.624798 -4.180586)
			(end 21.636736 -4.249674)
			(stroke
				(width 0.1)
				(type default)
			)
			(layer "F.SilkS")
		)
		(fp_line
			(start 21.624798 -4.180586)
			(end 21.636736 -4.249674)
			(stroke
				(width 0.1)
				(type default)
			)
			(layer "F.SilkS")
		)
		(fp_line
			(start 21.635466 -5.171694)
			(end 21.575522 -5.171694)
			(stroke
				(width 0.1)
				(type default)
			)
			(layer "F.SilkS")
		)
		(fp_line
			(start 21.635466 -5.171694)
			(end 21.575522 -5.171694)
			(stroke
				(width 0.1)
				(type default)
			)
			(layer "F.SilkS")
		)
		(fp_line
			(start 21.636736 -4.249674)
			(end 21.490686 -4.109466)
			(stroke
				(width 0.1)
				(type default)
			)
			(layer "F.SilkS")
		)
		(fp_line
			(start 21.636736 -4.249674)
			(end 21.490686 -4.109466)
			(stroke
				(width 0.1)
				(type default)
			)
			(layer "F.SilkS")
		)
		(fp_line
			(start 21.636736 -4.249674)
			(end 21.649182 -4.319016)
			(stroke
				(width 0.1)
				(type default)
			)
			(layer "F.SilkS")
		)
		(fp_line
			(start 21.636736 -4.249674)
			(end 21.649182 -4.319016)
			(stroke
				(width 0.1)
				(type default)
			)
			(layer "F.SilkS")
		)
		(fp_line
			(start 21.649182 -4.319016)
			(end 21.430742 -4.109466)
			(stroke
				(width 0.1)
				(type default)
			)
			(layer "F.SilkS")
		)
		(fp_line
			(start 21.649182 -4.319016)
			(end 21.430742 -4.109466)
			(stroke
				(width 0.1)
				(type default)
			)
			(layer "F.SilkS")
		)
		(fp_line
			(start 21.649182 -4.319016)
			(end 21.661374 -4.388358)
			(stroke
				(width 0.1)
				(type default)
			)
			(layer "F.SilkS")
		)
		(fp_line
			(start 21.649182 -4.319016)
			(end 21.661374 -4.388358)
			(stroke
				(width 0.1)
				(type default)
			)
			(layer "F.SilkS")
		)
		(fp_line
			(start 21.661374 -4.388358)
			(end 21.370544 -4.109466)
			(stroke
				(width 0.1)
				(type default)
			)
			(layer "F.SilkS")
		)
		(fp_line
			(start 21.661374 -4.388358)
			(end 21.370544 -4.109466)
			(stroke
				(width 0.1)
				(type default)
			)
			(layer "F.SilkS")
		)
		(fp_line
			(start 21.661374 -4.388358)
			(end 21.673312 -4.457954)
			(stroke
				(width 0.1)
				(type default)
			)
			(layer "F.SilkS")
		)
		(fp_line
			(start 21.661374 -4.388358)
			(end 21.673312 -4.457954)
			(stroke
				(width 0.1)
				(type default)
			)
			(layer "F.SilkS")
		)
		(fp_line
			(start 21.673312 -4.457954)
			(end 21.310346 -4.109466)
			(stroke
				(width 0.1)
				(type default)
			)
			(layer "F.SilkS")
		)
		(fp_line
			(start 21.673312 -4.457954)
			(end 21.310346 -4.109466)
			(stroke
				(width 0.1)
				(type default)
			)
			(layer "F.SilkS")
		)
		(fp_line
			(start 21.673312 -4.457954)
			(end 21.685504 -4.527296)
			(stroke
				(width 0.1)
				(type default)
			)
			(layer "F.SilkS")
		)
		(fp_line
			(start 21.673312 -4.457954)
			(end 21.685504 -4.527296)
			(stroke
				(width 0.1)
				(type default)
			)
			(layer "F.SilkS")
		)
		(fp_line
			(start 21.685504 -4.527296)
			(end 21.250402 -4.109466)
			(stroke
				(width 0.1)
				(type default)
			)
			(layer "F.SilkS")
		)
		(fp_line
			(start 21.685504 -4.527296)
			(end 21.250402 -4.109466)
			(stroke
				(width 0.1)
				(type default)
			)
			(layer "F.SilkS")
		)
		(fp_line
			(start 21.685504 -4.527296)
			(end 21.69795 -4.596638)
			(stroke
				(width 0.1)
				(type default)
			)
			(layer "F.SilkS")
		)
		(fp_line
			(start 21.685504 -4.527296)
			(end 21.69795 -4.596638)
			(stroke
				(width 0.1)
				(type default)
			)
			(layer "F.SilkS")
		)
		(fp_line
			(start 21.69541 -5.171694)
			(end 20.588224 -4.109466)
			(stroke
				(width 0.1)
				(type default)
			)
			(layer "F.SilkS")
		)
		(fp_line
			(start 21.69541 -5.171694)
			(end 20.588224 -4.109466)
			(stroke
				(width 0.1)
				(type default)
			)
			(layer "F.SilkS")
		)
		(fp_line
			(start 21.69541 -5.171694)
			(end 21.635466 -5.171694)
			(stroke
				(width 0.1)
				(type default)
			)
			(layer "F.SilkS")
		)
		(fp_line
			(start 21.69541 -5.171694)
			(end 21.635466 -5.171694)
			(stroke
				(width 0.1)
				(type default)
			)
			(layer "F.SilkS")
		)
		(fp_line
			(start 21.69795 -4.596638)
			(end 21.18995 -4.109466)
			(stroke
				(width 0.1)
				(type default)
			)
			(layer "F.SilkS")
		)
		(fp_line
			(start 21.69795 -4.596638)
			(end 21.18995 -4.109466)
			(stroke
				(width 0.1)
				(type default)
			)
			(layer "F.SilkS")
		)
		(fp_line
			(start 21.69795 -4.596638)
			(end 21.709888 -4.66598)
			(stroke
				(width 0.1)
				(type default)
			)
			(layer "F.SilkS")
		)
		(fp_line
			(start 21.69795 -4.596638)
			(end 21.709888 -4.66598)
			(stroke
				(width 0.1)
				(type default)
			)
			(layer "F.SilkS")
		)
		(fp_line
			(start 21.709888 -4.66598)
			(end 21.129752 -4.109466)
			(stroke
				(width 0.1)
				(type default)
			)
			(layer "F.SilkS")
		)
		(fp_line
			(start 21.709888 -4.66598)
			(end 21.129752 -4.109466)
			(stroke
				(width 0.1)
				(type default)
			)
			(layer "F.SilkS")
		)
		(fp_line
			(start 21.709888 -4.66598)
			(end 21.721826 -4.735576)
			(stroke
				(width 0.1)
				(type default)
			)
			(layer "F.SilkS")
		)
		(fp_line
			(start 21.709888 -4.66598)
			(end 21.721826 -4.735576)
			(stroke
				(width 0.1)
				(type default)
			)
			(layer "F.SilkS")
		)
		(fp_line
			(start 21.721826 -4.735576)
			(end 21.069554 -4.109466)
			(stroke
				(width 0.1)
				(type default)
			)
			(layer "F.SilkS")
		)
		(fp_line
			(start 21.721826 -4.735576)
			(end 21.069554 -4.109466)
			(stroke
				(width 0.1)
				(type default)
			)
			(layer "F.SilkS")
		)
		(fp_line
			(start 21.721826 -4.735576)
			(end 21.734018 -4.804664)
			(stroke
				(width 0.1)
				(type default)
			)
			(layer "F.SilkS")
		)
		(fp_line
			(start 21.721826 -4.735576)
			(end 21.734018 -4.804664)
			(stroke
				(width 0.1)
				(type default)
			)
			(layer "F.SilkS")
		)
		(fp_line
			(start 21.734018 -4.804664)
			(end 21.00961 -4.109466)
			(stroke
				(width 0.1)
				(type default)
			)
			(layer "F.SilkS")
		)
		(fp_line
			(start 21.734018 -4.804664)
			(end 21.00961 -4.109466)
			(stroke
				(width 0.1)
				(type default)
			)
			(layer "F.SilkS")
		)
		(fp_line
			(start 21.734018 -4.804664)
			(end 21.746464 -4.874006)
			(stroke
				(width 0.1)
				(type default)
			)
			(layer "F.SilkS")
		)
		(fp_line
			(start 21.734018 -4.804664)
			(end 21.746464 -4.874006)
			(stroke
				(width 0.1)
				(type default)
			)
			(layer "F.SilkS")
		)
		(fp_line
			(start 21.746464 -4.874006)
			(end 20.949666 -4.109466)
			(stroke
				(width 0.1)
				(type default)
			)
			(layer "F.SilkS")
		)
		(fp_line
			(start 21.746464 -4.874006)
			(end 20.949666 -4.109466)
			(stroke
				(width 0.1)
				(type default)
			)
			(layer "F.SilkS")
		)
		(fp_line
			(start 21.746464 -4.874006)
			(end 21.758402 -4.943348)
			(stroke
				(width 0.1)
				(type default)
			)
			(layer "F.SilkS")
		)
		(fp_line
			(start 21.746464 -4.874006)
			(end 21.758402 -4.943348)
			(stroke
				(width 0.1)
				(type default)
			)
			(layer "F.SilkS")
		)
		(fp_line
			(start 21.755608 -5.171694)
			(end 20.648422 -4.109466)
			(stroke
				(width 0.1)
				(type default)
			)
			(layer "F.SilkS")
		)
		(fp_line
			(start 21.755608 -5.171694)
			(end 20.648422 -4.109466)
			(stroke
				(width 0.1)
				(type default)
			)
			(layer "F.SilkS")
		)
		(fp_line
			(start 21.755608 -5.171694)
			(end 21.69541 -5.171694)
			(stroke
				(width 0.1)
				(type default)
			)
			(layer "F.SilkS")
		)
		(fp_line
			(start 21.755608 -5.171694)
			(end 21.69541 -5.171694)
			(stroke
				(width 0.1)
				(type default)
			)
			(layer "F.SilkS")
		)
		(fp_line
			(start 21.758402 -4.943348)
			(end 20.889214 -4.109466)
			(stroke
				(width 0.1)
				(type default)
			)
			(layer "F.SilkS")
		)
		(fp_line
			(start 21.758402 -4.943348)
			(end 20.889214 -4.109466)
			(stroke
				(width 0.1)
				(type default)
			)
			(layer "F.SilkS")
		)
		(fp_line
			(start 21.758402 -4.943348)
			(end 21.770594 -5.012944)
			(stroke
				(width 0.1)
				(type default)
			)
			(layer "F.SilkS")
		)
		(fp_line
			(start 21.758402 -4.943348)
			(end 21.770594 -5.012944)
			(stroke
				(width 0.1)
				(type default)
			)
			(layer "F.SilkS")
		)
		(fp_line
			(start 21.770594 -5.012944)
			(end 20.829016 -4.109466)
			(stroke
				(width 0.1)
				(type default)
			)
			(layer "F.SilkS")
		)
		(fp_line
			(start 21.770594 -5.012944)
			(end 20.829016 -4.109466)
			(stroke
				(width 0.1)
				(type default)
			)
			(layer "F.SilkS")
		)
		(fp_line
			(start 21.770594 -5.012944)
			(end 21.78304 -5.082032)
			(stroke
				(width 0.1)
				(type default)
			)
			(layer "F.SilkS")
		)
		(fp_line
			(start 21.770594 -5.012944)
			(end 21.78304 -5.082032)
			(stroke
				(width 0.1)
				(type default)
			)
			(layer "F.SilkS")
		)
		(fp_line
			(start 21.78304 -5.082032)
			(end 20.768564 -4.109466)
			(stroke
				(width 0.1)
				(type default)
			)
			(layer "F.SilkS")
		)
		(fp_line
			(start 21.78304 -5.082032)
			(end 20.768564 -4.109466)
			(stroke
				(width 0.1)
				(type default)
			)
			(layer "F.SilkS")
		)
		(fp_line
			(start 21.78304 -5.082032)
			(end 21.794978 -5.151374)
			(stroke
				(width 0.1)
				(type default)
			)
			(layer "F.SilkS")
		)
		(fp_line
			(start 21.78304 -5.082032)
			(end 21.794978 -5.151374)
			(stroke
				(width 0.1)
				(type default)
			)
			(layer "F.SilkS")
		)
		(fp_line
			(start 21.794978 -5.151374)
			(end 20.70862 -4.109466)
			(stroke
				(width 0.1)
				(type default)
			)
			(layer "F.SilkS")
		)
		(fp_line
			(start 21.794978 -5.151374)
			(end 20.70862 -4.109466)
			(stroke
				(width 0.1)
				(type default)
			)
			(layer "F.SilkS")
		)
		(fp_line
			(start 21.794978 -5.151374)
			(end 21.798534 -5.171694)
			(stroke
				(width 0.1)
				(type default)
			)
			(layer "F.SilkS")
		)
		(fp_line
			(start 21.794978 -5.151374)
			(end 21.798534 -5.171694)
			(stroke
				(width 0.1)
				(type default)
			)
			(layer "F.SilkS")
		)
		(fp_line
			(start 21.798534 -5.171694)
			(end 21.755608 -5.171694)
			(stroke
				(width 0.1)
				(type default)
			)
			(layer "F.SilkS")
		)
		(fp_line
			(start 21.798534 -5.171694)
			(end 21.755608 -5.171694)
			(stroke
				(width 0.1)
				(type default)
			)
			(layer "F.SilkS")
		)
		(fp_line
			(start 21.838158 -2.018792)
			(end 23.619206 -3.727196)
			(stroke
				(width 0.1)
				(type default)
			)
			(layer "F.SilkS")
		)
		(fp_line
			(start 21.838158 -2.018792)
			(end 23.619206 -3.727196)
			(stroke
				(width 0.1)
				(type default)
			)
			(layer "F.SilkS")
		)
		(fp_line
			(start 21.839428 -2.07772)
			(end 23.55469 -3.723386)
			(stroke
				(width 0.1)
				(type default)
			)
			(layer "F.SilkS")
		)
		(fp_line
			(start 21.839428 -2.07772)
			(end 23.55469 -3.723386)
			(stroke
				(width 0.1)
				(type default)
			)
			(layer "F.SilkS")
		)
		(fp_line
			(start 21.841206 -2.137156)
			(end 23.489666 -3.71856)
			(stroke
				(width 0.1)
				(type default)
			)
			(layer "F.SilkS")
		)
		(fp_line
			(start 21.841206 -2.137156)
			(end 23.489666 -3.71856)
			(stroke
				(width 0.1)
				(type default)
			)
			(layer "F.SilkS")
		)
		(fp_line
			(start 21.841206 -1.90627)
			(end 23.747984 -3.735324)
			(stroke
				(width 0.1)
				(type default)
			)
			(layer "F.SilkS")
		)
		(fp_line
			(start 21.841206 -1.90627)
			(end 23.747984 -3.735324)
			(stroke
				(width 0.1)
				(type default)
			)
			(layer "F.SilkS")
		)
		(fp_line
			(start 21.846032 -1.853184)
			(end 23.811992 -3.739388)
			(stroke
				(width 0.1)
				(type default)
			)
			(layer "F.SilkS")
		)
		(fp_line
			(start 21.846032 -1.853184)
			(end 23.811992 -3.739388)
			(stroke
				(width 0.1)
				(type default)
			)
			(layer "F.SilkS")
		)
		(fp_line
			(start 21.849334 -2.202942)
			(end 23.414228 -3.703828)
			(stroke
				(width 0.1)
				(type default)
			)
			(layer "F.SilkS")
		)
		(fp_line
			(start 21.849334 -2.202942)
			(end 23.414228 -3.703828)
			(stroke
				(width 0.1)
				(type default)
			)
			(layer "F.SilkS")
		)
		(fp_line
			(start 21.850858 -1.799844)
			(end 23.874222 -3.740912)
			(stroke
				(width 0.1)
				(type default)
			)
			(layer "F.SilkS")
		)
		(fp_line
			(start 21.850858 -1.799844)
			(end 23.874222 -3.740912)
			(stroke
				(width 0.1)
				(type default)
			)
			(layer "F.SilkS")
		)
		(fp_line
			(start 21.85797 -2.268728)
			(end 23.338282 -3.688842)
			(stroke
				(width 0.1)
				(type default)
			)
			(layer "F.SilkS")
		)
		(fp_line
			(start 21.85797 -2.268728)
			(end 23.338282 -3.688842)
			(stroke
				(width 0.1)
				(type default)
			)
			(layer "F.SilkS")
		)
		(fp_line
			(start 21.86051 -1.75133)
			(end 23.930864 -3.737864)
			(stroke
				(width 0.1)
				(type default)
			)
			(layer "F.SilkS")
		)
		(fp_line
			(start 21.86051 -1.75133)
			(end 23.930864 -3.737864)
			(stroke
				(width 0.1)
				(type default)
			)
			(layer "F.SilkS")
		)
		(fp_line
			(start 21.869146 -2.337308)
			(end 23.26259 -3.673856)
			(stroke
				(width 0.1)
				(type default)
			)
			(layer "F.SilkS")
		)
		(fp_line
			(start 21.869146 -2.337308)
			(end 23.26259 -3.673856)
			(stroke
				(width 0.1)
				(type default)
			)
			(layer "F.SilkS")
		)
		(fp_line
			(start 21.870416 -1.703578)
			(end 23.98776 -3.734816)
			(stroke
				(width 0.1)
				(type default)
			)
			(layer "F.SilkS")
		)
		(fp_line
			(start 21.870416 -1.703578)
			(end 23.98776 -3.734816)
			(stroke
				(width 0.1)
				(type default)
			)
			(layer "F.SilkS")
		)
		(fp_line
			(start 21.88083 -1.655826)
			(end 24.04491 -3.731768)
			(stroke
				(width 0.1)
				(type default)
			)
			(layer "F.SilkS")
		)
		(fp_line
			(start 21.88083 -1.655826)
			(end 24.04491 -3.731768)
			(stroke
				(width 0.1)
				(type default)
			)
			(layer "F.SilkS")
		)
		(fp_line
			(start 21.89099 -2.416048)
			(end 23.187152 -3.659124)
			(stroke
				(width 0.1)
				(type default)
			)
			(layer "F.SilkS")
		)
		(fp_line
			(start 21.89099 -2.416048)
			(end 23.187152 -3.659124)
			(stroke
				(width 0.1)
				(type default)
			)
			(layer "F.SilkS")
		)
		(fp_line
			(start 21.894546 -1.611376)
			(end 24.101806 -3.728974)
			(stroke
				(width 0.1)
				(type default)
			)
			(layer "F.SilkS")
		)
		(fp_line
			(start 21.894546 -1.611376)
			(end 24.101806 -3.728974)
			(stroke
				(width 0.1)
				(type default)
			)
			(layer "F.SilkS")
		)
		(fp_line
			(start 21.909786 -1.568196)
			(end 24.154892 -3.721862)
			(stroke
				(width 0.1)
				(type default)
			)
			(layer "F.SilkS")
		)
		(fp_line
			(start 21.909786 -1.568196)
			(end 24.154892 -3.721862)
			(stroke
				(width 0.1)
				(type default)
			)
			(layer "F.SilkS")
		)
		(fp_line
			(start 21.913088 -2.494788)
			(end 23.10003 -3.63347)
			(stroke
				(width 0.1)
				(type default)
			)
			(layer "F.SilkS")
		)
		(fp_line
			(start 21.913088 -2.494788)
			(end 23.10003 -3.63347)
			(stroke
				(width 0.1)
				(type default)
			)
			(layer "F.SilkS")
		)
		(fp_line
			(start 21.924772 -1.525016)
			(end 24.205946 -3.712972)
			(stroke
				(width 0.1)
				(type default)
			)
			(layer "F.SilkS")
		)
		(fp_line
			(start 21.924772 -1.525016)
			(end 24.205946 -3.712972)
			(stroke
				(width 0.1)
				(type default)
			)
			(layer "F.SilkS")
		)
		(fp_line
			(start 21.93544 -2.573782)
			(end 23.00478 -3.599942)
			(stroke
				(width 0.1)
				(type default)
			)
			(layer "F.SilkS")
		)
		(fp_line
			(start 21.93544 -2.573782)
			(end 23.00478 -3.599942)
			(stroke
				(width 0.1)
				(type default)
			)
			(layer "F.SilkS")
		)
		(fp_line
			(start 21.942806 -1.484376)
			(end 23.220934 -2.710688)
			(stroke
				(width 0.1)
				(type default)
			)
			(layer "F.SilkS")
		)
		(fp_line
			(start 21.942806 -1.484376)
			(end 23.220934 -2.710688)
			(stroke
				(width 0.1)
				(type default)
			)
			(layer "F.SilkS")
		)
		(fp_line
			(start 21.957538 -2.652776)
			(end 22.909784 -3.56616)
			(stroke
				(width 0.1)
				(type default)
			)
			(layer "F.SilkS")
		)
		(fp_line
			(start 21.957538 -2.652776)
			(end 22.909784 -3.56616)
			(stroke
				(width 0.1)
				(type default)
			)
			(layer "F.SilkS")
		)
		(fp_line
			(start 21.962364 -1.445514)
			(end 23.052786 -2.491486)
			(stroke
				(width 0.1)
				(type default)
			)
			(layer "F.SilkS")
		)
		(fp_line
			(start 21.962364 -1.445514)
			(end 23.052786 -2.491486)
			(stroke
				(width 0.1)
				(type default)
			)
			(layer "F.SilkS")
		)
		(fp_line
			(start 21.981922 -1.406652)
			(end 23.020782 -2.403094)
			(stroke
				(width 0.1)
				(type default)
			)
			(layer "F.SilkS")
		)
		(fp_line
			(start 21.981922 -1.406652)
			(end 23.020782 -2.403094)
			(stroke
				(width 0.1)
				(type default)
			)
			(layer "F.SilkS")
		)
		(fp_line
			(start 22.003004 -1.36906)
			(end 22.99081 -2.31648)
			(stroke
				(width 0.1)
				(type default)
			)
			(layer "F.SilkS")
		)
		(fp_line
			(start 22.003004 -1.36906)
			(end 22.99081 -2.31648)
			(stroke
				(width 0.1)
				(type default)
			)
			(layer "F.SilkS")
		)
		(fp_line
			(start 22.017228 -2.767838)
			(end 22.802342 -3.521202)
			(stroke
				(width 0.1)
				(type default)
			)
			(layer "F.SilkS")
		)
		(fp_line
			(start 22.017228 -2.767838)
			(end 22.802342 -3.521202)
			(stroke
				(width 0.1)
				(type default)
			)
			(layer "F.SilkS")
		)
		(fp_line
			(start 22.02688 -1.334262)
			(end 22.984206 -2.252726)
			(stroke
				(width 0.1)
				(type default)
			)
			(layer "F.SilkS")
		)
		(fp_line
			(start 22.02688 -1.334262)
			(end 22.984206 -2.252726)
			(stroke
				(width 0.1)
				(type default)
			)
			(layer "F.SilkS")
		)
		(fp_line
			(start 22.05101 -1.299464)
			(end 22.981158 -2.19202)
			(stroke
				(width 0.1)
				(type default)
			)
			(layer "F.SilkS")
		)
		(fp_line
			(start 22.05101 -1.299464)
			(end 22.981158 -2.19202)
			(stroke
				(width 0.1)
				(type default)
			)
			(layer "F.SilkS")
		)
		(fp_line
			(start 22.07514 -1.265174)
			(end 22.985222 -2.137918)
			(stroke
				(width 0.1)
				(type default)
			)
			(layer "F.SilkS")
		)
		(fp_line
			(start 22.07514 -1.265174)
			(end 22.985222 -2.137918)
			(stroke
				(width 0.1)
				(type default)
			)
			(layer "F.SilkS")
		)
		(fp_line
			(start 22.077934 -2.883408)
			(end 22.662896 -3.444748)
			(stroke
				(width 0.1)
				(type default)
			)
			(layer "F.SilkS")
		)
		(fp_line
			(start 22.077934 -2.883408)
			(end 22.662896 -3.444748)
			(stroke
				(width 0.1)
				(type default)
			)
			(layer "F.SilkS")
		)
		(fp_line
			(start 22.10308 -1.233932)
			(end 22.992588 -2.087372)
			(stroke
				(width 0.1)
				(type default)
			)
			(layer "F.SilkS")
		)
		(fp_line
			(start 22.10308 -1.233932)
			(end 22.992588 -2.087372)
			(stroke
				(width 0.1)
				(type default)
			)
			(layer "F.SilkS")
		)
		(fp_line
			(start 22.130512 -1.202944)
			(end 23.005542 -2.042414)
			(stroke
				(width 0.1)
				(type default)
			)
			(layer "F.SilkS")
		)
		(fp_line
			(start 22.130512 -1.202944)
			(end 23.005542 -2.042414)
			(stroke
				(width 0.1)
				(type default)
			)
			(layer "F.SilkS")
		)
		(fp_line
			(start 22.158452 -1.171956)
			(end 23.020782 -1.99898)
			(stroke
				(width 0.1)
				(type default)
			)
			(layer "F.SilkS")
		)
		(fp_line
			(start 22.158452 -1.171956)
			(end 23.020782 -1.99898)
			(stroke
				(width 0.1)
				(type default)
			)
			(layer "F.SilkS")
		)
		(fp_line
			(start 22.18944 -1.143762)
			(end 23.042372 -1.96215)
			(stroke
				(width 0.1)
				(type default)
			)
			(layer "F.SilkS")
		)
		(fp_line
			(start 22.18944 -1.143762)
			(end 23.042372 -1.96215)
			(stroke
				(width 0.1)
				(type default)
			)
			(layer "F.SilkS")
		)
		(fp_line
			(start 22.22119 -1.11633)
			(end 23.06447 -1.925828)
			(stroke
				(width 0.1)
				(type default)
			)
			(layer "F.SilkS")
		)
		(fp_line
			(start 22.22119 -1.11633)
			(end 23.06447 -1.925828)
			(stroke
				(width 0.1)
				(type default)
			)
			(layer "F.SilkS")
		)
		(fp_line
			(start 22.252432 -1.089152)
			(end 23.094188 -1.896364)
			(stroke
				(width 0.1)
				(type default)
			)
			(layer "F.SilkS")
		)
		(fp_line
			(start 22.252432 -1.089152)
			(end 23.094188 -1.896364)
			(stroke
				(width 0.1)
				(type default)
			)
			(layer "F.SilkS")
		)
		(fp_line
			(start 22.286214 -1.063752)
			(end 23.124414 -1.867916)
			(stroke
				(width 0.1)
				(type default)
			)
			(layer "F.SilkS")
		)
		(fp_line
			(start 22.286214 -1.063752)
			(end 23.124414 -1.867916)
			(stroke
				(width 0.1)
				(type default)
			)
			(layer "F.SilkS")
		)
		(fp_line
			(start 22.321774 -1.039622)
			(end 23.158196 -1.842262)
			(stroke
				(width 0.1)
				(type default)
			)
			(layer "F.SilkS")
		)
		(fp_line
			(start 22.321774 -1.039622)
			(end 23.158196 -1.842262)
			(stroke
				(width 0.1)
				(type default)
			)
			(layer "F.SilkS")
		)
		(fp_line
			(start 22.356572 -1.015746)
			(end 23.197058 -1.821942)
			(stroke
				(width 0.1)
				(type default)
			)
			(layer "F.SilkS")
		)
		(fp_line
			(start 22.356572 -1.015746)
			(end 23.197058 -1.821942)
			(stroke
				(width 0.1)
				(type default)
			)
			(layer "F.SilkS")
		)
		(fp_line
			(start 22.393402 -0.993394)
			(end 23.235666 -1.801622)
			(stroke
				(width 0.1)
				(type default)
			)
			(layer "F.SilkS")
		)
		(fp_line
			(start 22.393402 -0.993394)
			(end 23.235666 -1.801622)
			(stroke
				(width 0.1)
				(type default)
			)
			(layer "F.SilkS")
		)
		(fp_line
			(start 22.43201 -0.97282)
			(end 23.280878 -1.786636)
			(stroke
				(width 0.1)
				(type default)
			)
			(layer "F.SilkS")
		)
		(fp_line
			(start 22.43201 -0.97282)
			(end 23.280878 -1.786636)
			(stroke
				(width 0.1)
				(type default)
			)
			(layer "F.SilkS")
		)
		(fp_line
			(start 22.470872 -0.952246)
			(end 23.328122 -1.774444)
			(stroke
				(width 0.1)
				(type default)
			)
			(layer "F.SilkS")
		)
		(fp_line
			(start 22.470872 -0.952246)
			(end 23.328122 -1.774444)
			(stroke
				(width 0.1)
				(type default)
			)
			(layer "F.SilkS")
		)
		(fp_line
			(start 22.510496 -0.932688)
			(end 23.375366 -1.761998)
			(stroke
				(width 0.1)
				(type default)
			)
			(layer "F.SilkS")
		)
		(fp_line
			(start 22.510496 -0.932688)
			(end 23.375366 -1.761998)
			(stroke
				(width 0.1)
				(type default)
			)
			(layer "F.SilkS")
		)
		(fp_line
			(start 22.552914 -0.91567)
			(end 23.430484 -1.757172)
			(stroke
				(width 0.1)
				(type default)
			)
			(layer "F.SilkS")
		)
		(fp_line
			(start 22.552914 -0.91567)
			(end 23.430484 -1.757172)
			(stroke
				(width 0.1)
				(type default)
			)
			(layer "F.SilkS")
		)
		(fp_line
			(start 22.595332 -0.898398)
			(end 23.48611 -1.752854)
			(stroke
				(width 0.1)
				(type default)
			)
			(layer "F.SilkS")
		)
		(fp_line
			(start 22.595332 -0.898398)
			(end 23.48611 -1.752854)
			(stroke
				(width 0.1)
				(type default)
			)
			(layer "F.SilkS")
		)
		(fp_line
			(start 22.638258 -0.881888)
			(end 23.54199 -1.74879)
			(stroke
				(width 0.1)
				(type default)
			)
			(layer "F.SilkS")
		)
		(fp_line
			(start 22.638258 -0.881888)
			(end 23.54199 -1.74879)
			(stroke
				(width 0.1)
				(type default)
			)
			(layer "F.SilkS")
		)
		(fp_line
			(start 22.651212 -4.81838)
			(end 22.66696 -4.776216)
			(stroke
				(width 0.1)
				(type default)
			)
			(layer "F.SilkS")
		)
		(fp_line
			(start 22.651212 -4.81838)
			(end 22.66696 -4.776216)
			(stroke
				(width 0.1)
				(type default)
			)
			(layer "F.SilkS")
		)
		(fp_line
			(start 22.651212 -4.81838)
			(end 22.676358 -4.842764)
			(stroke
				(width 0.1)
				(type default)
			)
			(layer "F.SilkS")
		)
		(fp_line
			(start 22.651212 -4.81838)
			(end 22.676358 -4.842764)
			(stroke
				(width 0.1)
				(type default)
			)
			(layer "F.SilkS")
		)
		(fp_line
			(start 22.66696 -4.776216)
			(end 22.682708 -4.733798)
			(stroke
				(width 0.1)
				(type default)
			)
			(layer "F.SilkS")
		)
		(fp_line
			(start 22.66696 -4.776216)
			(end 22.682708 -4.733798)
			(stroke
				(width 0.1)
				(type default)
			)
			(layer "F.SilkS")
		)
		(fp_line
			(start 22.66696 -4.776216)
			(end 22.802088 -4.905756)
			(stroke
				(width 0.1)
				(type default)
			)
			(layer "F.SilkS")
		)
		(fp_line
			(start 22.66696 -4.776216)
			(end 22.802088 -4.905756)
			(stroke
				(width 0.1)
				(type default)
			)
			(layer "F.SilkS")
		)
		(fp_line
			(start 22.682708 -4.733798)
			(end 22.698964 -4.69138)
			(stroke
				(width 0.1)
				(type default)
			)
			(layer "F.SilkS")
		)
		(fp_line
			(start 22.682708 -4.733798)
			(end 22.698964 -4.69138)
			(stroke
				(width 0.1)
				(type default)
			)
			(layer "F.SilkS")
		)
		(fp_line
			(start 22.682708 -4.733798)
			(end 22.919436 -4.960874)
			(stroke
				(width 0.1)
				(type default)
			)
			(layer "F.SilkS")
		)
		(fp_line
			(start 22.682708 -4.733798)
			(end 22.919436 -4.960874)
			(stroke
				(width 0.1)
				(type default)
			)
			(layer "F.SilkS")
		)
		(fp_line
			(start 22.684232 -0.868172)
			(end 23.610316 -1.756664)
			(stroke
				(width 0.1)
				(type default)
			)
			(layer "F.SilkS")
		)
		(fp_line
			(start 22.684232 -0.868172)
			(end 23.610316 -1.756664)
			(stroke
				(width 0.1)
				(type default)
			)
			(layer "F.SilkS")
		)
		(fp_line
			(start 22.698964 -4.69138)
			(end 22.714712 -4.648962)
			(stroke
				(width 0.1)
				(type default)
			)
			(layer "F.SilkS")
		)
		(fp_line
			(start 22.698964 -4.69138)
			(end 22.714712 -4.648962)
			(stroke
				(width 0.1)
				(type default)
			)
			(layer "F.SilkS")
		)
		(fp_line
			(start 22.698964 -4.69138)
			(end 23.03272 -5.01142)
			(stroke
				(width 0.1)
				(type default)
			)
			(layer "F.SilkS")
		)
		(fp_line
			(start 22.698964 -4.69138)
			(end 23.03272 -5.01142)
			(stroke
				(width 0.1)
				(type default)
			)
			(layer "F.SilkS")
		)
		(fp_line
			(start 22.714712 -4.648962)
			(end 22.730714 -4.606544)
			(stroke
				(width 0.1)
				(type default)
			)
			(layer "F.SilkS")
		)
		(fp_line
			(start 22.714712 -4.648962)
			(end 22.730714 -4.606544)
			(stroke
				(width 0.1)
				(type default)
			)
			(layer "F.SilkS")
		)
		(fp_line
			(start 22.714712 -4.648962)
			(end 23.13432 -5.051298)
			(stroke
				(width 0.1)
				(type default)
			)
			(layer "F.SilkS")
		)
		(fp_line
			(start 22.714712 -4.648962)
			(end 23.13432 -5.051298)
			(stroke
				(width 0.1)
				(type default)
			)
			(layer "F.SilkS")
		)
		(fp_line
			(start 22.729952 -0.85471)
			(end 23.67915 -1.765046)
			(stroke
				(width 0.1)
				(type default)
			)
			(layer "F.SilkS")
		)
		(fp_line
			(start 22.729952 -0.85471)
			(end 23.67915 -1.765046)
			(stroke
				(width 0.1)
				(type default)
			)
			(layer "F.SilkS")
		)
		(fp_line
			(start 22.730714 -4.606544)
			(end 22.74697 -4.564126)
			(stroke
				(width 0.1)
				(type default)
			)
			(layer "F.SilkS")
		)
		(fp_line
			(start 22.730714 -4.606544)
			(end 22.74697 -4.564126)
			(stroke
				(width 0.1)
				(type default)
			)
			(layer "F.SilkS")
		)
		(fp_line
			(start 22.730714 -4.606544)
			(end 23.234396 -5.089652)
			(stroke
				(width 0.1)
				(type default)
			)
			(layer "F.SilkS")
		)
		(fp_line
			(start 22.730714 -4.606544)
			(end 23.234396 -5.089652)
			(stroke
				(width 0.1)
				(type default)
			)
			(layer "F.SilkS")
		)
		(fp_line
			(start 22.74697 -4.564126)
			(end 22.762718 -4.521708)
			(stroke
				(width 0.1)
				(type default)
			)
			(layer "F.SilkS")
		)
		(fp_line
			(start 22.74697 -4.564126)
			(end 22.762718 -4.521708)
			(stroke
				(width 0.1)
				(type default)
			)
			(layer "F.SilkS")
		)
		(fp_line
			(start 22.74697 -4.564126)
			(end 23.32355 -5.117592)
			(stroke
				(width 0.1)
				(type default)
			)
			(layer "F.SilkS")
		)
		(fp_line
			(start 22.74697 -4.564126)
			(end 23.32355 -5.117592)
			(stroke
				(width 0.1)
				(type default)
			)
			(layer "F.SilkS")
		)
		(fp_line
			(start 22.762718 -4.521708)
			(end 22.778466 -4.47929)
			(stroke
				(width 0.1)
				(type default)
			)
			(layer "F.SilkS")
		)
		(fp_line
			(start 22.762718 -4.521708)
			(end 22.778466 -4.47929)
			(stroke
				(width 0.1)
				(type default)
			)
			(layer "F.SilkS")
		)
		(fp_line
			(start 22.762718 -4.521708)
			(end 23.412704 -5.145278)
			(stroke
				(width 0.1)
				(type default)
			)
			(layer "F.SilkS")
		)
		(fp_line
			(start 22.762718 -4.521708)
			(end 23.412704 -5.145278)
			(stroke
				(width 0.1)
				(type default)
			)
			(layer "F.SilkS")
		)
		(fp_line
			(start 22.777196 -0.841756)
			(end 23.748238 -1.773682)
			(stroke
				(width 0.1)
				(type default)
			)
			(layer "F.SilkS")
		)
		(fp_line
			(start 22.777196 -0.841756)
			(end 23.748238 -1.773682)
			(stroke
				(width 0.1)
				(type default)
			)
			(layer "F.SilkS")
		)
		(fp_line
			(start 22.778466 -4.47929)
			(end 22.794722 -4.436872)
			(stroke
				(width 0.1)
				(type default)
			)
			(layer "F.SilkS")
		)
		(fp_line
			(start 22.778466 -4.47929)
			(end 22.794722 -4.436872)
			(stroke
				(width 0.1)
				(type default)
			)
			(layer "F.SilkS")
		)
		(fp_line
			(start 22.778466 -4.47929)
			(end 23.494746 -5.166106)
			(stroke
				(width 0.1)
				(type default)
			)
			(layer "F.SilkS")
		)
		(fp_line
			(start 22.778466 -4.47929)
			(end 23.494746 -5.166106)
			(stroke
				(width 0.1)
				(type default)
			)
			(layer "F.SilkS")
		)
		(fp_line
			(start 22.794722 -4.436872)
			(end 22.81047 -4.394708)
			(stroke
				(width 0.1)
				(type default)
			)
			(layer "F.SilkS")
		)
		(fp_line
			(start 22.794722 -4.436872)
			(end 22.81047 -4.394708)
			(stroke
				(width 0.1)
				(type default)
			)
			(layer "F.SilkS")
		)
		(fp_line
			(start 22.794722 -4.436872)
			(end 23.573994 -5.184648)
			(stroke
				(width 0.1)
				(type default)
			)
			(layer "F.SilkS")
		)
		(fp_line
			(start 22.794722 -4.436872)
			(end 23.573994 -5.184648)
			(stroke
				(width 0.1)
				(type default)
			)
			(layer "F.SilkS")
		)
		(fp_line
			(start 22.81047 -4.394708)
			(end 22.826472 -4.352036)
			(stroke
				(width 0.1)
				(type default)
			)
			(layer "F.SilkS")
		)
		(fp_line
			(start 22.81047 -4.394708)
			(end 22.826472 -4.352036)
			(stroke
				(width 0.1)
				(type default)
			)
			(layer "F.SilkS")
		)
		(fp_line
			(start 22.81047 -4.394708)
			(end 23.652226 -5.20192)
			(stroke
				(width 0.1)
				(type default)
			)
			(layer "F.SilkS")
		)
		(fp_line
			(start 22.81047 -4.394708)
			(end 23.652226 -5.20192)
			(stroke
				(width 0.1)
				(type default)
			)
			(layer "F.SilkS")
		)
		(fp_line
			(start 22.826472 -4.352036)
			(end 22.842728 -4.309618)
			(stroke
				(width 0.1)
				(type default)
			)
			(layer "F.SilkS")
		)
		(fp_line
			(start 22.826472 -4.352036)
			(end 22.842728 -4.309618)
			(stroke
				(width 0.1)
				(type default)
			)
			(layer "F.SilkS")
		)
		(fp_line
			(start 22.826472 -4.352036)
			(end 23.724616 -5.21335)
			(stroke
				(width 0.1)
				(type default)
			)
			(layer "F.SilkS")
		)
		(fp_line
			(start 22.826472 -4.352036)
			(end 23.724616 -5.21335)
			(stroke
				(width 0.1)
				(type default)
			)
			(layer "F.SilkS")
		)
		(fp_line
			(start 22.826726 -0.831596)
			(end 23.82012 -1.78435)
			(stroke
				(width 0.1)
				(type default)
			)
			(layer "F.SilkS")
		)
		(fp_line
			(start 22.826726 -0.831596)
			(end 23.82012 -1.78435)
			(stroke
				(width 0.1)
				(type default)
			)
			(layer "F.SilkS")
		)
		(fp_line
			(start 22.842728 -4.309618)
			(end 22.858476 -4.267454)
			(stroke
				(width 0.1)
				(type default)
			)
			(layer "F.SilkS")
		)
		(fp_line
			(start 22.842728 -4.309618)
			(end 22.858476 -4.267454)
			(stroke
				(width 0.1)
				(type default)
			)
			(layer "F.SilkS")
		)
		(fp_line
			(start 22.842728 -4.309618)
			(end 23.796498 -5.22478)
			(stroke
				(width 0.1)
				(type default)
			)
			(layer "F.SilkS")
		)
		(fp_line
			(start 22.842728 -4.309618)
			(end 23.796498 -5.22478)
			(stroke
				(width 0.1)
				(type default)
			)
			(layer "F.SilkS")
		)
		(fp_line
			(start 22.858476 -4.267454)
			(end 22.874224 -4.225036)
			(stroke
				(width 0.1)
				(type default)
			)
			(layer "F.SilkS")
		)
		(fp_line
			(start 22.858476 -4.267454)
			(end 22.874224 -4.225036)
			(stroke
				(width 0.1)
				(type default)
			)
			(layer "F.SilkS")
		)
		(fp_line
			(start 22.858476 -4.267454)
			(end 23.86711 -5.235194)
			(stroke
				(width 0.1)
				(type default)
			)
			(layer "F.SilkS")
		)
		(fp_line
			(start 22.858476 -4.267454)
			(end 23.86711 -5.235194)
			(stroke
				(width 0.1)
				(type default)
			)
			(layer "F.SilkS")
		)
		(fp_line
			(start 22.874224 -4.225036)
			(end 22.89048 -4.182618)
			(stroke
				(width 0.1)
				(type default)
			)
			(layer "F.SilkS")
		)
		(fp_line
			(start 22.874224 -4.225036)
			(end 22.89048 -4.182618)
			(stroke
				(width 0.1)
				(type default)
			)
			(layer "F.SilkS")
		)
		(fp_line
			(start 22.874224 -4.225036)
			(end 23.933658 -5.241036)
			(stroke
				(width 0.1)
				(type default)
			)
			(layer "F.SilkS")
		)
		(fp_line
			(start 22.874224 -4.225036)
			(end 23.933658 -5.241036)
			(stroke
				(width 0.1)
				(type default)
			)
			(layer "F.SilkS")
		)
		(fp_line
			(start 22.87651 -0.821436)
			(end 23.916894 -1.819656)
			(stroke
				(width 0.1)
				(type default)
			)
			(layer "F.SilkS")
		)
		(fp_line
			(start 22.87651 -0.821436)
			(end 23.916894 -1.819656)
			(stroke
				(width 0.1)
				(type default)
			)
			(layer "F.SilkS")
		)
		(fp_line
			(start 22.89048 -4.182618)
			(end 22.906482 -4.139946)
			(stroke
				(width 0.1)
				(type default)
			)
			(layer "F.SilkS")
		)
		(fp_line
			(start 22.89048 -4.182618)
			(end 22.906482 -4.139946)
			(stroke
				(width 0.1)
				(type default)
			)
			(layer "F.SilkS")
		)
		(fp_line
			(start 22.89048 -4.182618)
			(end 24.000206 -5.246878)
			(stroke
				(width 0.1)
				(type default)
			)
			(layer "F.SilkS")
		)
		(fp_line
			(start 22.89048 -4.182618)
			(end 24.000206 -5.246878)
			(stroke
				(width 0.1)
				(type default)
			)
			(layer "F.SilkS")
		)
		(fp_line
			(start 22.906482 -4.139946)
			(end 22.92223 -4.097782)
			(stroke
				(width 0.1)
				(type default)
			)
			(layer "F.SilkS")
		)
		(fp_line
			(start 22.906482 -4.139946)
			(end 22.92223 -4.097782)
			(stroke
				(width 0.1)
				(type default)
			)
			(layer "F.SilkS")
		)
		(fp_line
			(start 22.906482 -4.139946)
			(end 24.066246 -5.252974)
			(stroke
				(width 0.1)
				(type default)
			)
			(layer "F.SilkS")
		)
		(fp_line
			(start 22.906482 -4.139946)
			(end 24.066246 -5.252974)
			(stroke
				(width 0.1)
				(type default)
			)
			(layer "F.SilkS")
		)
		(fp_line
			(start 22.92223 -4.097782)
			(end 22.938486 -4.055364)
			(stroke
				(width 0.1)
				(type default)
			)
			(layer "F.SilkS")
		)
		(fp_line
			(start 22.92223 -4.097782)
			(end 22.938486 -4.055364)
			(stroke
				(width 0.1)
				(type default)
			)
			(layer "F.SilkS")
		)
		(fp_line
			(start 22.92223 -4.097782)
			(end 24.129492 -5.255768)
			(stroke
				(width 0.1)
				(type default)
			)
			(layer "F.SilkS")
		)
		(fp_line
			(start 22.92223 -4.097782)
			(end 24.129492 -5.255768)
			(stroke
				(width 0.1)
				(type default)
			)
			(layer "F.SilkS")
		)
		(fp_line
			(start 22.927818 -0.813308)
			(end 24.013668 -1.854962)
			(stroke
				(width 0.1)
				(type default)
			)
			(layer "F.SilkS")
		)
		(fp_line
			(start 22.927818 -0.813308)
			(end 24.013668 -1.854962)
			(stroke
				(width 0.1)
				(type default)
			)
			(layer "F.SilkS")
		)
		(fp_line
			(start 22.938486 -4.055364)
			(end 24.191468 -5.257546)
			(stroke
				(width 0.1)
				(type default)
			)
			(layer "F.SilkS")
		)
		(fp_line
			(start 22.938486 -4.055364)
			(end 24.191468 -5.257546)
			(stroke
				(width 0.1)
				(type default)
			)
			(layer "F.SilkS")
		)
		(fp_line
			(start 22.981158 -0.806704)
			(end 24.158956 -1.93675)
			(stroke
				(width 0.1)
				(type default)
			)
			(layer "F.SilkS")
		)
		(fp_line
			(start 22.981158 -0.806704)
			(end 24.158956 -1.93675)
			(stroke
				(width 0.1)
				(type default)
			)
			(layer "F.SilkS")
		)
		(fp_line
			(start 23.029672 -4.085336)
			(end 24.253444 -5.25907)
			(stroke
				(width 0.1)
				(type default)
			)
			(layer "F.SilkS")
		)
		(fp_line
			(start 23.029672 -4.085336)
			(end 24.253444 -5.25907)
			(stroke
				(width 0.1)
				(type default)
			)
			(layer "F.SilkS")
		)
		(fp_line
			(start 23.091394 -0.797052)
			(end 25.733502 -3.331464)
			(stroke
				(width 0.1)
				(type default)
			)
			(layer "F.SilkS")
		)
		(fp_line
			(start 23.091394 -0.797052)
			(end 25.733502 -3.331464)
			(stroke
				(width 0.1)
				(type default)
			)
			(layer "F.SilkS")
		)
		(fp_line
			(start 23.143718 -4.136898)
			(end 24.31542 -5.260848)
			(stroke
				(width 0.1)
				(type default)
			)
			(layer "F.SilkS")
		)
		(fp_line
			(start 23.143718 -4.136898)
			(end 24.31542 -5.260848)
			(stroke
				(width 0.1)
				(type default)
			)
			(layer "F.SilkS")
		)
		(fp_line
			(start 23.149306 -0.79502)
			(end 25.721056 -3.262122)
			(stroke
				(width 0.1)
				(type default)
			)
			(layer "F.SilkS")
		)
		(fp_line
			(start 23.149306 -0.79502)
			(end 25.721056 -3.262122)
			(stroke
				(width 0.1)
				(type default)
			)
			(layer "F.SilkS")
		)
		(fp_line
			(start 23.208488 -0.794258)
			(end 25.708864 -3.19278)
			(stroke
				(width 0.1)
				(type default)
			)
			(layer "F.SilkS")
		)
		(fp_line
			(start 23.208488 -0.794258)
			(end 25.708864 -3.19278)
			(stroke
				(width 0.1)
				(type default)
			)
			(layer "F.SilkS")
		)
		(fp_line
			(start 23.23084 -2.720086)
			(end 24.256492 -3.704082)
			(stroke
				(width 0.1)
				(type default)
			)
			(layer "F.SilkS")
		)
		(fp_line
			(start 23.23084 -2.720086)
			(end 24.256492 -3.704082)
			(stroke
				(width 0.1)
				(type default)
			)
			(layer "F.SilkS")
		)
		(fp_line
			(start 23.249382 -4.180586)
			(end 24.372824 -5.258562)
			(stroke
				(width 0.1)
				(type default)
			)
			(layer "F.SilkS")
		)
		(fp_line
			(start 23.249382 -4.180586)
			(end 24.372824 -5.258562)
			(stroke
				(width 0.1)
				(type default)
			)
			(layer "F.SilkS")
		)
		(fp_line
			(start 23.275798 -0.800608)
			(end 25.696926 -3.123184)
			(stroke
				(width 0.1)
				(type default)
			)
			(layer "F.SilkS")
		)
		(fp_line
			(start 23.275798 -0.800608)
			(end 25.696926 -3.123184)
			(stroke
				(width 0.1)
				(type default)
			)
			(layer "F.SilkS")
		)
		(fp_line
			(start 23.3426 -0.807466)
			(end 25.68448 -3.054096)
			(stroke
				(width 0.1)
				(type default)
			)
			(layer "F.SilkS")
		)
		(fp_line
			(start 23.3426 -0.807466)
			(end 25.68448 -3.054096)
			(stroke
				(width 0.1)
				(type default)
			)
			(layer "F.SilkS")
		)
		(fp_line
			(start 23.344632 -4.214114)
			(end 24.429212 -5.254752)
			(stroke
				(width 0.1)
				(type default)
			)
			(layer "F.SilkS")
		)
		(fp_line
			(start 23.344632 -4.214114)
			(end 24.429212 -5.254752)
			(stroke
				(width 0.1)
				(type default)
			)
			(layer "F.SilkS")
		)
		(fp_line
			(start 23.34895 -2.775712)
			(end 24.307546 -3.695192)
			(stroke
				(width 0.1)
				(type default)
			)
			(layer "F.SilkS")
		)
		(fp_line
			(start 23.34895 -2.775712)
			(end 24.307546 -3.695192)
			(stroke
				(width 0.1)
				(type default)
			)
			(layer "F.SilkS")
		)
		(fp_line
			(start 23.409402 -0.813562)
			(end 25.672542 -2.984754)
			(stroke
				(width 0.1)
				(type default)
			)
			(layer "F.SilkS")
		)
		(fp_line
			(start 23.409402 -0.813562)
			(end 25.672542 -2.984754)
			(stroke
				(width 0.1)
				(type default)
			)
			(layer "F.SilkS")
		)
		(fp_line
			(start 23.46071 -2.825242)
			(end 24.35606 -3.684016)
			(stroke
				(width 0.1)
				(type default)
			)
			(layer "F.SilkS")
		)
		(fp_line
			(start 23.46071 -2.825242)
			(end 24.35606 -3.684016)
			(stroke
				(width 0.1)
				(type default)
			)
			(layer "F.SilkS")
		)
		(fp_line
			(start 23.476458 -0.82042)
			(end 25.66035 -2.915412)
			(stroke
				(width 0.1)
				(type default)
			)
			(layer "F.SilkS")
		)
		(fp_line
			(start 23.476458 -0.82042)
			(end 25.66035 -2.915412)
			(stroke
				(width 0.1)
				(type default)
			)
			(layer "F.SilkS")
		)
		(fp_line
			(start 23.530052 -2.833878)
			(end 24.401272 -3.669538)
			(stroke
				(width 0.1)
				(type default)
			)
			(layer "F.SilkS")
		)
		(fp_line
			(start 23.530052 -2.833878)
			(end 24.401272 -3.669538)
			(stroke
				(width 0.1)
				(type default)
			)
			(layer "F.SilkS")
		)
		(fp_line
			(start 23.557484 -0.840232)
			(end 25.648412 -2.845816)
			(stroke
				(width 0.1)
				(type default)
			)
			(layer "F.SilkS")
		)
		(fp_line
			(start 23.557484 -0.840232)
			(end 25.648412 -2.845816)
			(stroke
				(width 0.1)
				(type default)
			)
			(layer "F.SilkS")
		)
		(fp_line
			(start 23.642828 -0.864616)
			(end 25.635966 -2.776474)
			(stroke
				(width 0.1)
				(type default)
			)
			(layer "F.SilkS")
		)
		(fp_line
			(start 23.642828 -0.864616)
			(end 25.635966 -2.776474)
			(stroke
				(width 0.1)
				(type default)
			)
			(layer "F.SilkS")
		)
		(fp_line
			(start 23.683468 -3.731514)
			(end 21.836634 -1.95961)
			(stroke
				(width 0.1)
				(type default)
			)
			(layer "F.SilkS")
		)
		(fp_line
			(start 23.683468 -3.731514)
			(end 21.836634 -1.95961)
			(stroke
				(width 0.1)
				(type default)
			)
			(layer "F.SilkS")
		)
		(fp_line
			(start 23.728426 -0.888746)
			(end 25.623774 -2.707132)
			(stroke
				(width 0.1)
				(type default)
			)
			(layer "F.SilkS")
		)
		(fp_line
			(start 23.728426 -0.888746)
			(end 25.623774 -2.707132)
			(stroke
				(width 0.1)
				(type default)
			)
			(layer "F.SilkS")
		)
		(fp_line
			(start 23.831296 -0.929894)
			(end 25.611836 -2.63779)
			(stroke
				(width 0.1)
				(type default)
			)
			(layer "F.SilkS")
		)
		(fp_line
			(start 23.831296 -0.929894)
			(end 25.611836 -2.63779)
			(stroke
				(width 0.1)
				(type default)
			)
			(layer "F.SilkS")
		)
		(fp_line
			(start 23.951692 -0.987552)
			(end 25.59939 -2.568194)
			(stroke
				(width 0.1)
				(type default)
			)
			(layer "F.SilkS")
		)
		(fp_line
			(start 23.951692 -0.987552)
			(end 25.59939 -2.568194)
			(stroke
				(width 0.1)
				(type default)
			)
			(layer "F.SilkS")
		)
		(fp_line
			(start 24.122888 -1.094232)
			(end 25.587452 -2.498852)
			(stroke
				(width 0.1)
				(type default)
			)
			(layer "F.SilkS")
		)
		(fp_line
			(start 24.122888 -1.094232)
			(end 25.587452 -2.498852)
			(stroke
				(width 0.1)
				(type default)
			)
			(layer "F.SilkS")
		)
		(fp_line
			(start 24.17699 -0.882904)
			(end 24.203406 -0.882904)
			(stroke
				(width 0.1)
				(type default)
			)
			(layer "F.SilkS")
		)
		(fp_line
			(start 24.17699 -0.882904)
			(end 24.203406 -0.882904)
			(stroke
				(width 0.1)
				(type default)
			)
			(layer "F.SilkS")
		)
		(fp_line
			(start 24.183848 -0.921512)
			(end 24.17699 -0.882904)
			(stroke
				(width 0.1)
				(type default)
			)
			(layer "F.SilkS")
		)
		(fp_line
			(start 24.183848 -0.921512)
			(end 24.17699 -0.882904)
			(stroke
				(width 0.1)
				(type default)
			)
			(layer "F.SilkS")
		)
		(fp_line
			(start 24.183848 -0.921512)
			(end 25.538684 -2.221484)
			(stroke
				(width 0.1)
				(type default)
			)
			(layer "F.SilkS")
		)
		(fp_line
			(start 24.183848 -0.921512)
			(end 25.538684 -2.221484)
			(stroke
				(width 0.1)
				(type default)
			)
			(layer "F.SilkS")
		)
		(fp_line
			(start 24.195786 -0.991108)
			(end 24.183848 -0.921512)
			(stroke
				(width 0.1)
				(type default)
			)
			(layer "F.SilkS")
		)
		(fp_line
			(start 24.195786 -0.991108)
			(end 24.183848 -0.921512)
			(stroke
				(width 0.1)
				(type default)
			)
			(layer "F.SilkS")
		)
		(fp_line
			(start 24.195786 -0.991108)
			(end 25.550876 -2.290826)
			(stroke
				(width 0.1)
				(type default)
			)
			(layer "F.SilkS")
		)
		(fp_line
			(start 24.195786 -0.991108)
			(end 25.550876 -2.290826)
			(stroke
				(width 0.1)
				(type default)
			)
			(layer "F.SilkS")
		)
		(fp_line
			(start 24.203406 -0.882904)
			(end 24.263858 -0.882904)
			(stroke
				(width 0.1)
				(type default)
			)
			(layer "F.SilkS")
		)
		(fp_line
			(start 24.203406 -0.882904)
			(end 24.263858 -0.882904)
			(stroke
				(width 0.1)
				(type default)
			)
			(layer "F.SilkS")
		)
		(fp_line
			(start 24.203406 -0.882904)
			(end 25.526746 -2.152142)
			(stroke
				(width 0.1)
				(type default)
			)
			(layer "F.SilkS")
		)
		(fp_line
			(start 24.203406 -0.882904)
			(end 25.526746 -2.152142)
			(stroke
				(width 0.1)
				(type default)
			)
			(layer "F.SilkS")
		)
		(fp_line
			(start 24.208232 -1.06045)
			(end 24.195786 -0.991108)
			(stroke
				(width 0.1)
				(type default)
			)
			(layer "F.SilkS")
		)
		(fp_line
			(start 24.208232 -1.06045)
			(end 24.195786 -0.991108)
			(stroke
				(width 0.1)
				(type default)
			)
			(layer "F.SilkS")
		)
		(fp_line
			(start 24.208232 -1.06045)
			(end 25.563322 -2.360422)
			(stroke
				(width 0.1)
				(type default)
			)
			(layer "F.SilkS")
		)
		(fp_line
			(start 24.208232 -1.06045)
			(end 25.563322 -2.360422)
			(stroke
				(width 0.1)
				(type default)
			)
			(layer "F.SilkS")
		)
		(fp_line
			(start 24.220424 -1.130046)
			(end 24.208232 -1.06045)
			(stroke
				(width 0.1)
				(type default)
			)
			(layer "F.SilkS")
		)
		(fp_line
			(start 24.220424 -1.130046)
			(end 24.208232 -1.06045)
			(stroke
				(width 0.1)
				(type default)
			)
			(layer "F.SilkS")
		)
		(fp_line
			(start 24.263858 -0.882904)
			(end 24.324056 -0.882904)
			(stroke
				(width 0.1)
				(type default)
			)
			(layer "F.SilkS")
		)
		(fp_line
			(start 24.263858 -0.882904)
			(end 24.324056 -0.882904)
			(stroke
				(width 0.1)
				(type default)
			)
			(layer "F.SilkS")
		)
		(fp_line
			(start 24.263858 -0.882904)
			(end 25.5143 -2.0828)
			(stroke
				(width 0.1)
				(type default)
			)
			(layer "F.SilkS")
		)
		(fp_line
			(start 24.263858 -0.882904)
			(end 25.5143 -2.0828)
			(stroke
				(width 0.1)
				(type default)
			)
			(layer "F.SilkS")
		)
		(fp_line
			(start 24.324056 -0.882904)
			(end 24.384 -0.882904)
			(stroke
				(width 0.1)
				(type default)
			)
			(layer "F.SilkS")
		)
		(fp_line
			(start 24.324056 -0.882904)
			(end 24.384 -0.882904)
			(stroke
				(width 0.1)
				(type default)
			)
			(layer "F.SilkS")
		)
		(fp_line
			(start 24.324056 -0.882904)
			(end 25.502362 -2.013204)
			(stroke
				(width 0.1)
				(type default)
			)
			(layer "F.SilkS")
		)
		(fp_line
			(start 24.324056 -0.882904)
			(end 25.502362 -2.013204)
			(stroke
				(width 0.1)
				(type default)
			)
			(layer "F.SilkS")
		)
		(fp_line
			(start 24.384 -0.882904)
			(end 24.443944 -0.882904)
			(stroke
				(width 0.1)
				(type default)
			)
			(layer "F.SilkS")
		)
		(fp_line
			(start 24.384 -0.882904)
			(end 24.443944 -0.882904)
			(stroke
				(width 0.1)
				(type default)
			)
			(layer "F.SilkS")
		)
		(fp_line
			(start 24.384 -0.882904)
			(end 25.49017 -1.943862)
			(stroke
				(width 0.1)
				(type default)
			)
			(layer "F.SilkS")
		)
		(fp_line
			(start 24.384 -0.882904)
			(end 25.49017 -1.943862)
			(stroke
				(width 0.1)
				(type default)
			)
			(layer "F.SilkS")
		)
		(fp_line
			(start 24.414988 -2.24028)
			(end 24.402796 -2.170938)
			(stroke
				(width 0.1)
				(type default)
			)
			(layer "F.SilkS")
		)
		(fp_line
			(start 24.414988 -2.24028)
			(end 24.402796 -2.170938)
			(stroke
				(width 0.1)
				(type default)
			)
			(layer "F.SilkS")
		)
		(fp_line
			(start 24.427434 -2.309368)
			(end 24.414988 -2.24028)
			(stroke
				(width 0.1)
				(type default)
			)
			(layer "F.SilkS")
		)
		(fp_line
			(start 24.427434 -2.309368)
			(end 24.414988 -2.24028)
			(stroke
				(width 0.1)
				(type default)
			)
			(layer "F.SilkS")
		)
		(fp_line
			(start 24.439372 -2.37871)
			(end 24.427434 -2.309368)
			(stroke
				(width 0.1)
				(type default)
			)
			(layer "F.SilkS")
		)
		(fp_line
			(start 24.439372 -2.37871)
			(end 24.427434 -2.309368)
			(stroke
				(width 0.1)
				(type default)
			)
			(layer "F.SilkS")
		)
		(fp_line
			(start 24.443944 -0.882904)
			(end 24.504142 -0.882904)
			(stroke
				(width 0.1)
				(type default)
			)
			(layer "F.SilkS")
		)
		(fp_line
			(start 24.443944 -0.882904)
			(end 24.504142 -0.882904)
			(stroke
				(width 0.1)
				(type default)
			)
			(layer "F.SilkS")
		)
		(fp_line
			(start 24.443944 -0.882904)
			(end 25.478232 -1.874774)
			(stroke
				(width 0.1)
				(type default)
			)
			(layer "F.SilkS")
		)
		(fp_line
			(start 24.443944 -0.882904)
			(end 25.478232 -1.874774)
			(stroke
				(width 0.1)
				(type default)
			)
			(layer "F.SilkS")
		)
		(fp_line
			(start 24.44623 -3.655568)
			(end 23.598886 -2.842514)
			(stroke
				(width 0.1)
				(type default)
			)
			(layer "F.SilkS")
		)
		(fp_line
			(start 24.44623 -3.655568)
			(end 23.598886 -2.842514)
			(stroke
				(width 0.1)
				(type default)
			)
			(layer "F.SilkS")
		)
		(fp_line
			(start 24.451564 -2.448306)
			(end 24.439372 -2.37871)
			(stroke
				(width 0.1)
				(type default)
			)
			(layer "F.SilkS")
		)
		(fp_line
			(start 24.451564 -2.448306)
			(end 24.439372 -2.37871)
			(stroke
				(width 0.1)
				(type default)
			)
			(layer "F.SilkS")
		)
		(fp_line
			(start 24.46401 -2.517648)
			(end 24.451564 -2.448306)
			(stroke
				(width 0.1)
				(type default)
			)
			(layer "F.SilkS")
		)
		(fp_line
			(start 24.46401 -2.517648)
			(end 24.451564 -2.448306)
			(stroke
				(width 0.1)
				(type default)
			)
			(layer "F.SilkS")
		)
		(fp_line
			(start 24.475948 -2.58699)
			(end 24.46401 -2.517648)
			(stroke
				(width 0.1)
				(type default)
			)
			(layer "F.SilkS")
		)
		(fp_line
			(start 24.475948 -2.58699)
			(end 24.46401 -2.517648)
			(stroke
				(width 0.1)
				(type default)
			)
			(layer "F.SilkS")
		)
		(fp_line
			(start 24.485346 -5.250942)
			(end 23.433532 -4.2418)
			(stroke
				(width 0.1)
				(type default)
			)
			(layer "F.SilkS")
		)
		(fp_line
			(start 24.485346 -5.250942)
			(end 23.433532 -4.2418)
			(stroke
				(width 0.1)
				(type default)
			)
			(layer "F.SilkS")
		)
		(fp_line
			(start 24.487886 -2.656332)
			(end 24.475948 -2.58699)
			(stroke
				(width 0.1)
				(type default)
			)
			(layer "F.SilkS")
		)
		(fp_line
			(start 24.487886 -2.656332)
			(end 24.475948 -2.58699)
			(stroke
				(width 0.1)
				(type default)
			)
			(layer "F.SilkS")
		)
		(fp_line
			(start 24.491696 -3.64109)
			(end 23.668482 -2.85115)
			(stroke
				(width 0.1)
				(type default)
			)
			(layer "F.SilkS")
		)
		(fp_line
			(start 24.491696 -3.64109)
			(end 23.668482 -2.85115)
			(stroke
				(width 0.1)
				(type default)
			)
			(layer "F.SilkS")
		)
		(fp_line
			(start 24.504142 -0.882904)
			(end 24.564594 -0.882904)
			(stroke
				(width 0.1)
				(type default)
			)
			(layer "F.SilkS")
		)
		(fp_line
			(start 24.504142 -0.882904)
			(end 24.564594 -0.882904)
			(stroke
				(width 0.1)
				(type default)
			)
			(layer "F.SilkS")
		)
		(fp_line
			(start 24.504142 -0.882904)
			(end 25.465786 -1.805178)
			(stroke
				(width 0.1)
				(type default)
			)
			(layer "F.SilkS")
		)
		(fp_line
			(start 24.504142 -0.882904)
			(end 25.465786 -1.805178)
			(stroke
				(width 0.1)
				(type default)
			)
			(layer "F.SilkS")
		)
		(fp_line
			(start 24.534114 -3.624072)
			(end 23.73757 -2.859786)
			(stroke
				(width 0.1)
				(type default)
			)
			(layer "F.SilkS")
		)
		(fp_line
			(start 24.534114 -3.624072)
			(end 23.73757 -2.859786)
			(stroke
				(width 0.1)
				(type default)
			)
			(layer "F.SilkS")
		)
		(fp_line
			(start 24.541734 -5.246878)
			(end 23.518114 -4.265168)
			(stroke
				(width 0.1)
				(type default)
			)
			(layer "F.SilkS")
		)
		(fp_line
			(start 24.541734 -5.246878)
			(end 23.518114 -4.265168)
			(stroke
				(width 0.1)
				(type default)
			)
			(layer "F.SilkS")
		)
		(fp_line
			(start 24.564594 -0.882904)
			(end 24.624538 -0.882904)
			(stroke
				(width 0.1)
				(type default)
			)
			(layer "F.SilkS")
		)
		(fp_line
			(start 24.564594 -0.882904)
			(end 24.624538 -0.882904)
			(stroke
				(width 0.1)
				(type default)
			)
			(layer "F.SilkS")
		)
		(fp_line
			(start 24.564594 -0.882904)
			(end 25.453594 -1.735836)
			(stroke
				(width 0.1)
				(type default)
			)
			(layer "F.SilkS")
		)
		(fp_line
			(start 24.564594 -0.882904)
			(end 25.453594 -1.735836)
			(stroke
				(width 0.1)
				(type default)
			)
			(layer "F.SilkS")
		)
		(fp_line
			(start 24.5745 -3.605276)
			(end 23.797006 -2.859024)
			(stroke
				(width 0.1)
				(type default)
			)
			(layer "F.SilkS")
		)
		(fp_line
			(start 24.5745 -3.605276)
			(end 23.797006 -2.859024)
			(stroke
				(width 0.1)
				(type default)
			)
			(layer "F.SilkS")
		)
		(fp_line
			(start 24.597614 -5.243068)
			(end 23.594822 -4.280916)
			(stroke
				(width 0.1)
				(type default)
			)
			(layer "F.SilkS")
		)
		(fp_line
			(start 24.597614 -5.243068)
			(end 23.594822 -4.280916)
			(stroke
				(width 0.1)
				(type default)
			)
			(layer "F.SilkS")
		)
		(fp_line
			(start 24.614886 -3.586226)
			(end 23.855426 -2.857754)
			(stroke
				(width 0.1)
				(type default)
			)
			(layer "F.SilkS")
		)
		(fp_line
			(start 24.614886 -3.586226)
			(end 23.855426 -2.857754)
			(stroke
				(width 0.1)
				(type default)
			)
			(layer "F.SilkS")
		)
		(fp_line
			(start 24.624538 -0.882904)
			(end 24.684736 -0.882904)
			(stroke
				(width 0.1)
				(type default)
			)
			(layer "F.SilkS")
		)
		(fp_line
			(start 24.624538 -0.882904)
			(end 24.684736 -0.882904)
			(stroke
				(width 0.1)
				(type default)
			)
			(layer "F.SilkS")
		)
		(fp_line
			(start 24.624538 -0.882904)
			(end 25.441656 -1.666494)
			(stroke
				(width 0.1)
				(type default)
			)
			(layer "F.SilkS")
		)
		(fp_line
			(start 24.624538 -0.882904)
			(end 25.441656 -1.666494)
			(stroke
				(width 0.1)
				(type default)
			)
			(layer "F.SilkS")
		)
		(fp_line
			(start 24.653748 -5.239258)
			(end 23.67026 -4.295902)
			(stroke
				(width 0.1)
				(type default)
			)
			(layer "F.SilkS")
		)
		(fp_line
			(start 24.653748 -5.239258)
			(end 23.67026 -4.295902)
			(stroke
				(width 0.1)
				(type default)
			)
			(layer "F.SilkS")
		)
		(fp_line
			(start 24.67102 -3.697478)
			(end 24.658574 -3.627882)
			(stroke
				(width 0.1)
				(type default)
			)
			(layer "F.SilkS")
		)
		(fp_line
			(start 24.67102 -3.697478)
			(end 24.658574 -3.627882)
			(stroke
				(width 0.1)
				(type default)
			)
			(layer "F.SilkS")
		)
		(fp_line
			(start 24.682958 -3.76682)
			(end 24.67102 -3.697478)
			(stroke
				(width 0.1)
				(type default)
			)
			(layer "F.SilkS")
		)
		(fp_line
			(start 24.682958 -3.76682)
			(end 24.67102 -3.697478)
			(stroke
				(width 0.1)
				(type default)
			)
			(layer "F.SilkS")
		)
		(fp_line
			(start 24.684736 -0.882904)
			(end 24.744934 -0.882904)
			(stroke
				(width 0.1)
				(type default)
			)
			(layer "F.SilkS")
		)
		(fp_line
			(start 24.684736 -0.882904)
			(end 24.744934 -0.882904)
			(stroke
				(width 0.1)
				(type default)
			)
			(layer "F.SilkS")
		)
		(fp_line
			(start 24.684736 -0.882904)
			(end 25.42921 -1.597406)
			(stroke
				(width 0.1)
				(type default)
			)
			(layer "F.SilkS")
		)
		(fp_line
			(start 24.684736 -0.882904)
			(end 25.42921 -1.597406)
			(stroke
				(width 0.1)
				(type default)
			)
			(layer "F.SilkS")
		)
		(fp_line
			(start 24.708866 -5.234432)
			(end 23.739856 -4.304792)
			(stroke
				(width 0.1)
				(type default)
			)
			(layer "F.SilkS")
		)
		(fp_line
			(start 24.708866 -5.234432)
			(end 23.739856 -4.304792)
			(stroke
				(width 0.1)
				(type default)
			)
			(layer "F.SilkS")
		)
		(fp_line
			(start 24.744934 -0.882904)
			(end 24.805386 -0.882904)
			(stroke
				(width 0.1)
				(type default)
			)
			(layer "F.SilkS")
		)
		(fp_line
			(start 24.744934 -0.882904)
			(end 24.805386 -0.882904)
			(stroke
				(width 0.1)
				(type default)
			)
			(layer "F.SilkS")
		)
		(fp_line
			(start 24.744934 -0.882904)
			(end 25.417272 -1.52781)
			(stroke
				(width 0.1)
				(type default)
			)
			(layer "F.SilkS")
		)
		(fp_line
			(start 24.744934 -0.882904)
			(end 25.417272 -1.52781)
			(stroke
				(width 0.1)
				(type default)
			)
			(layer "F.SilkS")
		)
		(fp_line
			(start 24.75738 -5.223256)
			(end 23.809452 -4.313936)
			(stroke
				(width 0.1)
				(type default)
			)
			(layer "F.SilkS")
		)
		(fp_line
			(start 24.75738 -5.223256)
			(end 23.809452 -4.313936)
			(stroke
				(width 0.1)
				(type default)
			)
			(layer "F.SilkS")
		)
		(fp_line
			(start 24.805386 -0.882904)
			(end 24.86533 -0.882904)
			(stroke
				(width 0.1)
				(type default)
			)
			(layer "F.SilkS")
		)
		(fp_line
			(start 24.805386 -0.882904)
			(end 24.86533 -0.882904)
			(stroke
				(width 0.1)
				(type default)
			)
			(layer "F.SilkS")
		)
		(fp_line
			(start 24.805386 -0.882904)
			(end 25.40508 -1.458214)
			(stroke
				(width 0.1)
				(type default)
			)
			(layer "F.SilkS")
		)
		(fp_line
			(start 24.805386 -0.882904)
			(end 25.40508 -1.458214)
			(stroke
				(width 0.1)
				(type default)
			)
			(layer "F.SilkS")
		)
		(fp_line
			(start 24.805894 -5.21208)
			(end 23.87473 -4.318762)
			(stroke
				(width 0.1)
				(type default)
			)
			(layer "F.SilkS")
		)
		(fp_line
			(start 24.805894 -5.21208)
			(end 23.87473 -4.318762)
			(stroke
				(width 0.1)
				(type default)
			)
			(layer "F.SilkS")
		)
		(fp_line
			(start 24.854154 -5.200904)
			(end 23.9395 -4.323334)
			(stroke
				(width 0.1)
				(type default)
			)
			(layer "F.SilkS")
		)
		(fp_line
			(start 24.854154 -5.200904)
			(end 23.9395 -4.323334)
			(stroke
				(width 0.1)
				(type default)
			)
			(layer "F.SilkS")
		)
		(fp_line
			(start 24.86533 -0.882904)
			(end 24.925274 -0.882904)
			(stroke
				(width 0.1)
				(type default)
			)
			(layer "F.SilkS")
		)
		(fp_line
			(start 24.86533 -0.882904)
			(end 24.925274 -0.882904)
			(stroke
				(width 0.1)
				(type default)
			)
			(layer "F.SilkS")
		)
		(fp_line
			(start 24.86533 -0.882904)
			(end 25.392634 -1.388872)
			(stroke
				(width 0.1)
				(type default)
			)
			(layer "F.SilkS")
		)
		(fp_line
			(start 24.86533 -0.882904)
			(end 25.392634 -1.388872)
			(stroke
				(width 0.1)
				(type default)
			)
			(layer "F.SilkS")
		)
		(fp_line
			(start 24.903176 -5.189728)
			(end 24.003254 -4.32689)
			(stroke
				(width 0.1)
				(type default)
			)
			(layer "F.SilkS")
		)
		(fp_line
			(start 24.903176 -5.189728)
			(end 24.003254 -4.32689)
			(stroke
				(width 0.1)
				(type default)
			)
			(layer "F.SilkS")
		)
		(fp_line
			(start 24.925274 -0.882904)
			(end 24.985472 -0.882904)
			(stroke
				(width 0.1)
				(type default)
			)
			(layer "F.SilkS")
		)
		(fp_line
			(start 24.925274 -0.882904)
			(end 24.985472 -0.882904)
			(stroke
				(width 0.1)
				(type default)
			)
			(layer "F.SilkS")
		)
		(fp_line
			(start 24.925274 -0.882904)
			(end 25.380696 -1.319784)
			(stroke
				(width 0.1)
				(type default)
			)
			(layer "F.SilkS")
		)
		(fp_line
			(start 24.925274 -0.882904)
			(end 25.380696 -1.319784)
			(stroke
				(width 0.1)
				(type default)
			)
			(layer "F.SilkS")
		)
		(fp_line
			(start 24.95169 -5.178552)
			(end 24.064976 -4.327906)
			(stroke
				(width 0.1)
				(type default)
			)
			(layer "F.SilkS")
		)
		(fp_line
			(start 24.95169 -5.178552)
			(end 24.064976 -4.327906)
			(stroke
				(width 0.1)
				(type default)
			)
			(layer "F.SilkS")
		)
		(fp_line
			(start 24.985472 -0.882904)
			(end 25.04567 -0.882904)
			(stroke
				(width 0.1)
				(type default)
			)
			(layer "F.SilkS")
		)
		(fp_line
			(start 24.985472 -0.882904)
			(end 25.04567 -0.882904)
			(stroke
				(width 0.1)
				(type default)
			)
			(layer "F.SilkS")
		)
		(fp_line
			(start 24.985472 -0.882904)
			(end 25.368504 -1.250188)
			(stroke
				(width 0.1)
				(type default)
			)
			(layer "F.SilkS")
		)
		(fp_line
			(start 24.985472 -0.882904)
			(end 25.368504 -1.250188)
			(stroke
				(width 0.1)
				(type default)
			)
			(layer "F.SilkS")
		)
		(fp_line
			(start 24.99995 -5.16763)
			(end 24.12619 -4.329176)
			(stroke
				(width 0.1)
				(type default)
			)
			(layer "F.SilkS")
		)
		(fp_line
			(start 24.99995 -5.16763)
			(end 24.12619 -4.329176)
			(stroke
				(width 0.1)
				(type default)
			)
			(layer "F.SilkS")
		)
		(fp_line
			(start 25.045162 -5.152898)
			(end 24.18588 -4.328922)
			(stroke
				(width 0.1)
				(type default)
			)
			(layer "F.SilkS")
		)
		(fp_line
			(start 25.045162 -5.152898)
			(end 24.18588 -4.328922)
			(stroke
				(width 0.1)
				(type default)
			)
			(layer "F.SilkS")
		)
		(fp_line
			(start 25.04567 -0.882904)
			(end 25.106122 -0.882904)
			(stroke
				(width 0.1)
				(type default)
			)
			(layer "F.SilkS")
		)
		(fp_line
			(start 25.04567 -0.882904)
			(end 25.106122 -0.882904)
			(stroke
				(width 0.1)
				(type default)
			)
			(layer "F.SilkS")
		)
		(fp_line
			(start 25.04567 -0.882904)
			(end 25.356058 -1.180592)
			(stroke
				(width 0.1)
				(type default)
			)
			(layer "F.SilkS")
		)
		(fp_line
			(start 25.04567 -0.882904)
			(end 25.356058 -1.180592)
			(stroke
				(width 0.1)
				(type default)
			)
			(layer "F.SilkS")
		)
		(fp_line
			(start 25.086056 -5.13461)
			(end 24.241252 -4.32435)
			(stroke
				(width 0.1)
				(type default)
			)
			(layer "F.SilkS")
		)
		(fp_line
			(start 25.086056 -5.13461)
			(end 24.241252 -4.32435)
			(stroke
				(width 0.1)
				(type default)
			)
			(layer "F.SilkS")
		)
		(fp_line
			(start 25.106122 -0.882904)
			(end 25.166066 -0.882904)
			(stroke
				(width 0.1)
				(type default)
			)
			(layer "F.SilkS")
		)
		(fp_line
			(start 25.106122 -0.882904)
			(end 25.166066 -0.882904)
			(stroke
				(width 0.1)
				(type default)
			)
			(layer "F.SilkS")
		)
		(fp_line
			(start 25.106122 -0.882904)
			(end 25.34412 -1.111504)
			(stroke
				(width 0.1)
				(type default)
			)
			(layer "F.SilkS")
		)
		(fp_line
			(start 25.106122 -0.882904)
			(end 25.34412 -1.111504)
			(stroke
				(width 0.1)
				(type default)
			)
			(layer "F.SilkS")
		)
		(fp_line
			(start 25.127458 -5.116322)
			(end 24.297132 -4.320032)
			(stroke
				(width 0.1)
				(type default)
			)
			(layer "F.SilkS")
		)
		(fp_line
			(start 25.127458 -5.116322)
			(end 24.297132 -4.320032)
			(stroke
				(width 0.1)
				(type default)
			)
			(layer "F.SilkS")
		)
		(fp_line
			(start 25.166066 -0.882904)
			(end 25.226264 -0.882904)
			(stroke
				(width 0.1)
				(type default)
			)
			(layer "F.SilkS")
		)
		(fp_line
			(start 25.166066 -0.882904)
			(end 25.226264 -0.882904)
			(stroke
				(width 0.1)
				(type default)
			)
			(layer "F.SilkS")
		)
		(fp_line
			(start 25.166066 -0.882904)
			(end 25.332182 -1.042416)
			(stroke
				(width 0.1)
				(type default)
			)
			(layer "F.SilkS")
		)
		(fp_line
			(start 25.166066 -0.882904)
			(end 25.332182 -1.042416)
			(stroke
				(width 0.1)
				(type default)
			)
			(layer "F.SilkS")
		)
		(fp_line
			(start 25.168352 -5.098034)
			(end 24.346408 -4.309618)
			(stroke
				(width 0.1)
				(type default)
			)
			(layer "F.SilkS")
		)
		(fp_line
			(start 25.168352 -5.098034)
			(end 24.346408 -4.309618)
			(stroke
				(width 0.1)
				(type default)
			)
			(layer "F.SilkS")
		)
		(fp_line
			(start 25.2095 -5.08)
			(end 24.393398 -4.296918)
			(stroke
				(width 0.1)
				(type default)
			)
			(layer "F.SilkS")
		)
		(fp_line
			(start 25.2095 -5.08)
			(end 24.393398 -4.296918)
			(stroke
				(width 0.1)
				(type default)
			)
			(layer "F.SilkS")
		)
		(fp_line
			(start 25.226264 -0.882904)
			(end 25.286462 -0.882904)
			(stroke
				(width 0.1)
				(type default)
			)
			(layer "F.SilkS")
		)
		(fp_line
			(start 25.226264 -0.882904)
			(end 25.286462 -0.882904)
			(stroke
				(width 0.1)
				(type default)
			)
			(layer "F.SilkS")
		)
		(fp_line
			(start 25.226264 -0.882904)
			(end 25.31999 -0.97282)
			(stroke
				(width 0.1)
				(type default)
			)
			(layer "F.SilkS")
		)
		(fp_line
			(start 25.226264 -0.882904)
			(end 25.31999 -0.97282)
			(stroke
				(width 0.1)
				(type default)
			)
			(layer "F.SilkS")
		)
		(fp_line
			(start 25.250648 -5.061712)
			(end 24.438356 -4.28244)
			(stroke
				(width 0.1)
				(type default)
			)
			(layer "F.SilkS")
		)
		(fp_line
			(start 25.250648 -5.061712)
			(end 24.438356 -4.28244)
			(stroke
				(width 0.1)
				(type default)
			)
			(layer "F.SilkS")
		)
		(fp_line
			(start 25.286462 -0.882904)
			(end 25.304242 -0.882904)
			(stroke
				(width 0.1)
				(type default)
			)
			(layer "F.SilkS")
		)
		(fp_line
			(start 25.286462 -0.882904)
			(end 25.304242 -0.882904)
			(stroke
				(width 0.1)
				(type default)
			)
			(layer "F.SilkS")
		)
		(fp_line
			(start 25.286462 -0.882904)
			(end 25.307544 -0.903224)
			(stroke
				(width 0.1)
				(type default)
			)
			(layer "F.SilkS")
		)
		(fp_line
			(start 25.286462 -0.882904)
			(end 25.307544 -0.903224)
			(stroke
				(width 0.1)
				(type default)
			)
			(layer "F.SilkS")
		)
		(fp_line
			(start 25.29205 -5.043424)
			(end 24.477726 -4.26212)
			(stroke
				(width 0.1)
				(type default)
			)
			(layer "F.SilkS")
		)
		(fp_line
			(start 25.29205 -5.043424)
			(end 24.477726 -4.26212)
			(stroke
				(width 0.1)
				(type default)
			)
			(layer "F.SilkS")
		)
		(fp_line
			(start 25.304242 -0.882904)
			(end 25.307544 -0.903224)
			(stroke
				(width 0.1)
				(type default)
			)
			(layer "F.SilkS")
		)
		(fp_line
			(start 25.304242 -0.882904)
			(end 25.307544 -0.903224)
			(stroke
				(width 0.1)
				(type default)
			)
			(layer "F.SilkS")
		)
		(fp_line
			(start 25.307544 -0.903224)
			(end 25.31999 -0.97282)
			(stroke
				(width 0.1)
				(type default)
			)
			(layer "F.SilkS")
		)
		(fp_line
			(start 25.307544 -0.903224)
			(end 25.31999 -0.97282)
			(stroke
				(width 0.1)
				(type default)
			)
			(layer "F.SilkS")
		)
		(fp_line
			(start 25.31999 -0.97282)
			(end 25.332182 -1.042416)
			(stroke
				(width 0.1)
				(type default)
			)
			(layer "F.SilkS")
		)
		(fp_line
			(start 25.31999 -0.97282)
			(end 25.332182 -1.042416)
			(stroke
				(width 0.1)
				(type default)
			)
			(layer "F.SilkS")
		)
		(fp_line
			(start 25.327356 -5.019294)
			(end 24.516334 -4.2418)
			(stroke
				(width 0.1)
				(type default)
			)
			(layer "F.SilkS")
		)
		(fp_line
			(start 25.327356 -5.019294)
			(end 24.516334 -4.2418)
			(stroke
				(width 0.1)
				(type default)
			)
			(layer "F.SilkS")
		)
		(fp_line
			(start 25.332182 -1.042416)
			(end 25.34412 -1.111504)
			(stroke
				(width 0.1)
				(type default)
			)
			(layer "F.SilkS")
		)
		(fp_line
			(start 25.332182 -1.042416)
			(end 25.34412 -1.111504)
			(stroke
				(width 0.1)
				(type default)
			)
			(layer "F.SilkS")
		)
		(fp_line
			(start 25.34412 -1.111504)
			(end 25.356058 -1.180592)
			(stroke
				(width 0.1)
				(type default)
			)
			(layer "F.SilkS")
		)
		(fp_line
			(start 25.34412 -1.111504)
			(end 25.356058 -1.180592)
			(stroke
				(width 0.1)
				(type default)
			)
			(layer "F.SilkS")
		)
		(fp_line
			(start 25.356058 -1.180592)
			(end 25.368504 -1.250188)
			(stroke
				(width 0.1)
				(type default)
			)
			(layer "F.SilkS")
		)
		(fp_line
			(start 25.356058 -1.180592)
			(end 25.368504 -1.250188)
			(stroke
				(width 0.1)
				(type default)
			)
			(layer "F.SilkS")
		)
		(fp_line
			(start 25.36063 -4.994148)
			(end 24.549354 -4.215892)
			(stroke
				(width 0.1)
				(type default)
			)
			(layer "F.SilkS")
		)
		(fp_line
			(start 25.36063 -4.994148)
			(end 24.549354 -4.215892)
			(stroke
				(width 0.1)
				(type default)
			)
			(layer "F.SilkS")
		)
		(fp_line
			(start 25.368504 -1.250188)
			(end 25.380696 -1.319784)
			(stroke
				(width 0.1)
				(type default)
			)
			(layer "F.SilkS")
		)
		(fp_line
			(start 25.368504 -1.250188)
			(end 25.380696 -1.319784)
			(stroke
				(width 0.1)
				(type default)
			)
			(layer "F.SilkS")
		)
		(fp_line
			(start 25.380696 -1.319784)
			(end 25.392634 -1.388872)
			(stroke
				(width 0.1)
				(type default)
			)
			(layer "F.SilkS")
		)
		(fp_line
			(start 25.380696 -1.319784)
			(end 25.392634 -1.388872)
			(stroke
				(width 0.1)
				(type default)
			)
			(layer "F.SilkS")
		)
		(fp_line
			(start 25.392634 -1.388872)
			(end 25.40508 -1.458214)
			(stroke
				(width 0.1)
				(type default)
			)
			(layer "F.SilkS")
		)
		(fp_line
			(start 25.392634 -1.388872)
			(end 25.40508 -1.458214)
			(stroke
				(width 0.1)
				(type default)
			)
			(layer "F.SilkS")
		)
		(fp_line
			(start 25.394412 -4.968494)
			(end 24.580596 -4.187952)
			(stroke
				(width 0.1)
				(type default)
			)
			(layer "F.SilkS")
		)
		(fp_line
			(start 25.394412 -4.968494)
			(end 24.580596 -4.187952)
			(stroke
				(width 0.1)
				(type default)
			)
			(layer "F.SilkS")
		)
		(fp_line
			(start 25.40508 -1.458214)
			(end 25.417272 -1.52781)
			(stroke
				(width 0.1)
				(type default)
			)
			(layer "F.SilkS")
		)
		(fp_line
			(start 25.40508 -1.458214)
			(end 25.417272 -1.52781)
			(stroke
				(width 0.1)
				(type default)
			)
			(layer "F.SilkS")
		)
		(fp_line
			(start 25.417272 -1.52781)
			(end 25.42921 -1.597406)
			(stroke
				(width 0.1)
				(type default)
			)
			(layer "F.SilkS")
		)
		(fp_line
			(start 25.417272 -1.52781)
			(end 25.42921 -1.597406)
			(stroke
				(width 0.1)
				(type default)
			)
			(layer "F.SilkS")
		)
		(fp_line
			(start 25.428194 -4.943094)
			(end 24.609044 -4.157218)
			(stroke
				(width 0.1)
				(type default)
			)
			(layer "F.SilkS")
		)
		(fp_line
			(start 25.428194 -4.943094)
			(end 24.609044 -4.157218)
			(stroke
				(width 0.1)
				(type default)
			)
			(layer "F.SilkS")
		)
		(fp_line
			(start 25.42921 -1.597406)
			(end 25.441656 -1.666494)
			(stroke
				(width 0.1)
				(type default)
			)
			(layer "F.SilkS")
		)
		(fp_line
			(start 25.42921 -1.597406)
			(end 25.441656 -1.666494)
			(stroke
				(width 0.1)
				(type default)
			)
			(layer "F.SilkS")
		)
		(fp_line
			(start 25.441656 -1.666494)
			(end 25.453594 -1.735836)
			(stroke
				(width 0.1)
				(type default)
			)
			(layer "F.SilkS")
		)
		(fp_line
			(start 25.441656 -1.666494)
			(end 25.453594 -1.735836)
			(stroke
				(width 0.1)
				(type default)
			)
			(layer "F.SilkS")
		)
		(fp_line
			(start 25.453594 -1.735836)
			(end 25.465786 -1.805178)
			(stroke
				(width 0.1)
				(type default)
			)
			(layer "F.SilkS")
		)
		(fp_line
			(start 25.453594 -1.735836)
			(end 25.465786 -1.805178)
			(stroke
				(width 0.1)
				(type default)
			)
			(layer "F.SilkS")
		)
		(fp_line
			(start 25.461722 -4.917694)
			(end 24.631904 -4.121912)
			(stroke
				(width 0.1)
				(type default)
			)
			(layer "F.SilkS")
		)
		(fp_line
			(start 25.461722 -4.917694)
			(end 24.631904 -4.121912)
			(stroke
				(width 0.1)
				(type default)
			)
			(layer "F.SilkS")
		)
		(fp_line
			(start 25.465786 -1.805178)
			(end 25.478232 -1.874774)
			(stroke
				(width 0.1)
				(type default)
			)
			(layer "F.SilkS")
		)
		(fp_line
			(start 25.465786 -1.805178)
			(end 25.478232 -1.874774)
			(stroke
				(width 0.1)
				(type default)
			)
			(layer "F.SilkS")
		)
		(fp_line
			(start 25.478232 -1.874774)
			(end 25.49017 -1.943862)
			(stroke
				(width 0.1)
				(type default)
			)
			(layer "F.SilkS")
		)
		(fp_line
			(start 25.478232 -1.874774)
			(end 25.49017 -1.943862)
			(stroke
				(width 0.1)
				(type default)
			)
			(layer "F.SilkS")
		)
		(fp_line
			(start 25.49017 -1.943862)
			(end 25.502362 -2.013204)
			(stroke
				(width 0.1)
				(type default)
			)
			(layer "F.SilkS")
		)
		(fp_line
			(start 25.49017 -1.943862)
			(end 25.502362 -2.013204)
			(stroke
				(width 0.1)
				(type default)
			)
			(layer "F.SilkS")
		)
		(fp_line
			(start 25.49525 -4.892294)
			(end 24.65451 -4.085844)
			(stroke
				(width 0.1)
				(type default)
			)
			(layer "F.SilkS")
		)
		(fp_line
			(start 25.49525 -4.892294)
			(end 24.65451 -4.085844)
			(stroke
				(width 0.1)
				(type default)
			)
			(layer "F.SilkS")
		)
		(fp_line
			(start 25.502362 -2.013204)
			(end 25.5143 -2.0828)
			(stroke
				(width 0.1)
				(type default)
			)
			(layer "F.SilkS")
		)
		(fp_line
			(start 25.502362 -2.013204)
			(end 25.5143 -2.0828)
			(stroke
				(width 0.1)
				(type default)
			)
			(layer "F.SilkS")
		)
		(fp_line
			(start 25.5143 -2.0828)
			(end 25.526746 -2.152142)
			(stroke
				(width 0.1)
				(type default)
			)
			(layer "F.SilkS")
		)
		(fp_line
			(start 25.5143 -2.0828)
			(end 25.526746 -2.152142)
			(stroke
				(width 0.1)
				(type default)
			)
			(layer "F.SilkS")
		)
		(fp_line
			(start 25.526746 -2.152142)
			(end 25.538684 -2.221484)
			(stroke
				(width 0.1)
				(type default)
			)
			(layer "F.SilkS")
		)
		(fp_line
			(start 25.526746 -2.152142)
			(end 25.538684 -2.221484)
			(stroke
				(width 0.1)
				(type default)
			)
			(layer "F.SilkS")
		)
		(fp_line
			(start 25.527508 -4.865624)
			(end 24.669242 -4.042156)
			(stroke
				(width 0.1)
				(type default)
			)
			(layer "F.SilkS")
		)
		(fp_line
			(start 25.527508 -4.865624)
			(end 24.669242 -4.042156)
			(stroke
				(width 0.1)
				(type default)
			)
			(layer "F.SilkS")
		)
		(fp_line
			(start 25.538684 -2.221484)
			(end 25.550876 -2.290826)
			(stroke
				(width 0.1)
				(type default)
			)
			(layer "F.SilkS")
		)
		(fp_line
			(start 25.538684 -2.221484)
			(end 25.550876 -2.290826)
			(stroke
				(width 0.1)
				(type default)
			)
			(layer "F.SilkS")
		)
		(fp_line
			(start 25.550876 -2.290826)
			(end 25.563322 -2.360422)
			(stroke
				(width 0.1)
				(type default)
			)
			(layer "F.SilkS")
		)
		(fp_line
			(start 25.550876 -2.290826)
			(end 25.563322 -2.360422)
			(stroke
				(width 0.1)
				(type default)
			)
			(layer "F.SilkS")
		)
		(fp_line
			(start 25.553162 -4.83235)
			(end 24.683974 -3.998722)
			(stroke
				(width 0.1)
				(type default)
			)
			(layer "F.SilkS")
		)
		(fp_line
			(start 25.553162 -4.83235)
			(end 24.683974 -3.998722)
			(stroke
				(width 0.1)
				(type default)
			)
			(layer "F.SilkS")
		)
		(fp_line
			(start 25.563322 -2.360422)
			(end 25.57526 -2.429764)
			(stroke
				(width 0.1)
				(type default)
			)
			(layer "F.SilkS")
		)
		(fp_line
			(start 25.563322 -2.360422)
			(end 25.57526 -2.429764)
			(stroke
				(width 0.1)
				(type default)
			)
			(layer "F.SilkS")
		)
		(fp_line
			(start 25.57526 -2.429764)
			(end 24.220424 -1.130046)
			(stroke
				(width 0.1)
				(type default)
			)
			(layer "F.SilkS")
		)
		(fp_line
			(start 25.57526 -2.429764)
			(end 24.220424 -1.130046)
			(stroke
				(width 0.1)
				(type default)
			)
			(layer "F.SilkS")
		)
		(fp_line
			(start 25.57526 -2.429764)
			(end 25.587452 -2.498852)
			(stroke
				(width 0.1)
				(type default)
			)
			(layer "F.SilkS")
		)
		(fp_line
			(start 25.57526 -2.429764)
			(end 25.587452 -2.498852)
			(stroke
				(width 0.1)
				(type default)
			)
			(layer "F.SilkS")
		)
		(fp_line
			(start 25.57907 -4.79933)
			(end 24.690324 -3.946652)
			(stroke
				(width 0.1)
				(type default)
			)
			(layer "F.SilkS")
		)
		(fp_line
			(start 25.57907 -4.79933)
			(end 24.690324 -3.946652)
			(stroke
				(width 0.1)
				(type default)
			)
			(layer "F.SilkS")
		)
		(fp_line
			(start 25.587452 -2.498852)
			(end 25.59939 -2.568194)
			(stroke
				(width 0.1)
				(type default)
			)
			(layer "F.SilkS")
		)
		(fp_line
			(start 25.587452 -2.498852)
			(end 25.59939 -2.568194)
			(stroke
				(width 0.1)
				(type default)
			)
			(layer "F.SilkS")
		)
		(fp_line
			(start 25.59939 -2.568194)
			(end 25.611836 -2.63779)
			(stroke
				(width 0.1)
				(type default)
			)
			(layer "F.SilkS")
		)
		(fp_line
			(start 25.59939 -2.568194)
			(end 25.611836 -2.63779)
			(stroke
				(width 0.1)
				(type default)
			)
			(layer "F.SilkS")
		)
		(fp_line
			(start 25.60447 -4.766564)
			(end 24.695658 -3.894328)
			(stroke
				(width 0.1)
				(type default)
			)
			(layer "F.SilkS")
		)
		(fp_line
			(start 25.60447 -4.766564)
			(end 24.695658 -3.894328)
			(stroke
				(width 0.1)
				(type default)
			)
			(layer "F.SilkS")
		)
		(fp_line
			(start 25.611836 -2.63779)
			(end 25.623774 -2.707132)
			(stroke
				(width 0.1)
				(type default)
			)
			(layer "F.SilkS")
		)
		(fp_line
			(start 25.611836 -2.63779)
			(end 25.623774 -2.707132)
			(stroke
				(width 0.1)
				(type default)
			)
			(layer "F.SilkS")
		)
		(fp_line
			(start 25.623774 -2.707132)
			(end 25.635966 -2.776474)
			(stroke
				(width 0.1)
				(type default)
			)
			(layer "F.SilkS")
		)
		(fp_line
			(start 25.623774 -2.707132)
			(end 25.635966 -2.776474)
			(stroke
				(width 0.1)
				(type default)
			)
			(layer "F.SilkS")
		)
		(fp_line
			(start 25.630378 -4.73329)
			(end 24.690324 -3.83159)
			(stroke
				(width 0.1)
				(type default)
			)
			(layer "F.SilkS")
		)
		(fp_line
			(start 25.630378 -4.73329)
			(end 24.690324 -3.83159)
			(stroke
				(width 0.1)
				(type default)
			)
			(layer "F.SilkS")
		)
		(fp_line
			(start 25.635966 -2.776474)
			(end 25.648412 -2.845816)
			(stroke
				(width 0.1)
				(type default)
			)
			(layer "F.SilkS")
		)
		(fp_line
			(start 25.635966 -2.776474)
			(end 25.648412 -2.845816)
			(stroke
				(width 0.1)
				(type default)
			)
			(layer "F.SilkS")
		)
		(fp_line
			(start 25.648412 -2.845816)
			(end 25.66035 -2.915412)
			(stroke
				(width 0.1)
				(type default)
			)
			(layer "F.SilkS")
		)
		(fp_line
			(start 25.648412 -2.845816)
			(end 25.66035 -2.915412)
			(stroke
				(width 0.1)
				(type default)
			)
			(layer "F.SilkS")
		)
		(fp_line
			(start 25.656286 -4.70027)
			(end 24.682958 -3.76682)
			(stroke
				(width 0.1)
				(type default)
			)
			(layer "F.SilkS")
		)
		(fp_line
			(start 25.656286 -4.70027)
			(end 24.682958 -3.76682)
			(stroke
				(width 0.1)
				(type default)
			)
			(layer "F.SilkS")
		)
		(fp_line
			(start 25.66035 -2.915412)
			(end 25.672542 -2.984754)
			(stroke
				(width 0.1)
				(type default)
			)
			(layer "F.SilkS")
		)
		(fp_line
			(start 25.66035 -2.915412)
			(end 25.672542 -2.984754)
			(stroke
				(width 0.1)
				(type default)
			)
			(layer "F.SilkS")
		)
		(fp_line
			(start 25.672542 -2.984754)
			(end 25.68448 -3.054096)
			(stroke
				(width 0.1)
				(type default)
			)
			(layer "F.SilkS")
		)
		(fp_line
			(start 25.672542 -2.984754)
			(end 25.68448 -3.054096)
			(stroke
				(width 0.1)
				(type default)
			)
			(layer "F.SilkS")
		)
		(fp_line
			(start 25.681686 -4.66725)
			(end 24.67102 -3.697478)
			(stroke
				(width 0.1)
				(type default)
			)
			(layer "F.SilkS")
		)
		(fp_line
			(start 25.681686 -4.66725)
			(end 24.67102 -3.697478)
			(stroke
				(width 0.1)
				(type default)
			)
			(layer "F.SilkS")
		)
		(fp_line
			(start 25.68448 -3.054096)
			(end 25.696926 -3.123184)
			(stroke
				(width 0.1)
				(type default)
			)
			(layer "F.SilkS")
		)
		(fp_line
			(start 25.68448 -3.054096)
			(end 25.696926 -3.123184)
			(stroke
				(width 0.1)
				(type default)
			)
			(layer "F.SilkS")
		)
		(fp_line
			(start 25.696926 -3.123184)
			(end 25.708864 -3.19278)
			(stroke
				(width 0.1)
				(type default)
			)
			(layer "F.SilkS")
		)
		(fp_line
			(start 25.696926 -3.123184)
			(end 25.708864 -3.19278)
			(stroke
				(width 0.1)
				(type default)
			)
			(layer "F.SilkS")
		)
		(fp_line
			(start 25.701498 -4.628388)
			(end 24.658574 -3.627882)
			(stroke
				(width 0.1)
				(type default)
			)
			(layer "F.SilkS")
		)
		(fp_line
			(start 25.701498 -4.628388)
			(end 24.658574 -3.627882)
			(stroke
				(width 0.1)
				(type default)
			)
			(layer "F.SilkS")
		)
		(fp_line
			(start 25.708864 -3.19278)
			(end 25.721056 -3.262122)
			(stroke
				(width 0.1)
				(type default)
			)
			(layer "F.SilkS")
		)
		(fp_line
			(start 25.708864 -3.19278)
			(end 25.721056 -3.262122)
			(stroke
				(width 0.1)
				(type default)
			)
			(layer "F.SilkS")
		)
		(fp_line
			(start 25.718516 -4.586986)
			(end 23.913084 -2.85496)
			(stroke
				(width 0.1)
				(type default)
			)
			(layer "F.SilkS")
		)
		(fp_line
			(start 25.718516 -4.586986)
			(end 23.913084 -2.85496)
			(stroke
				(width 0.1)
				(type default)
			)
			(layer "F.SilkS")
		)
		(fp_line
			(start 25.721056 -3.262122)
			(end 25.733502 -3.331464)
			(stroke
				(width 0.1)
				(type default)
			)
			(layer "F.SilkS")
		)
		(fp_line
			(start 25.721056 -3.262122)
			(end 25.733502 -3.331464)
			(stroke
				(width 0.1)
				(type default)
			)
			(layer "F.SilkS")
		)
		(fp_line
			(start 25.733502 -3.331464)
			(end 25.74544 -3.400806)
			(stroke
				(width 0.1)
				(type default)
			)
			(layer "F.SilkS")
		)
		(fp_line
			(start 25.733502 -3.331464)
			(end 25.74544 -3.400806)
			(stroke
				(width 0.1)
				(type default)
			)
			(layer "F.SilkS")
		)
		(fp_line
			(start 25.735534 -4.54533)
			(end 23.969472 -2.85115)
			(stroke
				(width 0.1)
				(type default)
			)
			(layer "F.SilkS")
		)
		(fp_line
			(start 25.735534 -4.54533)
			(end 23.969472 -2.85115)
			(stroke
				(width 0.1)
				(type default)
			)
			(layer "F.SilkS")
		)
		(fp_line
			(start 25.74544 -3.400806)
			(end 23.034752 -0.800608)
			(stroke
				(width 0.1)
				(type default)
			)
			(layer "F.SilkS")
		)
		(fp_line
			(start 25.74544 -3.400806)
			(end 23.034752 -0.800608)
			(stroke
				(width 0.1)
				(type default)
			)
			(layer "F.SilkS")
		)
		(fp_line
			(start 25.74544 -3.400806)
			(end 25.757632 -3.470402)
			(stroke
				(width 0.1)
				(type default)
			)
			(layer "F.SilkS")
		)
		(fp_line
			(start 25.74544 -3.400806)
			(end 25.757632 -3.470402)
			(stroke
				(width 0.1)
				(type default)
			)
			(layer "F.SilkS")
		)
		(fp_line
			(start 25.752298 -4.503928)
			(end 24.024336 -2.846324)
			(stroke
				(width 0.1)
				(type default)
			)
			(layer "F.SilkS")
		)
		(fp_line
			(start 25.752298 -4.503928)
			(end 24.024336 -2.846324)
			(stroke
				(width 0.1)
				(type default)
			)
			(layer "F.SilkS")
		)
		(fp_line
			(start 25.757632 -3.470402)
			(end 24.402796 -2.170938)
			(stroke
				(width 0.1)
				(type default)
			)
			(layer "F.SilkS")
		)
		(fp_line
			(start 25.757632 -3.470402)
			(end 24.402796 -2.170938)
			(stroke
				(width 0.1)
				(type default)
			)
			(layer "F.SilkS")
		)
		(fp_line
			(start 25.757632 -3.470402)
			(end 25.769824 -3.539744)
			(stroke
				(width 0.1)
				(type default)
			)
			(layer "F.SilkS")
		)
		(fp_line
			(start 25.757632 -3.470402)
			(end 25.769824 -3.539744)
			(stroke
				(width 0.1)
				(type default)
			)
			(layer "F.SilkS")
		)
		(fp_line
			(start 25.769316 -4.46278)
			(end 24.076914 -2.839466)
			(stroke
				(width 0.1)
				(type default)
			)
			(layer "F.SilkS")
		)
		(fp_line
			(start 25.769316 -4.46278)
			(end 24.076914 -2.839466)
			(stroke
				(width 0.1)
				(type default)
			)
			(layer "F.SilkS")
		)
		(fp_line
			(start 25.769824 -3.539744)
			(end 24.414988 -2.24028)
			(stroke
				(width 0.1)
				(type default)
			)
			(layer "F.SilkS")
		)
		(fp_line
			(start 25.769824 -3.539744)
			(end 24.414988 -2.24028)
			(stroke
				(width 0.1)
				(type default)
			)
			(layer "F.SilkS")
		)
		(fp_line
			(start 25.769824 -3.539744)
			(end 25.782016 -3.609086)
			(stroke
				(width 0.1)
				(type default)
			)
			(layer "F.SilkS")
		)
		(fp_line
			(start 25.769824 -3.539744)
			(end 25.782016 -3.609086)
			(stroke
				(width 0.1)
				(type default)
			)
			(layer "F.SilkS")
		)
		(fp_line
			(start 25.782016 -3.609086)
			(end 24.427434 -2.309368)
			(stroke
				(width 0.1)
				(type default)
			)
			(layer "F.SilkS")
		)
		(fp_line
			(start 25.782016 -3.609086)
			(end 24.427434 -2.309368)
			(stroke
				(width 0.1)
				(type default)
			)
			(layer "F.SilkS")
		)
		(fp_line
			(start 25.782016 -3.609086)
			(end 25.793954 -3.678174)
			(stroke
				(width 0.1)
				(type default)
			)
			(layer "F.SilkS")
		)
		(fp_line
			(start 25.782016 -3.609086)
			(end 25.793954 -3.678174)
			(stroke
				(width 0.1)
				(type default)
			)
			(layer "F.SilkS")
		)
		(fp_line
			(start 25.786588 -4.421378)
			(end 24.12873 -2.831084)
			(stroke
				(width 0.1)
				(type default)
			)
			(layer "F.SilkS")
		)
		(fp_line
			(start 25.786588 -4.421378)
			(end 24.12873 -2.831084)
			(stroke
				(width 0.1)
				(type default)
			)
			(layer "F.SilkS")
		)
		(fp_line
			(start 25.793954 -3.678174)
			(end 24.439372 -2.37871)
			(stroke
				(width 0.1)
				(type default)
			)
			(layer "F.SilkS")
		)
		(fp_line
			(start 25.793954 -3.678174)
			(end 24.439372 -2.37871)
			(stroke
				(width 0.1)
				(type default)
			)
			(layer "F.SilkS")
		)
		(fp_line
			(start 25.793954 -3.678174)
			(end 25.806146 -3.74777)
			(stroke
				(width 0.1)
				(type default)
			)
			(layer "F.SilkS")
		)
		(fp_line
			(start 25.793954 -3.678174)
			(end 25.806146 -3.74777)
			(stroke
				(width 0.1)
				(type default)
			)
			(layer "F.SilkS")
		)
		(fp_line
			(start 25.798526 -4.37515)
			(end 24.17826 -2.82067)
			(stroke
				(width 0.1)
				(type default)
			)
			(layer "F.SilkS")
		)
		(fp_line
			(start 25.798526 -4.37515)
			(end 24.17826 -2.82067)
			(stroke
				(width 0.1)
				(type default)
			)
			(layer "F.SilkS")
		)
		(fp_line
			(start 25.805384 -4.324096)
			(end 24.225504 -2.808478)
			(stroke
				(width 0.1)
				(type default)
			)
			(layer "F.SilkS")
		)
		(fp_line
			(start 25.805384 -4.324096)
			(end 24.225504 -2.808478)
			(stroke
				(width 0.1)
				(type default)
			)
			(layer "F.SilkS")
		)
		(fp_line
			(start 25.806146 -3.74777)
			(end 24.451564 -2.448306)
			(stroke
				(width 0.1)
				(type default)
			)
			(layer "F.SilkS")
		)
		(fp_line
			(start 25.806146 -3.74777)
			(end 24.451564 -2.448306)
			(stroke
				(width 0.1)
				(type default)
			)
			(layer "F.SilkS")
		)
		(fp_line
			(start 25.812242 -4.273296)
			(end 24.27097 -2.794508)
			(stroke
				(width 0.1)
				(type default)
			)
			(layer "F.SilkS")
		)
		(fp_line
			(start 25.812242 -4.273296)
			(end 24.27097 -2.794508)
			(stroke
				(width 0.1)
				(type default)
			)
			(layer "F.SilkS")
		)
		(fp_line
			(start 25.81275 -3.811524)
			(end 24.46401 -2.517648)
			(stroke
				(width 0.1)
				(type default)
			)
			(layer "F.SilkS")
		)
		(fp_line
			(start 25.81275 -3.811524)
			(end 24.46401 -2.517648)
			(stroke
				(width 0.1)
				(type default)
			)
			(layer "F.SilkS")
		)
		(fp_line
			(start 25.817576 -3.874008)
			(end 24.475948 -2.58699)
			(stroke
				(width 0.1)
				(type default)
			)
			(layer "F.SilkS")
		)
		(fp_line
			(start 25.817576 -3.874008)
			(end 24.475948 -2.58699)
			(stroke
				(width 0.1)
				(type default)
			)
			(layer "F.SilkS")
		)
		(fp_line
			(start 25.819608 -4.222242)
			(end 24.31415 -2.777998)
			(stroke
				(width 0.1)
				(type default)
			)
			(layer "F.SilkS")
		)
		(fp_line
			(start 25.819608 -4.222242)
			(end 24.31415 -2.777998)
			(stroke
				(width 0.1)
				(type default)
			)
			(layer "F.SilkS")
		)
		(fp_line
			(start 25.822656 -3.936492)
			(end 24.487886 -2.656332)
			(stroke
				(width 0.1)
				(type default)
			)
			(layer "F.SilkS")
		)
		(fp_line
			(start 25.822656 -3.936492)
			(end 24.487886 -2.656332)
			(stroke
				(width 0.1)
				(type default)
			)
			(layer "F.SilkS")
		)
		(fp_line
			(start 25.826466 -4.170934)
			(end 24.35606 -2.760472)
			(stroke
				(width 0.1)
				(type default)
			)
			(layer "F.SilkS")
		)
		(fp_line
			(start 25.826466 -4.170934)
			(end 24.35606 -2.760472)
			(stroke
				(width 0.1)
				(type default)
			)
			(layer "F.SilkS")
		)
		(fp_line
			(start 25.827736 -3.99923)
			(end 24.468836 -2.695448)
			(stroke
				(width 0.1)
				(type default)
			)
			(layer "F.SilkS")
		)
		(fp_line
			(start 25.827736 -3.99923)
			(end 24.468836 -2.695448)
			(stroke
				(width 0.1)
				(type default)
			)
			(layer "F.SilkS")
		)
		(fp_line
			(start 25.83307 -4.062222)
			(end 24.432514 -2.718816)
			(stroke
				(width 0.1)
				(type default)
			)
			(layer "F.SilkS")
		)
		(fp_line
			(start 25.83307 -4.062222)
			(end 24.432514 -2.718816)
			(stroke
				(width 0.1)
				(type default)
			)
			(layer "F.SilkS")
		)
		(fp_line
			(start 25.833324 -4.120134)
			(end 24.394668 -2.739898)
			(stroke
				(width 0.1)
				(type default)
			)
			(layer "F.SilkS")
		)
		(fp_line
			(start 25.833324 -4.120134)
			(end 24.394668 -2.739898)
			(stroke
				(width 0.1)
				(type default)
			)
			(layer "F.SilkS")
		)
	)
	(footprint ""
		(layer "F.Cu")
		(at 18.415 -183.896 180)
		(property "Reference" "R5466"
			(at 0 0 180)
			(layer "F.SilkS")
			(hide yes)
			(effects
				(font
					(size 1.27 1.27)
				)
			)
		)
		(property "Value" ""
			(at 0 0 180)
			(layer "F.Fab")
			(effects
				(font
					(size 1.27 1.27)
				)
			)
		)
		(duplicate_pad_numbers_are_jumpers no)
		(fp_line
			(start 0.7874 0.4064)
			(end -0.7874 0.4064)
			(stroke
				(width 0.1524)
				(type default)
			)
			(layer "F.SilkS")
		)
		(fp_line
			(start 0.7874 -0.4064)
			(end 0.7874 0.4064)
			(stroke
				(width 0.1524)
				(type default)
			)
			(layer "F.SilkS")
		)
		(fp_line
			(start -0.7874 0.4064)
			(end -0.7874 -0.4064)
			(stroke
				(width 0.1524)
				(type default)
			)
			(layer "F.SilkS")
		)
		(fp_line
			(start -0.7874 -0.4064)
			(end 0.7874 -0.4064)
			(stroke
				(width 0.1524)
				(type default)
			)
			(layer "F.SilkS")
		)
		(fp_line
			(start 0.67945 0.3048)
			(end 0.120396 0.3048)
			(stroke
				(width 0.1)
				(type default)
			)
			(layer "F.Fab")
		)
		(fp_line
			(start 0.67945 -0.3048)
			(end 0.67945 0.3048)
			(stroke
				(width 0.1)
				(type default)
			)
			(layer "F.Fab")
		)
		(fp_line
			(start 0.12065 -0.2794)
			(end 0.12065 -0.3048)
			(stroke
				(width 0.1)
				(type default)
			)
			(layer "F.Fab")
		)
		(fp_line
			(start 0.12065 -0.3048)
			(end 0.67945 -0.3048)
			(stroke
				(width 0.1)
				(type default)
			)
			(layer "F.Fab")
		)
		(fp_line
			(start 0.120396 0.3048)
			(end 0.120396 0.2794)
			(stroke
				(width 0.1)
				(type default)
			)
			(layer "F.Fab")
		)
		(fp_line
			(start 0.120396 0.2794)
			(end -0.12065 0.2794)
			(stroke
				(width 0.1)
				(type default)
			)
			(layer "F.Fab")
		)
		(fp_line
			(start -0.12065 0.3048)
			(end -0.67945 0.3048)
			(stroke
				(width 0.1)
				(type default)
			)
			(layer "F.Fab")
		)
		(fp_line
			(start -0.12065 0.2794)
			(end -0.12065 0.3048)
			(stroke
				(width 0.1)
				(type default)
			)
			(layer "F.Fab")
		)
		(fp_line
			(start -0.12065 -0.2794)
			(end 0.12065 -0.2794)
			(stroke
				(width 0.1)
				(type default)
			)
			(layer "F.Fab")
		)
		(fp_line
			(start -0.12065 -0.305054)
			(end -0.12065 -0.2794)
			(stroke
				(width 0.1)
				(type default)
			)
			(layer "F.Fab")
		)
		(fp_line
			(start -0.67945 0.3048)
			(end -0.67945 -0.305054)
			(stroke
				(width 0.1)
				(type default)
			)
			(layer "F.Fab")
		)
		(fp_line
			(start -0.67945 -0.305054)
			(end -0.12065 -0.305054)
			(stroke
				(width 0.1)
				(type default)
			)
			(layer "F.Fab")
		)
		(pad "1" smd circle
			(at -0.40005 0 180)
			(size 0 0)
			(layers "F.Cu" "F.Mask" "F.Paste")
			(net "SMB_PDBV_FAN_SDA")
		)
		(pad "2" smd circle
			(at 0.40005 0 180)
			(size 0 0)
			(layers "F.Cu" "F.Mask" "F.Paste")
			(net "SMB_PDBV_FAN_R_IOX_SDA")
		)
	)
	(footprint ""
		(layer "F.Cu")
		(at 6.604 -123.698)
		(property "Reference" "R5702"
			(at 0 0 0)
			(layer "F.SilkS")
			(hide yes)
			(effects
				(font
					(size 1.27 1.27)
				)
			)
		)
		(property "Value" ""
			(at 0 0 0)
			(layer "F.Fab")
			(effects
				(font
					(size 1.27 1.27)
				)
			)
		)
		(duplicate_pad_numbers_are_jumpers no)
		(fp_line
			(start -0.7874 -0.4064)
			(end 0.7874 -0.4064)
			(stroke
				(width 0.1524)
				(type default)
			)
			(layer "F.SilkS")
		)
		(fp_line
			(start -0.7874 0.4064)
			(end -0.7874 -0.4064)
			(stroke
				(width 0.1524)
				(type default)
			)
			(layer "F.SilkS")
		)
		(fp_line
			(start 0.7874 -0.4064)
			(end 0.7874 0.4064)
			(stroke
				(width 0.1524)
				(type default)
			)
			(layer "F.SilkS")
		)
		(fp_line
			(start 0.7874 0.4064)
			(end -0.7874 0.4064)
			(stroke
				(width 0.1524)
				(type default)
			)
			(layer "F.SilkS")
		)
		(fp_line
			(start -0.67945 -0.305054)
			(end -0.12065 -0.305054)
			(stroke
				(width 0.1)
				(type default)
			)
			(layer "F.Fab")
		)
		(fp_line
			(start -0.67945 0.3048)
			(end -0.67945 -0.305054)
			(stroke
				(width 0.1)
				(type default)
			)
			(layer "F.Fab")
		)
		(fp_line
			(start -0.12065 -0.305054)
			(end -0.12065 -0.2794)
			(stroke
				(width 0.1)
				(type default)
			)
			(layer "F.Fab")
		)
		(fp_line
			(start -0.12065 -0.2794)
			(end 0.12065 -0.2794)
			(stroke
				(width 0.1)
				(type default)
			)
			(layer "F.Fab")
		)
		(fp_line
			(start -0.12065 0.2794)
			(end -0.12065 0.3048)
			(stroke
				(width 0.1)
				(type default)
			)
			(layer "F.Fab")
		)
		(fp_line
			(start -0.12065 0.3048)
			(end -0.67945 0.3048)
			(stroke
				(width 0.1)
				(type default)
			)
			(layer "F.Fab")
		)
		(fp_line
			(start 0.120396 0.2794)
			(end -0.12065 0.2794)
			(stroke
				(width 0.1)
				(type default)
			)
			(layer "F.Fab")
		)
		(fp_line
			(start 0.120396 0.3048)
			(end 0.120396 0.2794)
			(stroke
				(width 0.1)
				(type default)
			)
			(layer "F.Fab")
		)
		(fp_line
			(start 0.12065 -0.3048)
			(end 0.67945 -0.3048)
			(stroke
				(width 0.1)
				(type default)
			)
			(layer "F.Fab")
		)
		(fp_line
			(start 0.12065 -0.2794)
			(end 0.12065 -0.3048)
			(stroke
				(width 0.1)
				(type default)
			)
			(layer "F.Fab")
		)
		(fp_line
			(start 0.67945 -0.3048)
			(end 0.67945 0.3048)
			(stroke
				(width 0.1)
				(type default)
			)
			(layer "F.Fab")
		)
		(fp_line
			(start 0.67945 0.3048)
			(end 0.120396 0.3048)
			(stroke
				(width 0.1)
				(type default)
			)
			(layer "F.Fab")
		)
		(pad "1" smd rect
			(at -0.40005 0 180)
			(size 0.4572 0.508)
			(layers "F.Cu" "F.Mask" "F.Paste")
			(net "P12V_LED_R_FAN5")
		)
		(pad "2" smd rect
			(at 0.40005 0 180)
			(size 0.4572 0.508)
			(layers "F.Cu" "F.Mask" "F.Paste")
			(net "P12V_LED_R1_FAN5")
		)
	)
	(footprint ""
		(layer "F.Cu")
		(at 6.477 -162.814)
		(property "Reference" "R98"
			(at 0 0 0)
			(layer "F.SilkS")
			(hide yes)
			(effects
				(font
					(size 1.27 1.27)
				)
			)
		)
		(property "Value" ""
			(at 0 0 0)
			(layer "F.Fab")
			(effects
				(font
					(size 1.27 1.27)
				)
			)
		)
		(duplicate_pad_numbers_are_jumpers no)
		(fp_line
			(start -0.7874 -0.4064)
			(end 0.7874 -0.4064)
			(stroke
				(width 0.1524)
				(type default)
			)
			(layer "F.SilkS")
		)
		(fp_line
			(start -0.7874 0.4064)
			(end -0.7874 -0.4064)
			(stroke
				(width 0.1524)
				(type default)
			)
			(layer "F.SilkS")
		)
		(fp_line
			(start 0.7874 -0.4064)
			(end 0.7874 0.4064)
			(stroke
				(width 0.1524)
				(type default)
			)
			(layer "F.SilkS")
		)
		(fp_line
			(start 0.7874 0.4064)
			(end -0.7874 0.4064)
			(stroke
				(width 0.1524)
				(type default)
			)
			(layer "F.SilkS")
		)
		(fp_line
			(start -0.67945 -0.305054)
			(end -0.12065 -0.305054)
			(stroke
				(width 0.1)
				(type default)
			)
			(layer "F.Fab")
		)
		(fp_line
			(start -0.67945 0.3048)
			(end -0.67945 -0.305054)
			(stroke
				(width 0.1)
				(type default)
			)
			(layer "F.Fab")
		)
		(fp_line
			(start -0.12065 -0.305054)
			(end -0.12065 -0.2794)
			(stroke
				(width 0.1)
				(type default)
			)
			(layer "F.Fab")
		)
		(fp_line
			(start -0.12065 -0.2794)
			(end 0.12065 -0.2794)
			(stroke
				(width 0.1)
				(type default)
			)
			(layer "F.Fab")
		)
		(fp_line
			(start -0.12065 0.2794)
			(end -0.12065 0.3048)
			(stroke
				(width 0.1)
				(type default)
			)
			(layer "F.Fab")
		)
		(fp_line
			(start -0.12065 0.3048)
			(end -0.67945 0.3048)
			(stroke
				(width 0.1)
				(type default)
			)
			(layer "F.Fab")
		)
		(fp_line
			(start 0.120396 0.2794)
			(end -0.12065 0.2794)
			(stroke
				(width 0.1)
				(type default)
			)
			(layer "F.Fab")
		)
		(fp_line
			(start 0.120396 0.3048)
			(end 0.120396 0.2794)
			(stroke
				(width 0.1)
				(type default)
			)
			(layer "F.Fab")
		)
		(fp_line
			(start 0.12065 -0.3048)
			(end 0.67945 -0.3048)
			(stroke
				(width 0.1)
				(type default)
			)
			(layer "F.Fab")
		)
		(fp_line
			(start 0.12065 -0.2794)
			(end 0.12065 -0.3048)
			(stroke
				(width 0.1)
				(type default)
			)
			(layer "F.Fab")
		)
		(fp_line
			(start 0.67945 -0.3048)
			(end 0.67945 0.3048)
			(stroke
				(width 0.1)
				(type default)
			)
			(layer "F.Fab")
		)
		(fp_line
			(start 0.67945 0.3048)
			(end 0.120396 0.3048)
			(stroke
				(width 0.1)
				(type default)
			)
			(layer "F.Fab")
		)
		(pad "1" smd circle
			(at -0.40005 0)
			(size 0 0)
			(layers "F.Cu" "F.Mask" "F.Paste")
			(net "P3V3_AUX")
		)
		(pad "2" smd circle
			(at 0.40005 0)
			(size 0 0)
			(layers "F.Cu" "F.Mask" "F.Paste")
			(net "FAN_0_PRSNT_BUF_R_N")
		)
	)
	(footprint ""
		(layer "F.Cu")
		(at 43.561 -170.815)
		(property "Reference" "R5095"
			(at 0 0 0)
			(layer "F.SilkS")
			(hide yes)
			(effects
				(font
					(size 1.27 1.27)
				)
			)
		)
		(property "Value" ""
			(at 0 0 0)
			(layer "F.Fab")
			(effects
				(font
					(size 1.27 1.27)
				)
			)
		)
		(duplicate_pad_numbers_are_jumpers no)
		(fp_line
			(start -0.7874 -0.4064)
			(end 0.7874 -0.4064)
			(stroke
				(width 0.1524)
				(type default)
			)
			(layer "F.SilkS")
		)
		(fp_line
			(start -0.7874 0.4064)
			(end -0.7874 -0.4064)
			(stroke
				(width 0.1524)
				(type default)
			)
			(layer "F.SilkS")
		)
		(fp_line
			(start 0.7874 -0.4064)
			(end 0.7874 0.4064)
			(stroke
				(width 0.1524)
				(type default)
			)
			(layer "F.SilkS")
		)
		(fp_line
			(start 0.7874 0.4064)
			(end -0.7874 0.4064)
			(stroke
				(width 0.1524)
				(type default)
			)
			(layer "F.SilkS")
		)
		(fp_line
			(start -0.67945 -0.305054)
			(end -0.12065 -0.305054)
			(stroke
				(width 0.1)
				(type default)
			)
			(layer "F.Fab")
		)
		(fp_line
			(start -0.67945 0.3048)
			(end -0.67945 -0.305054)
			(stroke
				(width 0.1)
				(type default)
			)
			(layer "F.Fab")
		)
		(fp_line
			(start -0.12065 -0.305054)
			(end -0.12065 -0.2794)
			(stroke
				(width 0.1)
				(type default)
			)
			(layer "F.Fab")
		)
		(fp_line
			(start -0.12065 -0.2794)
			(end 0.12065 -0.2794)
			(stroke
				(width 0.1)
				(type default)
			)
			(layer "F.Fab")
		)
		(fp_line
			(start -0.12065 0.2794)
			(end -0.12065 0.3048)
			(stroke
				(width 0.1)
				(type default)
			)
			(layer "F.Fab")
		)
		(fp_line
			(start -0.12065 0.3048)
			(end -0.67945 0.3048)
			(stroke
				(width 0.1)
				(type default)
			)
			(layer "F.Fab")
		)
		(fp_line
			(start 0.120396 0.2794)
			(end -0.12065 0.2794)
			(stroke
				(width 0.1)
				(type default)
			)
			(layer "F.Fab")
		)
		(fp_line
			(start 0.120396 0.3048)
			(end 0.120396 0.2794)
			(stroke
				(width 0.1)
				(type default)
			)
			(layer "F.Fab")
		)
		(fp_line
			(start 0.12065 -0.3048)
			(end 0.67945 -0.3048)
			(stroke
				(width 0.1)
				(type default)
			)
			(layer "F.Fab")
		)
		(fp_line
			(start 0.12065 -0.2794)
			(end 0.12065 -0.3048)
			(stroke
				(width 0.1)
				(type default)
			)
			(layer "F.Fab")
		)
		(fp_line
			(start 0.67945 -0.3048)
			(end 0.67945 0.3048)
			(stroke
				(width 0.1)
				(type default)
			)
			(layer "F.Fab")
		)
		(fp_line
			(start 0.67945 0.3048)
			(end 0.120396 0.3048)
			(stroke
				(width 0.1)
				(type default)
			)
			(layer "F.Fab")
		)
		(pad "1" smd circle
			(at -0.40005 0)
			(size 0 0)
			(layers "F.Cu" "F.Mask" "F.Paste")
			(net "FAN_0_FAIL_LED")
		)
		(pad "2" smd circle
			(at 0.40005 0)
			(size 0 0)
			(layers "F.Cu" "F.Mask" "F.Paste")
			(net "FAN_0_FAIL_R_LED")
		)
	)
	(footprint ""
		(layer "F.Cu")
		(at 28.956 -174.625 180)
		(property "Reference" "R5105"
			(at 0 0 180)
			(layer "F.SilkS")
			(hide yes)
			(effects
				(font
					(size 1.27 1.27)
				)
			)
		)
		(property "Value" ""
			(at 0 0 180)
			(layer "F.Fab")
			(effects
				(font
					(size 1.27 1.27)
				)
			)
		)
		(duplicate_pad_numbers_are_jumpers no)
		(fp_line
			(start 0.7874 0.4064)
			(end -0.7874 0.4064)
			(stroke
				(width 0.1524)
				(type default)
			)
			(layer "F.SilkS")
		)
		(fp_line
			(start 0.7874 -0.4064)
			(end 0.7874 0.4064)
			(stroke
				(width 0.1524)
				(type default)
			)
			(layer "F.SilkS")
		)
		(fp_line
			(start -0.7874 0.4064)
			(end -0.7874 -0.4064)
			(stroke
				(width 0.1524)
				(type default)
			)
			(layer "F.SilkS")
		)
		(fp_line
			(start -0.7874 -0.4064)
			(end 0.7874 -0.4064)
			(stroke
				(width 0.1524)
				(type default)
			)
			(layer "F.SilkS")
		)
		(fp_line
			(start 0.67945 0.3048)
			(end 0.120396 0.3048)
			(stroke
				(width 0.1)
				(type default)
			)
			(layer "F.Fab")
		)
		(fp_line
			(start 0.67945 -0.3048)
			(end 0.67945 0.3048)
			(stroke
				(width 0.1)
				(type default)
			)
			(layer "F.Fab")
		)
		(fp_line
			(start 0.12065 -0.2794)
			(end 0.12065 -0.3048)
			(stroke
				(width 0.1)
				(type default)
			)
			(layer "F.Fab")
		)
		(fp_line
			(start 0.12065 -0.3048)
			(end 0.67945 -0.3048)
			(stroke
				(width 0.1)
				(type default)
			)
			(layer "F.Fab")
		)
		(fp_line
			(start 0.120396 0.3048)
			(end 0.120396 0.2794)
			(stroke
				(width 0.1)
				(type default)
			)
			(layer "F.Fab")
		)
		(fp_line
			(start 0.120396 0.2794)
			(end -0.12065 0.2794)
			(stroke
				(width 0.1)
				(type default)
			)
			(layer "F.Fab")
		)
		(fp_line
			(start -0.12065 0.3048)
			(end -0.67945 0.3048)
			(stroke
				(width 0.1)
				(type default)
			)
			(layer "F.Fab")
		)
		(fp_line
			(start -0.12065 0.2794)
			(end -0.12065 0.3048)
			(stroke
				(width 0.1)
				(type default)
			)
			(layer "F.Fab")
		)
		(fp_line
			(start -0.12065 -0.2794)
			(end 0.12065 -0.2794)
			(stroke
				(width 0.1)
				(type default)
			)
			(layer "F.Fab")
		)
		(fp_line
			(start -0.12065 -0.305054)
			(end -0.12065 -0.2794)
			(stroke
				(width 0.1)
				(type default)
			)
			(layer "F.Fab")
		)
		(fp_line
			(start -0.67945 0.3048)
			(end -0.67945 -0.305054)
			(stroke
				(width 0.1)
				(type default)
			)
			(layer "F.Fab")
		)
		(fp_line
			(start -0.67945 -0.305054)
			(end -0.12065 -0.305054)
			(stroke
				(width 0.1)
				(type default)
			)
			(layer "F.Fab")
		)
		(pad "1" smd circle
			(at -0.40005 0 180)
			(size 0 0)
			(layers "F.Cu" "F.Mask" "F.Paste")
			(net "FAN_5_FAIL_LED")
		)
		(pad "2" smd circle
			(at 0.40005 0 180)
			(size 0 0)
			(layers "F.Cu" "F.Mask" "F.Paste")
			(net "FAN_5_FAIL_R_LED")
		)
	)
	(footprint ""
		(layer "F.Cu")
		(at 39.206932 -71.812912)
		(property "Reference" "C2069"
			(at 0 0 0)
			(layer "F.SilkS")
			(hide yes)
			(effects
				(font
					(size 1.27 1.27)
				)
			)
		)
		(property "Value" ""
			(at 0 0 0)
			(layer "F.Fab")
			(effects
				(font
					(size 1.27 1.27)
				)
			)
		)
		(duplicate_pad_numbers_are_jumpers no)
		(fp_line
			(start -0.7874 -0.4064)
			(end 0.7874 -0.4064)
			(stroke
				(width 0.1524)
				(type default)
			)
			(layer "F.SilkS")
		)
		(fp_line
			(start -0.7874 0.4064)
			(end -0.7874 -0.4064)
			(stroke
				(width 0.1524)
				(type default)
			)
			(layer "F.SilkS")
		)
		(fp_line
			(start 0.7874 -0.4064)
			(end 0.7874 0.4064)
			(stroke
				(width 0.1524)
				(type default)
			)
			(layer "F.SilkS")
		)
		(fp_line
			(start 0.7874 0.4064)
			(end -0.7874 0.4064)
			(stroke
				(width 0.1524)
				(type default)
			)
			(layer "F.SilkS")
		)
		(fp_line
			(start -0.67945 -0.305054)
			(end -0.12065 -0.305054)
			(stroke
				(width 0.1)
				(type default)
			)
			(layer "F.Fab")
		)
		(fp_line
			(start -0.67945 0.3048)
			(end -0.67945 -0.305054)
			(stroke
				(width 0.1)
				(type default)
			)
			(layer "F.Fab")
		)
		(fp_line
			(start -0.12065 -0.305054)
			(end -0.12065 -0.2794)
			(stroke
				(width 0.1)
				(type default)
			)
			(layer "F.Fab")
		)
		(fp_line
			(start -0.12065 -0.2794)
			(end 0.12065 -0.2794)
			(stroke
				(width 0.1)
				(type default)
			)
			(layer "F.Fab")
		)
		(fp_line
			(start -0.12065 0.2794)
			(end -0.12065 0.3048)
			(stroke
				(width 0.1)
				(type default)
			)
			(layer "F.Fab")
		)
		(fp_line
			(start -0.12065 0.3048)
			(end -0.67945 0.3048)
			(stroke
				(width 0.1)
				(type default)
			)
			(layer "F.Fab")
		)
		(fp_line
			(start 0.120396 0.2794)
			(end -0.12065 0.2794)
			(stroke
				(width 0.1)
				(type default)
			)
			(layer "F.Fab")
		)
		(fp_line
			(start 0.120396 0.3048)
			(end 0.120396 0.2794)
			(stroke
				(width 0.1)
				(type default)
			)
			(layer "F.Fab")
		)
		(fp_line
			(start 0.12065 -0.3048)
			(end 0.67945 -0.3048)
			(stroke
				(width 0.1)
				(type default)
			)
			(layer "F.Fab")
		)
		(fp_line
			(start 0.12065 -0.2794)
			(end 0.12065 -0.3048)
			(stroke
				(width 0.1)
				(type default)
			)
			(layer "F.Fab")
		)
		(fp_line
			(start 0.67945 -0.3048)
			(end 0.67945 0.3048)
			(stroke
				(width 0.1)
				(type default)
			)
			(layer "F.Fab")
		)
		(fp_line
			(start 0.67945 0.3048)
			(end 0.120396 0.3048)
			(stroke
				(width 0.1)
				(type default)
			)
			(layer "F.Fab")
		)
		(pad "1" smd circle
			(at -0.40005 0)
			(size 0 0)
			(layers "F.Cu" "F.Mask" "F.Paste")
			(net "P3V3_AUX")
		)
		(pad "2" smd circle
			(at 0.40005 0)
			(size 0 0)
			(layers "F.Cu" "F.Mask" "F.Paste")
			(net "GND")
		)
	)
	(footprint ""
		(layer "F.Cu")
		(at 34.417 -121.92 90)
		(property "Reference" "R4935"
			(at 0 0 90)
			(layer "F.SilkS")
			(hide yes)
			(effects
				(font
					(size 1.27 1.27)
				)
			)
		)
		(property "Value" ""
			(at 0 0 90)
			(layer "F.Fab")
			(effects
				(font
					(size 1.27 1.27)
				)
			)
		)
		(duplicate_pad_numbers_are_jumpers no)
		(fp_line
			(start 0.7874 -0.4064)
			(end 0.7874 0.4064)
			(stroke
				(width 0.1524)
				(type default)
			)
			(layer "F.SilkS")
		)
		(fp_line
			(start -0.7874 -0.4064)
			(end 0.7874 -0.4064)
			(stroke
				(width 0.1524)
				(type default)
			)
			(layer "F.SilkS")
		)
		(fp_line
			(start 0.7874 0.4064)
			(end -0.7874 0.4064)
			(stroke
				(width 0.1524)
				(type default)
			)
			(layer "F.SilkS")
		)
		(fp_line
			(start -0.7874 0.4064)
			(end -0.7874 -0.4064)
			(stroke
				(width 0.1524)
				(type default)
			)
			(layer "F.SilkS")
		)
		(fp_line
			(start -0.12065 -0.305054)
			(end -0.12065 -0.2794)
			(stroke
				(width 0.1)
				(type default)
			)
			(layer "F.Fab")
		)
		(fp_line
			(start -0.67945 -0.305054)
			(end -0.12065 -0.305054)
			(stroke
				(width 0.1)
				(type default)
			)
			(layer "F.Fab")
		)
		(fp_line
			(start 0.67945 -0.3048)
			(end 0.67945 0.3048)
			(stroke
				(width 0.1)
				(type default)
			)
			(layer "F.Fab")
		)
		(fp_line
			(start 0.12065 -0.3048)
			(end 0.67945 -0.3048)
			(stroke
				(width 0.1)
				(type default)
			)
			(layer "F.Fab")
		)
		(fp_line
			(start 0.12065 -0.2794)
			(end 0.12065 -0.3048)
			(stroke
				(width 0.1)
				(type default)
			)
			(layer "F.Fab")
		)
		(fp_line
			(start -0.12065 -0.2794)
			(end 0.12065 -0.2794)
			(stroke
				(width 0.1)
				(type default)
			)
			(layer "F.Fab")
		)
		(fp_line
			(start 0.120396 0.2794)
			(end -0.12065 0.2794)
			(stroke
				(width 0.1)
				(type default)
			)
			(layer "F.Fab")
		)
		(fp_line
			(start -0.12065 0.2794)
			(end -0.12065 0.3048)
			(stroke
				(width 0.1)
				(type default)
			)
			(layer "F.Fab")
		)
		(fp_line
			(start 0.67945 0.3048)
			(end 0.120396 0.3048)
			(stroke
				(width 0.1)
				(type default)
			)
			(layer "F.Fab")
		)
		(fp_line
			(start 0.120396 0.3048)
			(end 0.120396 0.2794)
			(stroke
				(width 0.1)
				(type default)
			)
			(layer "F.Fab")
		)
		(fp_line
			(start -0.12065 0.3048)
			(end -0.67945 0.3048)
			(stroke
				(width 0.1)
				(type default)
			)
			(layer "F.Fab")
		)
		(fp_line
			(start -0.67945 0.3048)
			(end -0.67945 -0.305054)
			(stroke
				(width 0.1)
				(type default)
			)
			(layer "F.Fab")
		)
		(pad "1" smd circle
			(at -0.40005 0 90)
			(size 0 0)
			(layers "F.Cu" "F.Mask" "F.Paste")
			(net "GND")
		)
		(pad "2" smd circle
			(at 0.40005 0 90)
			(size 0 0)
			(layers "F.Cu" "F.Mask" "F.Paste")
			(net "MAX31790_U317_WD_START")
		)
	)
	(footprint ""
		(layer "F.Cu")
		(at 25.4 -30.734 90)
		(property "Reference" "R5666"
			(at 0 0 90)
			(layer "F.SilkS")
			(hide yes)
			(effects
				(font
					(size 1.27 1.27)
				)
			)
		)
		(property "Value" ""
			(at 0 0 90)
			(layer "F.Fab")
			(effects
				(font
					(size 1.27 1.27)
				)
			)
		)
		(duplicate_pad_numbers_are_jumpers no)
		(fp_line
			(start 0.7874 -0.4064)
			(end 0.7874 0.4064)
			(stroke
				(width 0.1524)
				(type default)
			)
			(layer "F.SilkS")
		)
		(fp_line
			(start -0.7874 -0.4064)
			(end 0.7874 -0.4064)
			(stroke
				(width 0.1524)
				(type default)
			)
			(layer "F.SilkS")
		)
		(fp_line
			(start 0.7874 0.4064)
			(end -0.7874 0.4064)
			(stroke
				(width 0.1524)
				(type default)
			)
			(layer "F.SilkS")
		)
		(fp_line
			(start -0.7874 0.4064)
			(end -0.7874 -0.4064)
			(stroke
				(width 0.1524)
				(type default)
			)
			(layer "F.SilkS")
		)
		(fp_line
			(start -0.12065 -0.305054)
			(end -0.12065 -0.2794)
			(stroke
				(width 0.1)
				(type default)
			)
			(layer "F.Fab")
		)
		(fp_line
			(start -0.67945 -0.305054)
			(end -0.12065 -0.305054)
			(stroke
				(width 0.1)
				(type default)
			)
			(layer "F.Fab")
		)
		(fp_line
			(start 0.67945 -0.3048)
			(end 0.67945 0.3048)
			(stroke
				(width 0.1)
				(type default)
			)
			(layer "F.Fab")
		)
		(fp_line
			(start 0.12065 -0.3048)
			(end 0.67945 -0.3048)
			(stroke
				(width 0.1)
				(type default)
			)
			(layer "F.Fab")
		)
		(fp_line
			(start 0.12065 -0.2794)
			(end 0.12065 -0.3048)
			(stroke
				(width 0.1)
				(type default)
			)
			(layer "F.Fab")
		)
		(fp_line
			(start -0.12065 -0.2794)
			(end 0.12065 -0.2794)
			(stroke
				(width 0.1)
				(type default)
			)
			(layer "F.Fab")
		)
		(fp_line
			(start 0.120396 0.2794)
			(end -0.12065 0.2794)
			(stroke
				(width 0.1)
				(type default)
			)
			(layer "F.Fab")
		)
		(fp_line
			(start -0.12065 0.2794)
			(end -0.12065 0.3048)
			(stroke
				(width 0.1)
				(type default)
			)
			(layer "F.Fab")
		)
		(fp_line
			(start 0.67945 0.3048)
			(end 0.120396 0.3048)
			(stroke
				(width 0.1)
				(type default)
			)
			(layer "F.Fab")
		)
		(fp_line
			(start 0.120396 0.3048)
			(end 0.120396 0.2794)
			(stroke
				(width 0.1)
				(type default)
			)
			(layer "F.Fab")
		)
		(fp_line
			(start -0.12065 0.3048)
			(end -0.67945 0.3048)
			(stroke
				(width 0.1)
				(type default)
			)
			(layer "F.Fab")
		)
		(fp_line
			(start -0.67945 0.3048)
			(end -0.67945 -0.305054)
			(stroke
				(width 0.1)
				(type default)
			)
			(layer "F.Fab")
		)
		(pad "1" smd circle
			(at -0.40005 0 90)
			(size 0 0)
			(layers "F.Cu" "F.Mask" "F.Paste")
			(net "FAN_4_PRESENT")
		)
		(pad "2" smd circle
			(at 0.40005 0 90)
			(size 0 0)
			(layers "F.Cu" "F.Mask" "F.Paste")
			(net "GND")
		)
	)
	(footprint ""
		(layer "F.Cu")
		(at 32.96285 -101.473)
		(property "Reference" "R5329"
			(at 0 0 0)
			(layer "F.SilkS")
			(hide yes)
			(effects
				(font
					(size 1.27 1.27)
				)
			)
		)
		(property "Value" ""
			(at 0 0 0)
			(layer "F.Fab")
			(effects
				(font
					(size 1.27 1.27)
				)
			)
		)
		(duplicate_pad_numbers_are_jumpers no)
		(fp_line
			(start -1.2954 -0.5842)
			(end 1.2954 -0.5842)
			(stroke
				(width 0.1524)
				(type default)
			)
			(layer "F.SilkS")
		)
		(fp_line
			(start -1.2954 0.5842)
			(end -1.2954 -0.5842)
			(stroke
				(width 0.1524)
				(type default)
			)
			(layer "F.SilkS")
		)
		(fp_line
			(start 1.2954 -0.5842)
			(end 1.2954 0.5842)
			(stroke
				(width 0.1524)
				(type default)
			)
			(layer "F.SilkS")
		)
		(fp_line
			(start 1.2954 0.5842)
			(end -1.2954 0.5842)
			(stroke
				(width 0.1524)
				(type default)
			)
			(layer "F.SilkS")
		)
		(fp_line
			(start -1.1938 -0.406654)
			(end -0.8636 -0.406654)
			(stroke
				(width 0.1)
				(type default)
			)
			(layer "F.Fab")
		)
		(fp_line
			(start -1.1938 0.4064)
			(end -1.1938 -0.406654)
			(stroke
				(width 0.1)
				(type default)
			)
			(layer "F.Fab")
		)
		(fp_line
			(start -0.8636 -0.4572)
			(end 0.8636 -0.4572)
			(stroke
				(width 0.1)
				(type default)
			)
			(layer "F.Fab")
		)
		(fp_line
			(start -0.8636 -0.406654)
			(end -0.8636 -0.4572)
			(stroke
				(width 0.1)
				(type default)
			)
			(layer "F.Fab")
		)
		(fp_line
			(start -0.8636 0.4064)
			(end -1.1938 0.4064)
			(stroke
				(width 0.1)
				(type default)
			)
			(layer "F.Fab")
		)
		(fp_line
			(start -0.8636 0.4318)
			(end -0.8636 0.4064)
			(stroke
				(width 0.1)
				(type default)
			)
			(layer "F.Fab")
		)
		(fp_line
			(start -0.8636 0.4572)
			(end -0.8636 0.4318)
			(stroke
				(width 0.1)
				(type default)
			)
			(layer "F.Fab")
		)
		(fp_line
			(start 0.8636 -0.4572)
			(end 0.8636 -0.406654)
			(stroke
				(width 0.1)
				(type default)
			)
			(layer "F.Fab")
		)
		(fp_line
			(start 0.8636 -0.406654)
			(end 1.1938 -0.406654)
			(stroke
				(width 0.1)
				(type default)
			)
			(layer "F.Fab")
		)
		(fp_line
			(start 0.8636 0.4064)
			(end 0.8636 0.4572)
			(stroke
				(width 0.1)
				(type default)
			)
			(layer "F.Fab")
		)
		(fp_line
			(start 0.8636 0.4572)
			(end -0.8636 0.4572)
			(stroke
				(width 0.1)
				(type default)
			)
			(layer "F.Fab")
		)
		(fp_line
			(start 1.1938 -0.406654)
			(end 1.1938 0.4064)
			(stroke
				(width 0.1)
				(type default)
			)
			(layer "F.Fab")
		)
		(fp_line
			(start 1.1938 0.4064)
			(end 0.8636 0.4064)
			(stroke
				(width 0.1)
				(type default)
			)
			(layer "F.Fab")
		)
		(pad "1" smd rect
			(at -0.7366 0 270)
			(size 0.7112 0.8128)
			(layers "F.Cu" "F.Mask" "F.Paste")
			(net "P52V_FAN_2")
		)
		(pad "2" smd rect
			(at 0.7366 0 270)
			(size 0.7112 0.8128)
			(layers "F.Cu" "F.Mask" "F.Paste")
			(net "FAN_2_TACH_OL_R")
		)
	)
	(footprint ""
		(layer "F.Cu")
		(at 14.478 -24.765 180)
		(property "Reference" "D239"
			(at 4.191 -1.04267 0)
			(unlocked yes)
			(layer "F.SilkS")
			(effects
				(font
					(size 0.7874 0.5842)
					(thickness 0.1524)
				)
				(justify left)
			)
		)
		(property "Value" ""
			(at 0 0 180)
			(layer "F.Fab")
			(effects
				(font
					(size 1.27 1.27)
				)
			)
		)
		(duplicate_pad_numbers_are_jumpers no)
		(fp_line
			(start 0.94488 0.450088)
			(end 0.94488 -0.450088)
			(stroke
				(width 0.1524)
				(type default)
			)
			(layer "F.SilkS")
		)
		(fp_line
			(start 0.94488 -0.450088)
			(end -0.854964 -0.450088)
			(stroke
				(width 0.1524)
				(type default)
			)
			(layer "F.SilkS")
		)
		(fp_line
			(start 0.870458 -0.2794)
			(end 0.845058 0.4064)
			(stroke
				(width 0.1524)
				(type default)
			)
			(layer "F.SilkS")
		)
		(fp_line
			(start 0.845058 0.4064)
			(end 0.845058 -0.381)
			(stroke
				(width 0.1524)
				(type default)
			)
			(layer "F.SilkS")
		)
		(fp_line
			(start -0.854964 0.450088)
			(end 0.925068 0.450088)
			(stroke
				(width 0.1524)
				(type default)
			)
			(layer "F.SilkS")
		)
		(fp_line
			(start -0.854964 -0.450088)
			(end -0.854964 0.450088)
			(stroke
				(width 0.1524)
				(type default)
			)
			(layer "F.SilkS")
		)
		(fp_line
			(start 0.54991 0.350012)
			(end 0.54991 -0.350012)
			(stroke
				(width 0.1)
				(type default)
			)
			(layer "F.Fab")
		)
		(fp_line
			(start 0.54991 -0.350012)
			(end -0.54991 -0.350012)
			(stroke
				(width 0.1)
				(type default)
			)
			(layer "F.Fab")
		)
		(fp_line
			(start -0.54991 0.350012)
			(end 0.54991 0.350012)
			(stroke
				(width 0.1)
				(type default)
			)
			(layer "F.Fab")
		)
		(fp_line
			(start -0.54991 -0.350012)
			(end -0.54991 0.350012)
			(stroke
				(width 0.1)
				(type default)
			)
			(layer "F.Fab")
		)
		(fp_text user "-"
			(at 1.905 0.98425 0)
			(unlocked yes)
			(layer "F.SilkS")
			(effects
				(font
					(size 1.905 1.4224)
					(thickness 0.1524)
				)
				(justify left)
			)
		)
		(fp_text user "+"
			(at -0.381 0.98425 0)
			(unlocked yes)
			(layer "F.SilkS")
			(effects
				(font
					(size 1.905 1.4224)
					(thickness 0.1524)
				)
				(justify left)
			)
		)
		(fp_text user "-"
			(at 2.48539 0.239014 0)
			(unlocked yes)
			(layer "F.Fab")
			(effects
				(font
					(size 1.905 1.4224)
					(thickness 0.1524)
				)
				(justify left)
			)
		)
		(fp_text user "+"
			(at -0.808228 0.239014 0)
			(unlocked yes)
			(layer "F.Fab")
			(effects
				(font
					(size 1.905 1.4224)
					(thickness 0.1524)
				)
				(justify left)
			)
		)
		(pad "A" smd rect
			(at -0.424942 0 180)
			(size 0.5588 0.6096)
			(layers "F.Cu" "F.Mask" "F.Paste")
			(net "GND")
		)
		(pad "C" smd rect
			(at 0.424942 0)
			(size 0.5588 0.6096)
			(layers "F.Cu" "F.Mask" "F.Paste")
			(net "FAN_4_FAIL_R_LED_N")
		)
	)
	(footprint ""
		(layer "F.Cu")
		(at 32.258 -291.338 90)
		(property "Reference" "R5384"
			(at 0 0 90)
			(layer "F.SilkS")
			(hide yes)
			(effects
				(font
					(size 1.27 1.27)
				)
			)
		)
		(property "Value" ""
			(at 0 0 90)
			(layer "F.Fab")
			(effects
				(font
					(size 1.27 1.27)
				)
			)
		)
		(duplicate_pad_numbers_are_jumpers no)
		(fp_line
			(start 0.7874 -0.4064)
			(end 0.7874 0.4064)
			(stroke
				(width 0.1524)
				(type default)
			)
			(layer "F.SilkS")
		)
		(fp_line
			(start -0.7874 -0.4064)
			(end 0.7874 -0.4064)
			(stroke
				(width 0.1524)
				(type default)
			)
			(layer "F.SilkS")
		)
		(fp_line
			(start 0.7874 0.4064)
			(end -0.7874 0.4064)
			(stroke
				(width 0.1524)
				(type default)
			)
			(layer "F.SilkS")
		)
		(fp_line
			(start -0.7874 0.4064)
			(end -0.7874 -0.4064)
			(stroke
				(width 0.1524)
				(type default)
			)
			(layer "F.SilkS")
		)
		(fp_line
			(start -0.12065 -0.305054)
			(end -0.12065 -0.2794)
			(stroke
				(width 0.1)
				(type default)
			)
			(layer "F.Fab")
		)
		(fp_line
			(start -0.67945 -0.305054)
			(end -0.12065 -0.305054)
			(stroke
				(width 0.1)
				(type default)
			)
			(layer "F.Fab")
		)
		(fp_line
			(start 0.67945 -0.3048)
			(end 0.67945 0.3048)
			(stroke
				(width 0.1)
				(type default)
			)
			(layer "F.Fab")
		)
		(fp_line
			(start 0.12065 -0.3048)
			(end 0.67945 -0.3048)
			(stroke
				(width 0.1)
				(type default)
			)
			(layer "F.Fab")
		)
		(fp_line
			(start 0.12065 -0.2794)
			(end 0.12065 -0.3048)
			(stroke
				(width 0.1)
				(type default)
			)
			(layer "F.Fab")
		)
		(fp_line
			(start -0.12065 -0.2794)
			(end 0.12065 -0.2794)
			(stroke
				(width 0.1)
				(type default)
			)
			(layer "F.Fab")
		)
		(fp_line
			(start 0.120396 0.2794)
			(end -0.12065 0.2794)
			(stroke
				(width 0.1)
				(type default)
			)
			(layer "F.Fab")
		)
		(fp_line
			(start -0.12065 0.2794)
			(end -0.12065 0.3048)
			(stroke
				(width 0.1)
				(type default)
			)
			(layer "F.Fab")
		)
		(fp_line
			(start 0.67945 0.3048)
			(end 0.120396 0.3048)
			(stroke
				(width 0.1)
				(type default)
			)
			(layer "F.Fab")
		)
		(fp_line
			(start 0.120396 0.3048)
			(end 0.120396 0.2794)
			(stroke
				(width 0.1)
				(type default)
			)
			(layer "F.Fab")
		)
		(fp_line
			(start -0.12065 0.3048)
			(end -0.67945 0.3048)
			(stroke
				(width 0.1)
				(type default)
			)
			(layer "F.Fab")
		)
		(fp_line
			(start -0.67945 0.3048)
			(end -0.67945 -0.305054)
			(stroke
				(width 0.1)
				(type default)
			)
			(layer "F.Fab")
		)
		(pad "1" smd circle
			(at -0.40005 0 90)
			(size 0 0)
			(layers "F.Cu" "F.Mask" "F.Paste")
			(net "P3V3_AUX")
		)
		(pad "2" smd circle
			(at 0.40005 0 90)
			(size 0 0)
			(layers "F.Cu" "F.Mask" "F.Paste")
			(net "FAN_0_OK_R_LED")
		)
	)
	(footprint ""
		(layer "F.Cu")
		(at 31.623 -124.206 90)
		(property "Reference" "R4779"
			(at 0 0 90)
			(layer "F.SilkS")
			(hide yes)
			(effects
				(font
					(size 1.27 1.27)
				)
			)
		)
		(property "Value" ""
			(at 0 0 90)
			(layer "F.Fab")
			(effects
				(font
					(size 1.27 1.27)
				)
			)
		)
		(duplicate_pad_numbers_are_jumpers no)
		(fp_line
			(start 0.7874 -0.4064)
			(end 0.7874 0.4064)
			(stroke
				(width 0.1524)
				(type default)
			)
			(layer "F.SilkS")
		)
		(fp_line
			(start -0.7874 -0.4064)
			(end 0.7874 -0.4064)
			(stroke
				(width 0.1524)
				(type default)
			)
			(layer "F.SilkS")
		)
		(fp_line
			(start 0.7874 0.4064)
			(end -0.7874 0.4064)
			(stroke
				(width 0.1524)
				(type default)
			)
			(layer "F.SilkS")
		)
		(fp_line
			(start -0.7874 0.4064)
			(end -0.7874 -0.4064)
			(stroke
				(width 0.1524)
				(type default)
			)
			(layer "F.SilkS")
		)
		(fp_line
			(start -0.12065 -0.305054)
			(end -0.12065 -0.2794)
			(stroke
				(width 0.1)
				(type default)
			)
			(layer "F.Fab")
		)
		(fp_line
			(start -0.67945 -0.305054)
			(end -0.12065 -0.305054)
			(stroke
				(width 0.1)
				(type default)
			)
			(layer "F.Fab")
		)
		(fp_line
			(start 0.67945 -0.3048)
			(end 0.67945 0.3048)
			(stroke
				(width 0.1)
				(type default)
			)
			(layer "F.Fab")
		)
		(fp_line
			(start 0.12065 -0.3048)
			(end 0.67945 -0.3048)
			(stroke
				(width 0.1)
				(type default)
			)
			(layer "F.Fab")
		)
		(fp_line
			(start 0.12065 -0.2794)
			(end 0.12065 -0.3048)
			(stroke
				(width 0.1)
				(type default)
			)
			(layer "F.Fab")
		)
		(fp_line
			(start -0.12065 -0.2794)
			(end 0.12065 -0.2794)
			(stroke
				(width 0.1)
				(type default)
			)
			(layer "F.Fab")
		)
		(fp_line
			(start 0.120396 0.2794)
			(end -0.12065 0.2794)
			(stroke
				(width 0.1)
				(type default)
			)
			(layer "F.Fab")
		)
		(fp_line
			(start -0.12065 0.2794)
			(end -0.12065 0.3048)
			(stroke
				(width 0.1)
				(type default)
			)
			(layer "F.Fab")
		)
		(fp_line
			(start 0.67945 0.3048)
			(end 0.120396 0.3048)
			(stroke
				(width 0.1)
				(type default)
			)
			(layer "F.Fab")
		)
		(fp_line
			(start 0.120396 0.3048)
			(end 0.120396 0.2794)
			(stroke
				(width 0.1)
				(type default)
			)
			(layer "F.Fab")
		)
		(fp_line
			(start -0.12065 0.3048)
			(end -0.67945 0.3048)
			(stroke
				(width 0.1)
				(type default)
			)
			(layer "F.Fab")
		)
		(fp_line
			(start -0.67945 0.3048)
			(end -0.67945 -0.305054)
			(stroke
				(width 0.1)
				(type default)
			)
			(layer "F.Fab")
		)
		(pad "1" smd circle
			(at -0.40005 0 90)
			(size 0 0)
			(layers "F.Cu" "F.Mask" "F.Paste")
			(net "P3V3_AUX")
		)
		(pad "2" smd circle
			(at 0.40005 0 90)
			(size 0 0)
			(layers "F.Cu" "F.Mask" "F.Paste")
			(net "MAX31790_U317_ADD1")
		)
	)
	(footprint ""
		(layer "F.Cu")
		(at 17.907 -164.338 180)
		(property "Reference" "R5496"
			(at 0 0 180)
			(layer "F.SilkS")
			(hide yes)
			(effects
				(font
					(size 1.27 1.27)
				)
			)
		)
		(property "Value" ""
			(at 0 0 180)
			(layer "F.Fab")
			(effects
				(font
					(size 1.27 1.27)
				)
			)
		)
		(duplicate_pad_numbers_are_jumpers no)
		(fp_line
			(start 0.7874 0.4064)
			(end -0.7874 0.4064)
			(stroke
				(width 0.1524)
				(type default)
			)
			(layer "F.SilkS")
		)
		(fp_line
			(start 0.7874 -0.4064)
			(end 0.7874 0.4064)
			(stroke
				(width 0.1524)
				(type default)
			)
			(layer "F.SilkS")
		)
		(fp_line
			(start -0.7874 0.4064)
			(end -0.7874 -0.4064)
			(stroke
				(width 0.1524)
				(type default)
			)
			(layer "F.SilkS")
		)
		(fp_line
			(start -0.7874 -0.4064)
			(end 0.7874 -0.4064)
			(stroke
				(width 0.1524)
				(type default)
			)
			(layer "F.SilkS")
		)
		(fp_line
			(start 0.67945 0.3048)
			(end 0.120396 0.3048)
			(stroke
				(width 0.1)
				(type default)
			)
			(layer "F.Fab")
		)
		(fp_line
			(start 0.67945 -0.3048)
			(end 0.67945 0.3048)
			(stroke
				(width 0.1)
				(type default)
			)
			(layer "F.Fab")
		)
		(fp_line
			(start 0.12065 -0.2794)
			(end 0.12065 -0.3048)
			(stroke
				(width 0.1)
				(type default)
			)
			(layer "F.Fab")
		)
		(fp_line
			(start 0.12065 -0.3048)
			(end 0.67945 -0.3048)
			(stroke
				(width 0.1)
				(type default)
			)
			(layer "F.Fab")
		)
		(fp_line
			(start 0.120396 0.3048)
			(end 0.120396 0.2794)
			(stroke
				(width 0.1)
				(type default)
			)
			(layer "F.Fab")
		)
		(fp_line
			(start 0.120396 0.2794)
			(end -0.12065 0.2794)
			(stroke
				(width 0.1)
				(type default)
			)
			(layer "F.Fab")
		)
		(fp_line
			(start -0.12065 0.3048)
			(end -0.67945 0.3048)
			(stroke
				(width 0.1)
				(type default)
			)
			(layer "F.Fab")
		)
		(fp_line
			(start -0.12065 0.2794)
			(end -0.12065 0.3048)
			(stroke
				(width 0.1)
				(type default)
			)
			(layer "F.Fab")
		)
		(fp_line
			(start -0.12065 -0.2794)
			(end 0.12065 -0.2794)
			(stroke
				(width 0.1)
				(type default)
			)
			(layer "F.Fab")
		)
		(fp_line
			(start -0.12065 -0.305054)
			(end -0.12065 -0.2794)
			(stroke
				(width 0.1)
				(type default)
			)
			(layer "F.Fab")
		)
		(fp_line
			(start -0.67945 0.3048)
			(end -0.67945 -0.305054)
			(stroke
				(width 0.1)
				(type default)
			)
			(layer "F.Fab")
		)
		(fp_line
			(start -0.67945 -0.305054)
			(end -0.12065 -0.305054)
			(stroke
				(width 0.1)
				(type default)
			)
			(layer "F.Fab")
		)
		(pad "1" smd circle
			(at -0.40005 0 180)
			(size 0 0)
			(layers "F.Cu" "F.Mask" "F.Paste")
			(net "FAN_1_PRESENT_R_N")
		)
		(pad "2" smd circle
			(at 0.40005 0 180)
			(size 0 0)
			(layers "F.Cu" "F.Mask" "F.Paste")
			(net "FAN_1_PRESENT_N")
		)
	)
	(footprint ""
		(layer "F.Cu")
		(at 3.81 -184.658 180)
		(property "Reference" "R2355"
			(at 0 0 180)
			(layer "F.SilkS")
			(hide yes)
			(effects
				(font
					(size 1.27 1.27)
				)
			)
		)
		(property "Value" ""
			(at 0 0 180)
			(layer "F.Fab")
			(effects
				(font
					(size 1.27 1.27)
				)
			)
		)
		(duplicate_pad_numbers_are_jumpers no)
		(fp_line
			(start 0.7874 0.4064)
			(end -0.7874 0.4064)
			(stroke
				(width 0.1524)
				(type default)
			)
			(layer "F.SilkS")
		)
		(fp_line
			(start 0.7874 -0.4064)
			(end 0.7874 0.4064)
			(stroke
				(width 0.1524)
				(type default)
			)
			(layer "F.SilkS")
		)
		(fp_line
			(start -0.7874 0.4064)
			(end -0.7874 -0.4064)
			(stroke
				(width 0.1524)
				(type default)
			)
			(layer "F.SilkS")
		)
		(fp_line
			(start -0.7874 -0.4064)
			(end 0.7874 -0.4064)
			(stroke
				(width 0.1524)
				(type default)
			)
			(layer "F.SilkS")
		)
		(fp_line
			(start 0.67945 0.3048)
			(end 0.120396 0.3048)
			(stroke
				(width 0.1)
				(type default)
			)
			(layer "F.Fab")
		)
		(fp_line
			(start 0.67945 -0.3048)
			(end 0.67945 0.3048)
			(stroke
				(width 0.1)
				(type default)
			)
			(layer "F.Fab")
		)
		(fp_line
			(start 0.12065 -0.2794)
			(end 0.12065 -0.3048)
			(stroke
				(width 0.1)
				(type default)
			)
			(layer "F.Fab")
		)
		(fp_line
			(start 0.12065 -0.3048)
			(end 0.67945 -0.3048)
			(stroke
				(width 0.1)
				(type default)
			)
			(layer "F.Fab")
		)
		(fp_line
			(start 0.120396 0.3048)
			(end 0.120396 0.2794)
			(stroke
				(width 0.1)
				(type default)
			)
			(layer "F.Fab")
		)
		(fp_line
			(start 0.120396 0.2794)
			(end -0.12065 0.2794)
			(stroke
				(width 0.1)
				(type default)
			)
			(layer "F.Fab")
		)
		(fp_line
			(start -0.12065 0.3048)
			(end -0.67945 0.3048)
			(stroke
				(width 0.1)
				(type default)
			)
			(layer "F.Fab")
		)
		(fp_line
			(start -0.12065 0.2794)
			(end -0.12065 0.3048)
			(stroke
				(width 0.1)
				(type default)
			)
			(layer "F.Fab")
		)
		(fp_line
			(start -0.12065 -0.2794)
			(end 0.12065 -0.2794)
			(stroke
				(width 0.1)
				(type default)
			)
			(layer "F.Fab")
		)
		(fp_line
			(start -0.12065 -0.305054)
			(end -0.12065 -0.2794)
			(stroke
				(width 0.1)
				(type default)
			)
			(layer "F.Fab")
		)
		(fp_line
			(start -0.67945 0.3048)
			(end -0.67945 -0.305054)
			(stroke
				(width 0.1)
				(type default)
			)
			(layer "F.Fab")
		)
		(fp_line
			(start -0.67945 -0.305054)
			(end -0.12065 -0.305054)
			(stroke
				(width 0.1)
				(type default)
			)
			(layer "F.Fab")
		)
		(pad "1" smd circle
			(at -0.40005 0 180)
			(size 0 0)
			(layers "F.Cu" "F.Mask" "F.Paste")
			(net "PCA9555_MB0_A1")
		)
		(pad "2" smd circle
			(at 0.40005 0 180)
			(size 0 0)
			(layers "F.Cu" "F.Mask" "F.Paste")
			(net "GND")
		)
	)
	(footprint ""
		(layer "F.Cu")
		(at 43.18 -217.424)
		(property "Reference" "U406"
			(at -1.69926 2.03581 0)
			(unlocked yes)
			(layer "F.SilkS")
			(effects
				(font
					(size 0.7874 0.5842)
					(thickness 0.1524)
				)
				(justify left)
			)
		)
		(property "Value" ""
			(at 0 0 0)
			(layer "F.Fab")
			(effects
				(font
					(size 1.27 1.27)
				)
			)
		)
		(duplicate_pad_numbers_are_jumpers no)
		(fp_line
			(start -1.335278 -1.100074)
			(end -1.335278 1.100074)
			(stroke
				(width 0.1524)
				(type default)
			)
			(layer "F.SilkS")
		)
		(fp_line
			(start -1.335278 1.100074)
			(end 1.335278 1.100074)
			(stroke
				(width 0.1524)
				(type default)
			)
			(layer "F.SilkS")
		)
		(fp_line
			(start 1.335278 -1.100074)
			(end -1.335278 -1.100074)
			(stroke
				(width 0.1524)
				(type default)
			)
			(layer "F.SilkS")
		)
		(fp_line
			(start 1.335278 1.100074)
			(end 1.335278 -1.100074)
			(stroke
				(width 0.1524)
				(type default)
			)
			(layer "F.SilkS")
		)
		(fp_line
			(start -0.674878 -1.100074)
			(end -0.674878 1.100074)
			(stroke
				(width 0.1)
				(type default)
			)
			(layer "F.Fab")
		)
		(fp_line
			(start -0.674878 1.100074)
			(end 0.674878 1.100074)
			(stroke
				(width 0.1)
				(type default)
			)
			(layer "F.Fab")
		)
		(fp_line
			(start 0.674878 -1.100074)
			(end -0.674878 -1.100074)
			(stroke
				(width 0.1)
				(type default)
			)
			(layer "F.Fab")
		)
		(fp_line
			(start 0.674878 1.100074)
			(end 0.674878 -1.100074)
			(stroke
				(width 0.1)
				(type default)
			)
			(layer "F.Fab")
		)
		(pad "D" smd rect
			(at 0.8001 0 270)
			(size 0.6096 0.8128)
			(layers "F.Cu" "F.Mask" "F.Paste")
			(net "U406_D1")
		)
		(pad "G" smd rect
			(at -0.8001 -0.649986 270)
			(size 0.6096 0.8128)
			(layers "F.Cu" "F.Mask" "F.Paste")
			(net "FAN_1_PRESENT")
		)
		(pad "S" smd rect
			(at -0.8001 0.649986 270)
			(size 0.6096 0.8128)
			(layers "F.Cu" "F.Mask" "F.Paste")
			(net "GND")
		)
	)
	(footprint ""
		(layer "F.Cu")
		(at 8.382 -135.255 -90)
		(property "Reference" "R5570"
			(at 0 0 270)
			(layer "F.SilkS")
			(hide yes)
			(effects
				(font
					(size 1.27 1.27)
				)
			)
		)
		(property "Value" ""
			(at 0 0 270)
			(layer "F.Fab")
			(effects
				(font
					(size 1.27 1.27)
				)
			)
		)
		(duplicate_pad_numbers_are_jumpers no)
		(fp_line
			(start -0.7874 0.4064)
			(end -0.7874 -0.4064)
			(stroke
				(width 0.1524)
				(type default)
			)
			(layer "F.SilkS")
		)
		(fp_line
			(start 0.7874 0.4064)
			(end -0.7874 0.4064)
			(stroke
				(width 0.1524)
				(type default)
			)
			(layer "F.SilkS")
		)
		(fp_line
			(start -0.7874 -0.4064)
			(end 0.7874 -0.4064)
			(stroke
				(width 0.1524)
				(type default)
			)
			(layer "F.SilkS")
		)
		(fp_line
			(start 0.7874 -0.4064)
			(end 0.7874 0.4064)
			(stroke
				(width 0.1524)
				(type default)
			)
			(layer "F.SilkS")
		)
		(fp_line
			(start -0.67945 0.3048)
			(end -0.67945 -0.305054)
			(stroke
				(width 0.1)
				(type default)
			)
			(layer "F.Fab")
		)
		(fp_line
			(start -0.12065 0.3048)
			(end -0.67945 0.3048)
			(stroke
				(width 0.1)
				(type default)
			)
			(layer "F.Fab")
		)
		(fp_line
			(start 0.120396 0.3048)
			(end 0.120396 0.2794)
			(stroke
				(width 0.1)
				(type default)
			)
			(layer "F.Fab")
		)
		(fp_line
			(start 0.67945 0.3048)
			(end 0.120396 0.3048)
			(stroke
				(width 0.1)
				(type default)
			)
			(layer "F.Fab")
		)
		(fp_line
			(start -0.12065 0.2794)
			(end -0.12065 0.3048)
			(stroke
				(width 0.1)
				(type default)
			)
			(layer "F.Fab")
		)
		(fp_line
			(start 0.120396 0.2794)
			(end -0.12065 0.2794)
			(stroke
				(width 0.1)
				(type default)
			)
			(layer "F.Fab")
		)
		(fp_line
			(start -0.12065 -0.2794)
			(end 0.12065 -0.2794)
			(stroke
				(width 0.1)
				(type default)
			)
			(layer "F.Fab")
		)
		(fp_line
			(start 0.12065 -0.2794)
			(end 0.12065 -0.3048)
			(stroke
				(width 0.1)
				(type default)
			)
			(layer "F.Fab")
		)
		(fp_line
			(start 0.12065 -0.3048)
			(end 0.67945 -0.3048)
			(stroke
				(width 0.1)
				(type default)
			)
			(layer "F.Fab")
		)
		(fp_line
			(start 0.67945 -0.3048)
			(end 0.67945 0.3048)
			(stroke
				(width 0.1)
				(type default)
			)
			(layer "F.Fab")
		)
		(fp_line
			(start -0.67945 -0.305054)
			(end -0.12065 -0.305054)
			(stroke
				(width 0.1)
				(type default)
			)
			(layer "F.Fab")
		)
		(fp_line
			(start -0.12065 -0.305054)
			(end -0.12065 -0.2794)
			(stroke
				(width 0.1)
				(type default)
			)
			(layer "F.Fab")
		)
		(pad "1" smd circle
			(at -0.40005 0 270)
			(size 0 0)
			(layers "F.Cu" "F.Mask" "F.Paste")
			(net "GND")
		)
		(pad "2" smd circle
			(at 0.40005 0 270)
			(size 0 0)
			(layers "F.Cu" "F.Mask" "F.Paste")
			(net "U404_ADD0")
		)
	)
	(footprint ""
		(layer "F.Cu")
		(at 47.244 -186.182)
		(property "Reference" "C2086"
			(at 0 0 0)
			(layer "F.SilkS")
			(hide yes)
			(effects
				(font
					(size 1.27 1.27)
				)
			)
		)
		(property "Value" ""
			(at 0 0 0)
			(layer "F.Fab")
			(effects
				(font
					(size 1.27 1.27)
				)
			)
		)
		(duplicate_pad_numbers_are_jumpers no)
		(fp_line
			(start -0.7874 -0.4064)
			(end 0.7874 -0.4064)
			(stroke
				(width 0.1524)
				(type default)
			)
			(layer "F.SilkS")
		)
		(fp_line
			(start -0.7874 0.4064)
			(end -0.7874 -0.4064)
			(stroke
				(width 0.1524)
				(type default)
			)
			(layer "F.SilkS")
		)
		(fp_line
			(start 0.7874 -0.4064)
			(end 0.7874 0.4064)
			(stroke
				(width 0.1524)
				(type default)
			)
			(layer "F.SilkS")
		)
		(fp_line
			(start 0.7874 0.4064)
			(end -0.7874 0.4064)
			(stroke
				(width 0.1524)
				(type default)
			)
			(layer "F.SilkS")
		)
		(fp_line
			(start -0.67945 -0.305054)
			(end -0.12065 -0.305054)
			(stroke
				(width 0.1)
				(type default)
			)
			(layer "F.Fab")
		)
		(fp_line
			(start -0.67945 0.3048)
			(end -0.67945 -0.305054)
			(stroke
				(width 0.1)
				(type default)
			)
			(layer "F.Fab")
		)
		(fp_line
			(start -0.12065 -0.305054)
			(end -0.12065 -0.2794)
			(stroke
				(width 0.1)
				(type default)
			)
			(layer "F.Fab")
		)
		(fp_line
			(start -0.12065 -0.2794)
			(end 0.12065 -0.2794)
			(stroke
				(width 0.1)
				(type default)
			)
			(layer "F.Fab")
		)
		(fp_line
			(start -0.12065 0.2794)
			(end -0.12065 0.3048)
			(stroke
				(width 0.1)
				(type default)
			)
			(layer "F.Fab")
		)
		(fp_line
			(start -0.12065 0.3048)
			(end -0.67945 0.3048)
			(stroke
				(width 0.1)
				(type default)
			)
			(layer "F.Fab")
		)
		(fp_line
			(start 0.120396 0.2794)
			(end -0.12065 0.2794)
			(stroke
				(width 0.1)
				(type default)
			)
			(layer "F.Fab")
		)
		(fp_line
			(start 0.120396 0.3048)
			(end 0.120396 0.2794)
			(stroke
				(width 0.1)
				(type default)
			)
			(layer "F.Fab")
		)
		(fp_line
			(start 0.12065 -0.3048)
			(end 0.67945 -0.3048)
			(stroke
				(width 0.1)
				(type default)
			)
			(layer "F.Fab")
		)
		(fp_line
			(start 0.12065 -0.2794)
			(end 0.12065 -0.3048)
			(stroke
				(width 0.1)
				(type default)
			)
			(layer "F.Fab")
		)
		(fp_line
			(start 0.67945 -0.3048)
			(end 0.67945 0.3048)
			(stroke
				(width 0.1)
				(type default)
			)
			(layer "F.Fab")
		)
		(fp_line
			(start 0.67945 0.3048)
			(end 0.120396 0.3048)
			(stroke
				(width 0.1)
				(type default)
			)
			(layer "F.Fab")
		)
		(pad "1" smd circle
			(at -0.40005 0)
			(size 0 0)
			(layers "F.Cu" "F.Mask" "F.Paste")
			(net "P52V_FAN_7_BUFF_EN_R")
		)
		(pad "2" smd circle
			(at 0.40005 0)
			(size 0 0)
			(layers "F.Cu" "F.Mask" "F.Paste")
			(net "GND")
		)
	)
	(footprint ""
		(layer "F.Cu")
		(at 38.6461 -124.968)
		(property "Reference" "R5583"
			(at 0 0 0)
			(layer "F.SilkS")
			(hide yes)
			(effects
				(font
					(size 1.27 1.27)
				)
			)
		)
		(property "Value" ""
			(at 0 0 0)
			(layer "F.Fab")
			(effects
				(font
					(size 1.27 1.27)
				)
			)
		)
		(duplicate_pad_numbers_are_jumpers no)
		(fp_line
			(start -0.7874 -0.4064)
			(end 0.7874 -0.4064)
			(stroke
				(width 0.1524)
				(type default)
			)
			(layer "F.SilkS")
		)
		(fp_line
			(start -0.7874 0.4064)
			(end -0.7874 -0.4064)
			(stroke
				(width 0.1524)
				(type default)
			)
			(layer "F.SilkS")
		)
		(fp_line
			(start 0.7874 -0.4064)
			(end 0.7874 0.4064)
			(stroke
				(width 0.1524)
				(type default)
			)
			(layer "F.SilkS")
		)
		(fp_line
			(start 0.7874 0.4064)
			(end -0.7874 0.4064)
			(stroke
				(width 0.1524)
				(type default)
			)
			(layer "F.SilkS")
		)
		(fp_line
			(start -0.67945 -0.305054)
			(end -0.12065 -0.305054)
			(stroke
				(width 0.1)
				(type default)
			)
			(layer "F.Fab")
		)
		(fp_line
			(start -0.67945 0.3048)
			(end -0.67945 -0.305054)
			(stroke
				(width 0.1)
				(type default)
			)
			(layer "F.Fab")
		)
		(fp_line
			(start -0.12065 -0.305054)
			(end -0.12065 -0.2794)
			(stroke
				(width 0.1)
				(type default)
			)
			(layer "F.Fab")
		)
		(fp_line
			(start -0.12065 -0.2794)
			(end 0.12065 -0.2794)
			(stroke
				(width 0.1)
				(type default)
			)
			(layer "F.Fab")
		)
		(fp_line
			(start -0.12065 0.2794)
			(end -0.12065 0.3048)
			(stroke
				(width 0.1)
				(type default)
			)
			(layer "F.Fab")
		)
		(fp_line
			(start -0.12065 0.3048)
			(end -0.67945 0.3048)
			(stroke
				(width 0.1)
				(type default)
			)
			(layer "F.Fab")
		)
		(fp_line
			(start 0.120396 0.2794)
			(end -0.12065 0.2794)
			(stroke
				(width 0.1)
				(type default)
			)
			(layer "F.Fab")
		)
		(fp_line
			(start 0.120396 0.3048)
			(end 0.120396 0.2794)
			(stroke
				(width 0.1)
				(type default)
			)
			(layer "F.Fab")
		)
		(fp_line
			(start 0.12065 -0.3048)
			(end 0.67945 -0.3048)
			(stroke
				(width 0.1)
				(type default)
			)
			(layer "F.Fab")
		)
		(fp_line
			(start 0.12065 -0.2794)
			(end 0.12065 -0.3048)
			(stroke
				(width 0.1)
				(type default)
			)
			(layer "F.Fab")
		)
		(fp_line
			(start 0.67945 -0.3048)
			(end 0.67945 0.3048)
			(stroke
				(width 0.1)
				(type default)
			)
			(layer "F.Fab")
		)
		(fp_line
			(start 0.67945 0.3048)
			(end 0.120396 0.3048)
			(stroke
				(width 0.1)
				(type default)
			)
			(layer "F.Fab")
		)
		(pad "1" smd rect
			(at -0.40005 0 180)
			(size 0.4572 0.508)
			(layers "F.Cu" "F.Mask" "F.Paste")
			(net "FAN_3_PWM")
		)
		(pad "2" smd rect
			(at 0.40005 0 180)
			(size 0.4572 0.508)
			(layers "F.Cu" "F.Mask" "F.Paste")
			(net "FAN_3_PWM_R2")
		)
	)
	(footprint ""
		(layer "F.Cu")
		(at 4.445 -249.555 -90)
		(property "Reference" "PR64"
			(at 0 0 270)
			(layer "F.SilkS")
			(hide yes)
			(effects
				(font
					(size 1.27 1.27)
				)
			)
		)
		(property "Value" ""
			(at 0 0 270)
			(layer "F.Fab")
			(effects
				(font
					(size 1.27 1.27)
				)
			)
		)
		(duplicate_pad_numbers_are_jumpers no)
		(fp_line
			(start -0.7874 0.4064)
			(end -0.7874 -0.4064)
			(stroke
				(width 0.1524)
				(type default)
			)
			(layer "F.SilkS")
		)
		(fp_line
			(start 0.7874 0.4064)
			(end -0.7874 0.4064)
			(stroke
				(width 0.1524)
				(type default)
			)
			(layer "F.SilkS")
		)
		(fp_line
			(start -0.7874 -0.4064)
			(end 0.7874 -0.4064)
			(stroke
				(width 0.1524)
				(type default)
			)
			(layer "F.SilkS")
		)
		(fp_line
			(start 0.7874 -0.4064)
			(end 0.7874 0.4064)
			(stroke
				(width 0.1524)
				(type default)
			)
			(layer "F.SilkS")
		)
		(fp_line
			(start -0.67945 0.3048)
			(end -0.67945 -0.305054)
			(stroke
				(width 0.1)
				(type default)
			)
			(layer "F.Fab")
		)
		(fp_line
			(start -0.12065 0.3048)
			(end -0.67945 0.3048)
			(stroke
				(width 0.1)
				(type default)
			)
			(layer "F.Fab")
		)
		(fp_line
			(start 0.120396 0.3048)
			(end 0.120396 0.2794)
			(stroke
				(width 0.1)
				(type default)
			)
			(layer "F.Fab")
		)
		(fp_line
			(start 0.67945 0.3048)
			(end 0.120396 0.3048)
			(stroke
				(width 0.1)
				(type default)
			)
			(layer "F.Fab")
		)
		(fp_line
			(start -0.12065 0.2794)
			(end -0.12065 0.3048)
			(stroke
				(width 0.1)
				(type default)
			)
			(layer "F.Fab")
		)
		(fp_line
			(start 0.120396 0.2794)
			(end -0.12065 0.2794)
			(stroke
				(width 0.1)
				(type default)
			)
			(layer "F.Fab")
		)
		(fp_line
			(start -0.12065 -0.2794)
			(end 0.12065 -0.2794)
			(stroke
				(width 0.1)
				(type default)
			)
			(layer "F.Fab")
		)
		(fp_line
			(start 0.12065 -0.2794)
			(end 0.12065 -0.3048)
			(stroke
				(width 0.1)
				(type default)
			)
			(layer "F.Fab")
		)
		(fp_line
			(start 0.12065 -0.3048)
			(end 0.67945 -0.3048)
			(stroke
				(width 0.1)
				(type default)
			)
			(layer "F.Fab")
		)
		(fp_line
			(start 0.67945 -0.3048)
			(end 0.67945 0.3048)
			(stroke
				(width 0.1)
				(type default)
			)
			(layer "F.Fab")
		)
		(fp_line
			(start -0.67945 -0.305054)
			(end -0.12065 -0.305054)
			(stroke
				(width 0.1)
				(type default)
			)
			(layer "F.Fab")
		)
		(fp_line
			(start -0.12065 -0.305054)
			(end -0.12065 -0.2794)
			(stroke
				(width 0.1)
				(type default)
			)
			(layer "F.Fab")
		)
		(pad "1" smd rect
			(at -0.40005 0 90)
			(size 0.4572 0.508)
			(layers "F.Cu" "F.Mask" "F.Paste")
			(net "FAN_6_FAULT_R")
		)
		(pad "2" smd rect
			(at 0.40005 0 90)
			(size 0.4572 0.508)
			(layers "F.Cu" "F.Mask" "F.Paste")
			(net "FAN_6_FAULT")
		)
	)
	(footprint ""
		(layer "F.Cu")
		(at 36.322 -209.959956)
		(property "Reference" "D133"
			(at 2.667 -0.960374 0)
			(unlocked yes)
			(layer "F.SilkS")
			(effects
				(font
					(size 0.7874 0.5842)
					(thickness 0.1524)
				)
				(justify left)
			)
		)
		(property "Value" ""
			(at 0 0 0)
			(layer "F.Fab")
			(effects
				(font
					(size 1.27 1.27)
				)
			)
		)
		(duplicate_pad_numbers_are_jumpers no)
		(fp_line
			(start -1.651 -0.7112)
			(end 2.032 -0.7112)
			(stroke
				(width 0.1524)
				(type default)
			)
			(layer "F.SilkS")
		)
		(fp_line
			(start -1.651 0.7112)
			(end -1.651 -0.7112)
			(stroke
				(width 0.1524)
				(type default)
			)
			(layer "F.SilkS")
		)
		(fp_line
			(start -0.299974 -0.500126)
			(end -0.299974 0.500126)
			(stroke
				(width 0.1524)
				(type default)
			)
			(layer "F.SilkS")
		)
		(fp_line
			(start -0.299974 0.500126)
			(end 0.199898 0)
			(stroke
				(width 0.1524)
				(type default)
			)
			(layer "F.SilkS")
		)
		(fp_line
			(start 0.199898 0)
			(end -0.299974 -0.500126)
			(stroke
				(width 0.1524)
				(type default)
			)
			(layer "F.SilkS")
		)
		(fp_line
			(start 0.299974 -0.500126)
			(end 0.299974 0.500126)
			(stroke
				(width 0.1524)
				(type default)
			)
			(layer "F.SilkS")
		)
		(fp_line
			(start 1.651 -0.6858)
			(end 1.651 0.6858)
			(stroke
				(width 0.1524)
				(type default)
			)
			(layer "F.SilkS")
		)
		(fp_line
			(start 1.778 0.6858)
			(end 1.778 -0.6858)
			(stroke
				(width 0.1524)
				(type default)
			)
			(layer "F.SilkS")
		)
		(fp_line
			(start 1.905 -0.6858)
			(end 1.905 0.6858)
			(stroke
				(width 0.1524)
				(type default)
			)
			(layer "F.SilkS")
		)
		(fp_line
			(start 2.032 -0.7112)
			(end 2.032 0.7112)
			(stroke
				(width 0.1524)
				(type default)
			)
			(layer "F.SilkS")
		)
		(fp_line
			(start 2.032 0.7112)
			(end -1.651 0.7112)
			(stroke
				(width 0.1524)
				(type default)
			)
			(layer "F.SilkS")
		)
		(fp_line
			(start -1.35001 -0.225044)
			(end -0.899922 -0.225044)
			(stroke
				(width 0.1)
				(type default)
			)
			(layer "F.Fab")
		)
		(fp_line
			(start -1.35001 0.175006)
			(end -1.35001 -0.225044)
			(stroke
				(width 0.1)
				(type default)
			)
			(layer "F.Fab")
		)
		(fp_line
			(start -0.899922 -0.700024)
			(end 0.899922 -0.700024)
			(stroke
				(width 0.1)
				(type default)
			)
			(layer "F.Fab")
		)
		(fp_line
			(start -0.899922 -0.225044)
			(end -0.899922 -0.700024)
			(stroke
				(width 0.1)
				(type default)
			)
			(layer "F.Fab")
		)
		(fp_line
			(start -0.899922 0.175006)
			(end -1.35001 0.175006)
			(stroke
				(width 0.1)
				(type default)
			)
			(layer "F.Fab")
		)
		(fp_line
			(start -0.899922 0.700024)
			(end -0.899922 0.175006)
			(stroke
				(width 0.1)
				(type default)
			)
			(layer "F.Fab")
		)
		(fp_line
			(start -0.299974 -0.500126)
			(end -0.299974 0.500126)
			(stroke
				(width 0.1)
				(type default)
			)
			(layer "F.Fab")
		)
		(fp_line
			(start -0.299974 0.500126)
			(end 0.199898 0)
			(stroke
				(width 0.1)
				(type default)
			)
			(layer "F.Fab")
		)
		(fp_line
			(start 0.199898 0)
			(end -0.299974 -0.500126)
			(stroke
				(width 0.1)
				(type default)
			)
			(layer "F.Fab")
		)
		(fp_line
			(start 0.299974 -0.500126)
			(end 0.299974 0.500126)
			(stroke
				(width 0.1)
				(type default)
			)
			(layer "F.Fab")
		)
		(fp_line
			(start 0.899922 -0.700024)
			(end 0.899922 -0.225044)
			(stroke
				(width 0.1)
				(type default)
			)
			(layer "F.Fab")
		)
		(fp_line
			(start 0.899922 -0.225044)
			(end 1.35001 -0.225044)
			(stroke
				(width 0.1)
				(type default)
			)
			(layer "F.Fab")
		)
		(fp_line
			(start 0.899922 0.175006)
			(end 0.899922 0.700024)
			(stroke
				(width 0.1)
				(type default)
			)
			(layer "F.Fab")
		)
		(fp_line
			(start 0.899922 0.700024)
			(end -0.899922 0.700024)
			(stroke
				(width 0.1)
				(type default)
			)
			(layer "F.Fab")
		)
		(fp_line
			(start 1.35001 -0.225044)
			(end 1.35001 0.175006)
			(stroke
				(width 0.1)
				(type default)
			)
			(layer "F.Fab")
		)
		(fp_line
			(start 1.35001 0.175006)
			(end 0.899922 0.175006)
			(stroke
				(width 0.1)
				(type default)
			)
			(layer "F.Fab")
		)
		(fp_text user "+"
			(at -2.667 0.822706 0)
			(unlocked yes)
			(layer "F.SilkS")
			(effects
				(font
					(size 1.905 1.4224)
					(thickness 0.1524)
				)
				(justify left)
			)
		)
		(fp_text user "-"
			(at 0.508 -1.209294 0)
			(unlocked yes)
			(layer "F.SilkS")
			(effects
				(font
					(size 1.905 1.4224)
					(thickness 0.1524)
				)
				(justify left)
			)
		)
		(fp_text user "+"
			(at -2.794 -0.19685 0)
			(unlocked yes)
			(layer "F.Fab")
			(effects
				(font
					(size 1.905 1.4224)
					(thickness 0.1524)
				)
				(justify left)
			)
		)
		(fp_text user "-"
			(at 1.8288 -0.24765 0)
			(unlocked yes)
			(layer "F.Fab")
			(effects
				(font
					(size 1.905 1.4224)
					(thickness 0.1524)
				)
				(justify left)
			)
		)
		(pad "1" smd rect
			(at -1.0922 0 180)
			(size 0.8128 0.8636)
			(layers "F.Cu" "F.Mask" "F.Paste")
			(net "FAN_1_TACH_IL_R")
		)
		(pad "2" smd rect
			(at 1.0922 0)
			(size 0.8128 0.8636)
			(layers "F.Cu" "F.Mask" "F.Paste")
			(net "FAN_1_TACH_IL_D")
		)
	)
	(footprint ""
		(layer "F.Cu")
		(at 37.82695 -123.698 180)
		(property "Reference" "R5608"
			(at 0 0 180)
			(layer "F.SilkS")
			(hide yes)
			(effects
				(font
					(size 1.27 1.27)
				)
			)
		)
		(property "Value" ""
			(at 0 0 180)
			(layer "F.Fab")
			(effects
				(font
					(size 1.27 1.27)
				)
			)
		)
		(duplicate_pad_numbers_are_jumpers no)
		(fp_line
			(start 0.7874 0.4064)
			(end -0.7874 0.4064)
			(stroke
				(width 0.1524)
				(type default)
			)
			(layer "F.SilkS")
		)
		(fp_line
			(start 0.7874 -0.4064)
			(end 0.7874 0.4064)
			(stroke
				(width 0.1524)
				(type default)
			)
			(layer "F.SilkS")
		)
		(fp_line
			(start -0.7874 0.4064)
			(end -0.7874 -0.4064)
			(stroke
				(width 0.1524)
				(type default)
			)
			(layer "F.SilkS")
		)
		(fp_line
			(start -0.7874 -0.4064)
			(end 0.7874 -0.4064)
			(stroke
				(width 0.1524)
				(type default)
			)
			(layer "F.SilkS")
		)
		(fp_line
			(start 0.67945 0.3048)
			(end 0.120396 0.3048)
			(stroke
				(width 0.1)
				(type default)
			)
			(layer "F.Fab")
		)
		(fp_line
			(start 0.67945 -0.3048)
			(end 0.67945 0.3048)
			(stroke
				(width 0.1)
				(type default)
			)
			(layer "F.Fab")
		)
		(fp_line
			(start 0.12065 -0.2794)
			(end 0.12065 -0.3048)
			(stroke
				(width 0.1)
				(type default)
			)
			(layer "F.Fab")
		)
		(fp_line
			(start 0.12065 -0.3048)
			(end 0.67945 -0.3048)
			(stroke
				(width 0.1)
				(type default)
			)
			(layer "F.Fab")
		)
		(fp_line
			(start 0.120396 0.3048)
			(end 0.120396 0.2794)
			(stroke
				(width 0.1)
				(type default)
			)
			(layer "F.Fab")
		)
		(fp_line
			(start 0.120396 0.2794)
			(end -0.12065 0.2794)
			(stroke
				(width 0.1)
				(type default)
			)
			(layer "F.Fab")
		)
		(fp_line
			(start -0.12065 0.3048)
			(end -0.67945 0.3048)
			(stroke
				(width 0.1)
				(type default)
			)
			(layer "F.Fab")
		)
		(fp_line
			(start -0.12065 0.2794)
			(end -0.12065 0.3048)
			(stroke
				(width 0.1)
				(type default)
			)
			(layer "F.Fab")
		)
		(fp_line
			(start -0.12065 -0.2794)
			(end 0.12065 -0.2794)
			(stroke
				(width 0.1)
				(type default)
			)
			(layer "F.Fab")
		)
		(fp_line
			(start -0.12065 -0.305054)
			(end -0.12065 -0.2794)
			(stroke
				(width 0.1)
				(type default)
			)
			(layer "F.Fab")
		)
		(fp_line
			(start -0.67945 0.3048)
			(end -0.67945 -0.305054)
			(stroke
				(width 0.1)
				(type default)
			)
			(layer "F.Fab")
		)
		(fp_line
			(start -0.67945 -0.305054)
			(end -0.12065 -0.305054)
			(stroke
				(width 0.1)
				(type default)
			)
			(layer "F.Fab")
		)
		(pad "1" smd rect
			(at -0.40005 0)
			(size 0.4572 0.508)
			(layers "F.Cu" "F.Mask" "F.Paste")
			(net "FAN_3_TACH_OL")
		)
		(pad "2" smd rect
			(at 0.40005 0)
			(size 0.4572 0.508)
			(layers "F.Cu" "F.Mask" "F.Paste")
			(net "FAN_3_TACH_OL_R1")
		)
	)
	(footprint ""
		(layer "F.Cu")
		(at 19.05 -143.891 -90)
		(property "Reference" "R5471"
			(at 0 0 270)
			(layer "F.SilkS")
			(hide yes)
			(effects
				(font
					(size 1.27 1.27)
				)
			)
		)
		(property "Value" ""
			(at 0 0 270)
			(layer "F.Fab")
			(effects
				(font
					(size 1.27 1.27)
				)
			)
		)
		(duplicate_pad_numbers_are_jumpers no)
		(fp_line
			(start -0.7874 0.4064)
			(end -0.7874 -0.4064)
			(stroke
				(width 0.1524)
				(type default)
			)
			(layer "F.SilkS")
		)
		(fp_line
			(start 0.7874 0.4064)
			(end -0.7874 0.4064)
			(stroke
				(width 0.1524)
				(type default)
			)
			(layer "F.SilkS")
		)
		(fp_line
			(start -0.7874 -0.4064)
			(end 0.7874 -0.4064)
			(stroke
				(width 0.1524)
				(type default)
			)
			(layer "F.SilkS")
		)
		(fp_line
			(start 0.7874 -0.4064)
			(end 0.7874 0.4064)
			(stroke
				(width 0.1524)
				(type default)
			)
			(layer "F.SilkS")
		)
		(fp_line
			(start -0.67945 0.3048)
			(end -0.67945 -0.305054)
			(stroke
				(width 0.1)
				(type default)
			)
			(layer "F.Fab")
		)
		(fp_line
			(start -0.12065 0.3048)
			(end -0.67945 0.3048)
			(stroke
				(width 0.1)
				(type default)
			)
			(layer "F.Fab")
		)
		(fp_line
			(start 0.120396 0.3048)
			(end 0.120396 0.2794)
			(stroke
				(width 0.1)
				(type default)
			)
			(layer "F.Fab")
		)
		(fp_line
			(start 0.67945 0.3048)
			(end 0.120396 0.3048)
			(stroke
				(width 0.1)
				(type default)
			)
			(layer "F.Fab")
		)
		(fp_line
			(start -0.12065 0.2794)
			(end -0.12065 0.3048)
			(stroke
				(width 0.1)
				(type default)
			)
			(layer "F.Fab")
		)
		(fp_line
			(start 0.120396 0.2794)
			(end -0.12065 0.2794)
			(stroke
				(width 0.1)
				(type default)
			)
			(layer "F.Fab")
		)
		(fp_line
			(start -0.12065 -0.2794)
			(end 0.12065 -0.2794)
			(stroke
				(width 0.1)
				(type default)
			)
			(layer "F.Fab")
		)
		(fp_line
			(start 0.12065 -0.2794)
			(end 0.12065 -0.3048)
			(stroke
				(width 0.1)
				(type default)
			)
			(layer "F.Fab")
		)
		(fp_line
			(start 0.12065 -0.3048)
			(end 0.67945 -0.3048)
			(stroke
				(width 0.1)
				(type default)
			)
			(layer "F.Fab")
		)
		(fp_line
			(start 0.67945 -0.3048)
			(end 0.67945 0.3048)
			(stroke
				(width 0.1)
				(type default)
			)
			(layer "F.Fab")
		)
		(fp_line
			(start -0.67945 -0.305054)
			(end -0.12065 -0.305054)
			(stroke
				(width 0.1)
				(type default)
			)
			(layer "F.Fab")
		)
		(fp_line
			(start -0.12065 -0.305054)
			(end -0.12065 -0.2794)
			(stroke
				(width 0.1)
				(type default)
			)
			(layer "F.Fab")
		)
		(pad "1" smd circle
			(at -0.40005 0 270)
			(size 0 0)
			(layers "F.Cu" "F.Mask" "F.Paste")
			(net "PD_TCA9548_SML1_U321_A1")
		)
		(pad "2" smd circle
			(at 0.40005 0 270)
			(size 0 0)
			(layers "F.Cu" "F.Mask" "F.Paste")
			(net "GND")
		)
	)
	(footprint ""
		(layer "F.Cu")
		(at 3.248914 -252.095 90)
		(property "Reference" "C2071"
			(at 0 0 90)
			(layer "F.SilkS")
			(hide yes)
			(effects
				(font
					(size 1.27 1.27)
				)
			)
		)
		(property "Value" ""
			(at 0 0 90)
			(layer "F.Fab")
			(effects
				(font
					(size 1.27 1.27)
				)
			)
		)
		(duplicate_pad_numbers_are_jumpers no)
		(fp_line
			(start 0.7874 -0.4064)
			(end 0.7874 0.4064)
			(stroke
				(width 0.1524)
				(type default)
			)
			(layer "F.SilkS")
		)
		(fp_line
			(start -0.7874 -0.4064)
			(end 0.7874 -0.4064)
			(stroke
				(width 0.1524)
				(type default)
			)
			(layer "F.SilkS")
		)
		(fp_line
			(start 0.7874 0.4064)
			(end -0.7874 0.4064)
			(stroke
				(width 0.1524)
				(type default)
			)
			(layer "F.SilkS")
		)
		(fp_line
			(start -0.7874 0.4064)
			(end -0.7874 -0.4064)
			(stroke
				(width 0.1524)
				(type default)
			)
			(layer "F.SilkS")
		)
		(fp_line
			(start -0.12065 -0.305054)
			(end -0.12065 -0.2794)
			(stroke
				(width 0.1)
				(type default)
			)
			(layer "F.Fab")
		)
		(fp_line
			(start -0.67945 -0.305054)
			(end -0.12065 -0.305054)
			(stroke
				(width 0.1)
				(type default)
			)
			(layer "F.Fab")
		)
		(fp_line
			(start 0.67945 -0.3048)
			(end 0.67945 0.3048)
			(stroke
				(width 0.1)
				(type default)
			)
			(layer "F.Fab")
		)
		(fp_line
			(start 0.12065 -0.3048)
			(end 0.67945 -0.3048)
			(stroke
				(width 0.1)
				(type default)
			)
			(layer "F.Fab")
		)
		(fp_line
			(start 0.12065 -0.2794)
			(end 0.12065 -0.3048)
			(stroke
				(width 0.1)
				(type default)
			)
			(layer "F.Fab")
		)
		(fp_line
			(start -0.12065 -0.2794)
			(end 0.12065 -0.2794)
			(stroke
				(width 0.1)
				(type default)
			)
			(layer "F.Fab")
		)
		(fp_line
			(start 0.120396 0.2794)
			(end -0.12065 0.2794)
			(stroke
				(width 0.1)
				(type default)
			)
			(layer "F.Fab")
		)
		(fp_line
			(start -0.12065 0.2794)
			(end -0.12065 0.3048)
			(stroke
				(width 0.1)
				(type default)
			)
			(layer "F.Fab")
		)
		(fp_line
			(start 0.67945 0.3048)
			(end 0.120396 0.3048)
			(stroke
				(width 0.1)
				(type default)
			)
			(layer "F.Fab")
		)
		(fp_line
			(start 0.120396 0.3048)
			(end 0.120396 0.2794)
			(stroke
				(width 0.1)
				(type default)
			)
			(layer "F.Fab")
		)
		(fp_line
			(start -0.12065 0.3048)
			(end -0.67945 0.3048)
			(stroke
				(width 0.1)
				(type default)
			)
			(layer "F.Fab")
		)
		(fp_line
			(start -0.67945 0.3048)
			(end -0.67945 -0.305054)
			(stroke
				(width 0.1)
				(type default)
			)
			(layer "F.Fab")
		)
		(pad "1" smd circle
			(at -0.40005 0 90)
			(size 0 0)
			(layers "F.Cu" "F.Mask" "F.Paste")
			(net "P3V3_AUX")
		)
		(pad "2" smd circle
			(at 0.40005 0 90)
			(size 0 0)
			(layers "F.Cu" "F.Mask" "F.Paste")
			(net "GND")
		)
	)
	(footprint ""
		(layer "F.Cu")
		(at 17.907 -165.481 180)
		(property "Reference" "R5497"
			(at 0 0 180)
			(layer "F.SilkS")
			(hide yes)
			(effects
				(font
					(size 1.27 1.27)
				)
			)
		)
		(property "Value" ""
			(at 0 0 180)
			(layer "F.Fab")
			(effects
				(font
					(size 1.27 1.27)
				)
			)
		)
		(duplicate_pad_numbers_are_jumpers no)
		(fp_line
			(start 0.7874 0.4064)
			(end -0.7874 0.4064)
			(stroke
				(width 0.1524)
				(type default)
			)
			(layer "F.SilkS")
		)
		(fp_line
			(start 0.7874 -0.4064)
			(end 0.7874 0.4064)
			(stroke
				(width 0.1524)
				(type default)
			)
			(layer "F.SilkS")
		)
		(fp_line
			(start -0.7874 0.4064)
			(end -0.7874 -0.4064)
			(stroke
				(width 0.1524)
				(type default)
			)
			(layer "F.SilkS")
		)
		(fp_line
			(start -0.7874 -0.4064)
			(end 0.7874 -0.4064)
			(stroke
				(width 0.1524)
				(type default)
			)
			(layer "F.SilkS")
		)
		(fp_line
			(start 0.67945 0.3048)
			(end 0.120396 0.3048)
			(stroke
				(width 0.1)
				(type default)
			)
			(layer "F.Fab")
		)
		(fp_line
			(start 0.67945 -0.3048)
			(end 0.67945 0.3048)
			(stroke
				(width 0.1)
				(type default)
			)
			(layer "F.Fab")
		)
		(fp_line
			(start 0.12065 -0.2794)
			(end 0.12065 -0.3048)
			(stroke
				(width 0.1)
				(type default)
			)
			(layer "F.Fab")
		)
		(fp_line
			(start 0.12065 -0.3048)
			(end 0.67945 -0.3048)
			(stroke
				(width 0.1)
				(type default)
			)
			(layer "F.Fab")
		)
		(fp_line
			(start 0.120396 0.3048)
			(end 0.120396 0.2794)
			(stroke
				(width 0.1)
				(type default)
			)
			(layer "F.Fab")
		)
		(fp_line
			(start 0.120396 0.2794)
			(end -0.12065 0.2794)
			(stroke
				(width 0.1)
				(type default)
			)
			(layer "F.Fab")
		)
		(fp_line
			(start -0.12065 0.3048)
			(end -0.67945 0.3048)
			(stroke
				(width 0.1)
				(type default)
			)
			(layer "F.Fab")
		)
		(fp_line
			(start -0.12065 0.2794)
			(end -0.12065 0.3048)
			(stroke
				(width 0.1)
				(type default)
			)
			(layer "F.Fab")
		)
		(fp_line
			(start -0.12065 -0.2794)
			(end 0.12065 -0.2794)
			(stroke
				(width 0.1)
				(type default)
			)
			(layer "F.Fab")
		)
		(fp_line
			(start -0.12065 -0.305054)
			(end -0.12065 -0.2794)
			(stroke
				(width 0.1)
				(type default)
			)
			(layer "F.Fab")
		)
		(fp_line
			(start -0.67945 0.3048)
			(end -0.67945 -0.305054)
			(stroke
				(width 0.1)
				(type default)
			)
			(layer "F.Fab")
		)
		(fp_line
			(start -0.67945 -0.305054)
			(end -0.12065 -0.305054)
			(stroke
				(width 0.1)
				(type default)
			)
			(layer "F.Fab")
		)
		(pad "1" smd circle
			(at -0.40005 0 180)
			(size 0 0)
			(layers "F.Cu" "F.Mask" "F.Paste")
			(net "FAN_2_PRESENT_R_N")
		)
		(pad "2" smd circle
			(at 0.40005 0 180)
			(size 0 0)
			(layers "F.Cu" "F.Mask" "F.Paste")
			(net "FAN_2_PRESENT_N")
		)
	)
	(footprint ""
		(layer "F.Cu")
		(at 38.6461 -126.238)
		(property "Reference" "R5582"
			(at 0 0 0)
			(layer "F.SilkS")
			(hide yes)
			(effects
				(font
					(size 1.27 1.27)
				)
			)
		)
		(property "Value" ""
			(at 0 0 0)
			(layer "F.Fab")
			(effects
				(font
					(size 1.27 1.27)
				)
			)
		)
		(duplicate_pad_numbers_are_jumpers no)
		(fp_line
			(start -0.7874 -0.4064)
			(end 0.7874 -0.4064)
			(stroke
				(width 0.1524)
				(type default)
			)
			(layer "F.SilkS")
		)
		(fp_line
			(start -0.7874 0.4064)
			(end -0.7874 -0.4064)
			(stroke
				(width 0.1524)
				(type default)
			)
			(layer "F.SilkS")
		)
		(fp_line
			(start 0.7874 -0.4064)
			(end 0.7874 0.4064)
			(stroke
				(width 0.1524)
				(type default)
			)
			(layer "F.SilkS")
		)
		(fp_line
			(start 0.7874 0.4064)
			(end -0.7874 0.4064)
			(stroke
				(width 0.1524)
				(type default)
			)
			(layer "F.SilkS")
		)
		(fp_line
			(start -0.67945 -0.305054)
			(end -0.12065 -0.305054)
			(stroke
				(width 0.1)
				(type default)
			)
			(layer "F.Fab")
		)
		(fp_line
			(start -0.67945 0.3048)
			(end -0.67945 -0.305054)
			(stroke
				(width 0.1)
				(type default)
			)
			(layer "F.Fab")
		)
		(fp_line
			(start -0.12065 -0.305054)
			(end -0.12065 -0.2794)
			(stroke
				(width 0.1)
				(type default)
			)
			(layer "F.Fab")
		)
		(fp_line
			(start -0.12065 -0.2794)
			(end 0.12065 -0.2794)
			(stroke
				(width 0.1)
				(type default)
			)
			(layer "F.Fab")
		)
		(fp_line
			(start -0.12065 0.2794)
			(end -0.12065 0.3048)
			(stroke
				(width 0.1)
				(type default)
			)
			(layer "F.Fab")
		)
		(fp_line
			(start -0.12065 0.3048)
			(end -0.67945 0.3048)
			(stroke
				(width 0.1)
				(type default)
			)
			(layer "F.Fab")
		)
		(fp_line
			(start 0.120396 0.2794)
			(end -0.12065 0.2794)
			(stroke
				(width 0.1)
				(type default)
			)
			(layer "F.Fab")
		)
		(fp_line
			(start 0.120396 0.3048)
			(end 0.120396 0.2794)
			(stroke
				(width 0.1)
				(type default)
			)
			(layer "F.Fab")
		)
		(fp_line
			(start 0.12065 -0.3048)
			(end 0.67945 -0.3048)
			(stroke
				(width 0.1)
				(type default)
			)
			(layer "F.Fab")
		)
		(fp_line
			(start 0.12065 -0.2794)
			(end 0.12065 -0.3048)
			(stroke
				(width 0.1)
				(type default)
			)
			(layer "F.Fab")
		)
		(fp_line
			(start 0.67945 -0.3048)
			(end 0.67945 0.3048)
			(stroke
				(width 0.1)
				(type default)
			)
			(layer "F.Fab")
		)
		(fp_line
			(start 0.67945 0.3048)
			(end 0.120396 0.3048)
			(stroke
				(width 0.1)
				(type default)
			)
			(layer "F.Fab")
		)
		(pad "1" smd rect
			(at -0.40005 0 180)
			(size 0.4572 0.508)
			(layers "F.Cu" "F.Mask" "F.Paste")
			(net "FAN_2_TACH_OL")
		)
		(pad "2" smd rect
			(at 0.40005 0 180)
			(size 0.4572 0.508)
			(layers "F.Cu" "F.Mask" "F.Paste")
			(net "FAN_2_TACH_OL_R2")
		)
	)
	(footprint ""
		(layer "F.Cu")
		(at 24.638 -189.23 180)
		(property "Reference" "C2083"
			(at 0 0 180)
			(layer "F.SilkS")
			(hide yes)
			(effects
				(font
					(size 1.27 1.27)
				)
			)
		)
		(property "Value" ""
			(at 0 0 180)
			(layer "F.Fab")
			(effects
				(font
					(size 1.27 1.27)
				)
			)
		)
		(duplicate_pad_numbers_are_jumpers no)
		(fp_line
			(start 0.7874 0.4064)
			(end -0.7874 0.4064)
			(stroke
				(width 0.1524)
				(type default)
			)
			(layer "F.SilkS")
		)
		(fp_line
			(start 0.7874 -0.4064)
			(end 0.7874 0.4064)
			(stroke
				(width 0.1524)
				(type default)
			)
			(layer "F.SilkS")
		)
		(fp_line
			(start -0.7874 0.4064)
			(end -0.7874 -0.4064)
			(stroke
				(width 0.1524)
				(type default)
			)
			(layer "F.SilkS")
		)
		(fp_line
			(start -0.7874 -0.4064)
			(end 0.7874 -0.4064)
			(stroke
				(width 0.1524)
				(type default)
			)
			(layer "F.SilkS")
		)
		(fp_line
			(start 0.67945 0.3048)
			(end 0.120396 0.3048)
			(stroke
				(width 0.1)
				(type default)
			)
			(layer "F.Fab")
		)
		(fp_line
			(start 0.67945 -0.3048)
			(end 0.67945 0.3048)
			(stroke
				(width 0.1)
				(type default)
			)
			(layer "F.Fab")
		)
		(fp_line
			(start 0.12065 -0.2794)
			(end 0.12065 -0.3048)
			(stroke
				(width 0.1)
				(type default)
			)
			(layer "F.Fab")
		)
		(fp_line
			(start 0.12065 -0.3048)
			(end 0.67945 -0.3048)
			(stroke
				(width 0.1)
				(type default)
			)
			(layer "F.Fab")
		)
		(fp_line
			(start 0.120396 0.3048)
			(end 0.120396 0.2794)
			(stroke
				(width 0.1)
				(type default)
			)
			(layer "F.Fab")
		)
		(fp_line
			(start 0.120396 0.2794)
			(end -0.12065 0.2794)
			(stroke
				(width 0.1)
				(type default)
			)
			(layer "F.Fab")
		)
		(fp_line
			(start -0.12065 0.3048)
			(end -0.67945 0.3048)
			(stroke
				(width 0.1)
				(type default)
			)
			(layer "F.Fab")
		)
		(fp_line
			(start -0.12065 0.2794)
			(end -0.12065 0.3048)
			(stroke
				(width 0.1)
				(type default)
			)
			(layer "F.Fab")
		)
		(fp_line
			(start -0.12065 -0.2794)
			(end 0.12065 -0.2794)
			(stroke
				(width 0.1)
				(type default)
			)
			(layer "F.Fab")
		)
		(fp_line
			(start -0.12065 -0.305054)
			(end -0.12065 -0.2794)
			(stroke
				(width 0.1)
				(type default)
			)
			(layer "F.Fab")
		)
		(fp_line
			(start -0.67945 0.3048)
			(end -0.67945 -0.305054)
			(stroke
				(width 0.1)
				(type default)
			)
			(layer "F.Fab")
		)
		(fp_line
			(start -0.67945 -0.305054)
			(end -0.12065 -0.305054)
			(stroke
				(width 0.1)
				(type default)
			)
			(layer "F.Fab")
		)
		(pad "1" smd circle
			(at -0.40005 0 180)
			(size 0 0)
			(layers "F.Cu" "F.Mask" "F.Paste")
			(net "P52V_FAN_4_BUFF_EN_R")
		)
		(pad "2" smd circle
			(at 0.40005 0 180)
			(size 0 0)
			(layers "F.Cu" "F.Mask" "F.Paste")
			(net "GND")
		)
	)
	(footprint ""
		(layer "F.Cu")
		(at 14.361922 -19.136868)
		(property "Reference" "R5130"
			(at 0 0 0)
			(layer "F.SilkS")
			(hide yes)
			(effects
				(font
					(size 1.27 1.27)
				)
			)
		)
		(property "Value" ""
			(at 0 0 0)
			(layer "F.Fab")
			(effects
				(font
					(size 1.27 1.27)
				)
			)
		)
		(duplicate_pad_numbers_are_jumpers no)
		(fp_line
			(start -0.7874 -0.4064)
			(end 0.7874 -0.4064)
			(stroke
				(width 0.1524)
				(type default)
			)
			(layer "F.SilkS")
		)
		(fp_line
			(start -0.7874 0.4064)
			(end -0.7874 -0.4064)
			(stroke
				(width 0.1524)
				(type default)
			)
			(layer "F.SilkS")
		)
		(fp_line
			(start 0.7874 -0.4064)
			(end 0.7874 0.4064)
			(stroke
				(width 0.1524)
				(type default)
			)
			(layer "F.SilkS")
		)
		(fp_line
			(start 0.7874 0.4064)
			(end -0.7874 0.4064)
			(stroke
				(width 0.1524)
				(type default)
			)
			(layer "F.SilkS")
		)
		(fp_line
			(start -0.67945 -0.305054)
			(end -0.12065 -0.305054)
			(stroke
				(width 0.1)
				(type default)
			)
			(layer "F.Fab")
		)
		(fp_line
			(start -0.67945 0.3048)
			(end -0.67945 -0.305054)
			(stroke
				(width 0.1)
				(type default)
			)
			(layer "F.Fab")
		)
		(fp_line
			(start -0.12065 -0.305054)
			(end -0.12065 -0.2794)
			(stroke
				(width 0.1)
				(type default)
			)
			(layer "F.Fab")
		)
		(fp_line
			(start -0.12065 -0.2794)
			(end 0.12065 -0.2794)
			(stroke
				(width 0.1)
				(type default)
			)
			(layer "F.Fab")
		)
		(fp_line
			(start -0.12065 0.2794)
			(end -0.12065 0.3048)
			(stroke
				(width 0.1)
				(type default)
			)
			(layer "F.Fab")
		)
		(fp_line
			(start -0.12065 0.3048)
			(end -0.67945 0.3048)
			(stroke
				(width 0.1)
				(type default)
			)
			(layer "F.Fab")
		)
		(fp_line
			(start 0.120396 0.2794)
			(end -0.12065 0.2794)
			(stroke
				(width 0.1)
				(type default)
			)
			(layer "F.Fab")
		)
		(fp_line
			(start 0.120396 0.3048)
			(end 0.120396 0.2794)
			(stroke
				(width 0.1)
				(type default)
			)
			(layer "F.Fab")
		)
		(fp_line
			(start 0.12065 -0.3048)
			(end 0.67945 -0.3048)
			(stroke
				(width 0.1)
				(type default)
			)
			(layer "F.Fab")
		)
		(fp_line
			(start 0.12065 -0.2794)
			(end 0.12065 -0.3048)
			(stroke
				(width 0.1)
				(type default)
			)
			(layer "F.Fab")
		)
		(fp_line
			(start 0.67945 -0.3048)
			(end 0.67945 0.3048)
			(stroke
				(width 0.1)
				(type default)
			)
			(layer "F.Fab")
		)
		(fp_line
			(start 0.67945 0.3048)
			(end 0.120396 0.3048)
			(stroke
				(width 0.1)
				(type default)
			)
			(layer "F.Fab")
		)
		(pad "1" smd circle
			(at -0.40005 0)
			(size 0 0)
			(layers "F.Cu" "F.Mask" "F.Paste")
			(net "FAN_4_PWM_IL_R")
		)
		(pad "2" smd circle
			(at 0.40005 0)
			(size 0 0)
			(layers "F.Cu" "F.Mask" "F.Paste")
			(net "FAN_4_PWM_IL")
		)
	)
	(footprint ""
		(layer "F.Cu")
		(at 43.561 -168.529 180)
		(property "Reference" "R5114"
			(at 0 0 180)
			(layer "F.SilkS")
			(hide yes)
			(effects
				(font
					(size 1.27 1.27)
				)
			)
		)
		(property "Value" ""
			(at 0 0 180)
			(layer "F.Fab")
			(effects
				(font
					(size 1.27 1.27)
				)
			)
		)
		(duplicate_pad_numbers_are_jumpers no)
		(fp_line
			(start 0.7874 0.4064)
			(end -0.7874 0.4064)
			(stroke
				(width 0.1524)
				(type default)
			)
			(layer "F.SilkS")
		)
		(fp_line
			(start 0.7874 -0.4064)
			(end 0.7874 0.4064)
			(stroke
				(width 0.1524)
				(type default)
			)
			(layer "F.SilkS")
		)
		(fp_line
			(start -0.7874 0.4064)
			(end -0.7874 -0.4064)
			(stroke
				(width 0.1524)
				(type default)
			)
			(layer "F.SilkS")
		)
		(fp_line
			(start -0.7874 -0.4064)
			(end 0.7874 -0.4064)
			(stroke
				(width 0.1524)
				(type default)
			)
			(layer "F.SilkS")
		)
		(fp_line
			(start 0.67945 0.3048)
			(end 0.120396 0.3048)
			(stroke
				(width 0.1)
				(type default)
			)
			(layer "F.Fab")
		)
		(fp_line
			(start 0.67945 -0.3048)
			(end 0.67945 0.3048)
			(stroke
				(width 0.1)
				(type default)
			)
			(layer "F.Fab")
		)
		(fp_line
			(start 0.12065 -0.2794)
			(end 0.12065 -0.3048)
			(stroke
				(width 0.1)
				(type default)
			)
			(layer "F.Fab")
		)
		(fp_line
			(start 0.12065 -0.3048)
			(end 0.67945 -0.3048)
			(stroke
				(width 0.1)
				(type default)
			)
			(layer "F.Fab")
		)
		(fp_line
			(start 0.120396 0.3048)
			(end 0.120396 0.2794)
			(stroke
				(width 0.1)
				(type default)
			)
			(layer "F.Fab")
		)
		(fp_line
			(start 0.120396 0.2794)
			(end -0.12065 0.2794)
			(stroke
				(width 0.1)
				(type default)
			)
			(layer "F.Fab")
		)
		(fp_line
			(start -0.12065 0.3048)
			(end -0.67945 0.3048)
			(stroke
				(width 0.1)
				(type default)
			)
			(layer "F.Fab")
		)
		(fp_line
			(start -0.12065 0.2794)
			(end -0.12065 0.3048)
			(stroke
				(width 0.1)
				(type default)
			)
			(layer "F.Fab")
		)
		(fp_line
			(start -0.12065 -0.2794)
			(end 0.12065 -0.2794)
			(stroke
				(width 0.1)
				(type default)
			)
			(layer "F.Fab")
		)
		(fp_line
			(start -0.12065 -0.305054)
			(end -0.12065 -0.2794)
			(stroke
				(width 0.1)
				(type default)
			)
			(layer "F.Fab")
		)
		(fp_line
			(start -0.67945 0.3048)
			(end -0.67945 -0.305054)
			(stroke
				(width 0.1)
				(type default)
			)
			(layer "F.Fab")
		)
		(fp_line
			(start -0.67945 -0.305054)
			(end -0.12065 -0.305054)
			(stroke
				(width 0.1)
				(type default)
			)
			(layer "F.Fab")
		)
		(pad "1" smd circle
			(at -0.40005 0 180)
			(size 0 0)
			(layers "F.Cu" "F.Mask" "F.Paste")
			(net "P3V3_AUX")
		)
		(pad "2" smd circle
			(at 0.40005 0 180)
			(size 0 0)
			(layers "F.Cu" "F.Mask" "F.Paste")
			(net "PCA9552_MB1_A2")
		)
	)
	(footprint ""
		(layer "F.Cu")
		(at 20.828 -173.736 180)
		(property "Reference" "R5671"
			(at 0 0 180)
			(layer "F.SilkS")
			(hide yes)
			(effects
				(font
					(size 1.27 1.27)
				)
			)
		)
		(property "Value" ""
			(at 0 0 180)
			(layer "F.Fab")
			(effects
				(font
					(size 1.27 1.27)
				)
			)
		)
		(duplicate_pad_numbers_are_jumpers no)
		(fp_line
			(start 0.7874 0.4064)
			(end -0.7874 0.4064)
			(stroke
				(width 0.1524)
				(type default)
			)
			(layer "F.SilkS")
		)
		(fp_line
			(start 0.7874 -0.4064)
			(end 0.7874 0.4064)
			(stroke
				(width 0.1524)
				(type default)
			)
			(layer "F.SilkS")
		)
		(fp_line
			(start -0.7874 0.4064)
			(end -0.7874 -0.4064)
			(stroke
				(width 0.1524)
				(type default)
			)
			(layer "F.SilkS")
		)
		(fp_line
			(start -0.7874 -0.4064)
			(end 0.7874 -0.4064)
			(stroke
				(width 0.1524)
				(type default)
			)
			(layer "F.SilkS")
		)
		(fp_line
			(start 0.67945 0.3048)
			(end 0.120396 0.3048)
			(stroke
				(width 0.1)
				(type default)
			)
			(layer "F.Fab")
		)
		(fp_line
			(start 0.67945 -0.3048)
			(end 0.67945 0.3048)
			(stroke
				(width 0.1)
				(type default)
			)
			(layer "F.Fab")
		)
		(fp_line
			(start 0.12065 -0.2794)
			(end 0.12065 -0.3048)
			(stroke
				(width 0.1)
				(type default)
			)
			(layer "F.Fab")
		)
		(fp_line
			(start 0.12065 -0.3048)
			(end 0.67945 -0.3048)
			(stroke
				(width 0.1)
				(type default)
			)
			(layer "F.Fab")
		)
		(fp_line
			(start 0.120396 0.3048)
			(end 0.120396 0.2794)
			(stroke
				(width 0.1)
				(type default)
			)
			(layer "F.Fab")
		)
		(fp_line
			(start 0.120396 0.2794)
			(end -0.12065 0.2794)
			(stroke
				(width 0.1)
				(type default)
			)
			(layer "F.Fab")
		)
		(fp_line
			(start -0.12065 0.3048)
			(end -0.67945 0.3048)
			(stroke
				(width 0.1)
				(type default)
			)
			(layer "F.Fab")
		)
		(fp_line
			(start -0.12065 0.2794)
			(end -0.12065 0.3048)
			(stroke
				(width 0.1)
				(type default)
			)
			(layer "F.Fab")
		)
		(fp_line
			(start -0.12065 -0.2794)
			(end 0.12065 -0.2794)
			(stroke
				(width 0.1)
				(type default)
			)
			(layer "F.Fab")
		)
		(fp_line
			(start -0.12065 -0.305054)
			(end -0.12065 -0.2794)
			(stroke
				(width 0.1)
				(type default)
			)
			(layer "F.Fab")
		)
		(fp_line
			(start -0.67945 0.3048)
			(end -0.67945 -0.305054)
			(stroke
				(width 0.1)
				(type default)
			)
			(layer "F.Fab")
		)
		(fp_line
			(start -0.67945 -0.305054)
			(end -0.12065 -0.305054)
			(stroke
				(width 0.1)
				(type default)
			)
			(layer "F.Fab")
		)
		(pad "1" smd circle
			(at -0.40005 0 180)
			(size 0 0)
			(layers "F.Cu" "F.Mask" "F.Paste")
			(net "P3V3_AUX")
		)
		(pad "2" smd circle
			(at 0.40005 0 180)
			(size 0 0)
			(layers "F.Cu" "F.Mask" "F.Paste")
			(net "FM_BOARD_SKU_ID1")
		)
	)
	(footprint ""
		(layer "F.Cu")
		(at 10.287 -188.722)
		(property "Reference" "U59"
			(at -0.127 3.20167 0)
			(unlocked yes)
			(layer "F.SilkS")
			(effects
				(font
					(size 0.7874 0.5842)
					(thickness 0.1524)
				)
				(justify left)
			)
		)
		(property "Value" ""
			(at 0 0 0)
			(layer "F.Fab")
			(effects
				(font
					(size 1.27 1.27)
				)
			)
		)
		(duplicate_pad_numbers_are_jumpers no)
		(fp_line
			(start -1.4224 -2.5146)
			(end -1.4224 2.5146)
			(stroke
				(width 0.1524)
				(type default)
			)
			(layer "F.SilkS")
		)
		(fp_line
			(start -1.4224 2.5146)
			(end 1.4224 2.5146)
			(stroke
				(width 0.1524)
				(type default)
			)
			(layer "F.SilkS")
		)
		(fp_line
			(start -0.4572 -2.5146)
			(end -1.4224 -2.5146)
			(stroke
				(width 0.1524)
				(type default)
			)
			(layer "F.SilkS")
		)
		(fp_line
			(start 0 -2.0574)
			(end -0.4572 -2.5146)
			(stroke
				(width 0.1524)
				(type default)
			)
			(layer "F.SilkS")
		)
		(fp_line
			(start 0.4572 -2.5146)
			(end 0 -2.0574)
			(stroke
				(width 0.1524)
				(type default)
			)
			(layer "F.SilkS")
		)
		(fp_line
			(start 1.4224 -2.5146)
			(end 0.4572 -2.5146)
			(stroke
				(width 0.1524)
				(type default)
			)
			(layer "F.SilkS")
		)
		(fp_line
			(start 1.4224 2.5146)
			(end 1.4224 -2.5146)
			(stroke
				(width 0.1524)
				(type default)
			)
			(layer "F.SilkS")
		)
		(fp_poly
			(pts
				(xy -2.702814 -2.4892) (xy -3.083814 -3.2512) (xy -2.321814 -3.2512)
			)
			(stroke
				(width 0)
				(type default)
			)
			(fill yes)
			(layer "F.SilkS")
		)
		(fp_line
			(start -2.648712 -2.114804)
			(end -2.648712 2.112264)
			(stroke
				(width 0.1)
				(type default)
			)
			(layer "F.Fab")
		)
		(fp_line
			(start -2.648712 2.112264)
			(end -2.0066 2.112264)
			(stroke
				(width 0.1)
				(type default)
			)
			(layer "F.Fab")
		)
		(fp_line
			(start -2.0066 -2.5146)
			(end -2.0066 -2.114804)
			(stroke
				(width 0.1)
				(type default)
			)
			(layer "F.Fab")
		)
		(fp_line
			(start -2.0066 -2.114804)
			(end -2.648712 -2.114804)
			(stroke
				(width 0.1)
				(type default)
			)
			(layer "F.Fab")
		)
		(fp_line
			(start -2.0066 2.112264)
			(end -2.0066 2.5146)
			(stroke
				(width 0.1)
				(type default)
			)
			(layer "F.Fab")
		)
		(fp_line
			(start -2.0066 2.5146)
			(end 2.0066 2.5146)
			(stroke
				(width 0.1)
				(type default)
			)
			(layer "F.Fab")
		)
		(fp_line
			(start 2.0066 -2.5146)
			(end -2.0066 -2.5146)
			(stroke
				(width 0.1)
				(type default)
			)
			(layer "F.Fab")
		)
		(fp_line
			(start 2.0066 -2.112264)
			(end 2.0066 -2.5146)
			(stroke
				(width 0.1)
				(type default)
			)
			(layer "F.Fab")
		)
		(fp_line
			(start 2.0066 2.112264)
			(end 2.642616 2.112264)
			(stroke
				(width 0.1)
				(type default)
			)
			(layer "F.Fab")
		)
		(fp_line
			(start 2.0066 2.5146)
			(end 2.0066 2.112264)
			(stroke
				(width 0.1)
				(type default)
			)
			(layer "F.Fab")
		)
		(fp_line
			(start 2.642616 -2.112264)
			(end 2.0066 -2.112264)
			(stroke
				(width 0.1)
				(type default)
			)
			(layer "F.Fab")
		)
		(fp_line
			(start 2.642616 2.112264)
			(end 2.642616 -2.112264)
			(stroke
				(width 0.1)
				(type default)
			)
			(layer "F.Fab")
		)
		(fp_poly
			(pts
				(xy -3.6322 -1.869186) (xy -4.3942 -1.488186) (xy -4.3942 -2.250186)
			)
			(stroke
				(width 0)
				(type default)
			)
			(fill yes)
			(layer "F.Fab")
		)
		(pad "1" smd rect
			(at -2.6416 -1.905 270)
			(size 0.5588 1.7272)
			(layers "F.Cu" "F.Mask" "F.Paste")
			(net "FRU_ADDR0")
		)
		(pad "2" smd rect
			(at -2.6416 -0.635 270)
			(size 0.5588 1.7272)
			(layers "F.Cu" "F.Mask" "F.Paste")
			(net "FRU_ADDR1")
		)
		(pad "3" smd rect
			(at -2.6416 0.635 270)
			(size 0.5588 1.7272)
			(layers "F.Cu" "F.Mask" "F.Paste")
			(net "FRU_ADDR2")
		)
		(pad "4" smd rect
			(at -2.6416 1.905 270)
			(size 0.5588 1.7272)
			(layers "F.Cu" "F.Mask" "F.Paste")
			(net "GND")
		)
		(pad "5" smd rect
			(at 2.6416 1.905 270)
			(size 0.5588 1.7272)
			(layers "F.Cu" "F.Mask" "F.Paste")
			(net "SMB_FRU_DAT")
		)
		(pad "6" smd rect
			(at 2.6416 0.635 270)
			(size 0.5588 1.7272)
			(layers "F.Cu" "F.Mask" "F.Paste")
			(net "SMB_FRU_CLK")
		)
		(pad "7" smd rect
			(at 2.6416 -0.635 270)
			(size 0.5588 1.7272)
			(layers "F.Cu" "F.Mask" "F.Paste")
			(net "FRU_WP_N")
		)
		(pad "8" smd rect
			(at 2.6416 -1.905 270)
			(size 0.5588 1.7272)
			(layers "F.Cu" "F.Mask" "F.Paste")
			(net "P3V3_AUX")
		)
	)
	(footprint ""
		(layer "F.Cu")
		(at 20.828 -133.985 -90)
		(property "Reference" "R4849"
			(at 0 0 270)
			(layer "F.SilkS")
			(hide yes)
			(effects
				(font
					(size 1.27 1.27)
				)
			)
		)
		(property "Value" ""
			(at 0 0 270)
			(layer "F.Fab")
			(effects
				(font
					(size 1.27 1.27)
				)
			)
		)
		(duplicate_pad_numbers_are_jumpers no)
		(fp_line
			(start -0.7874 0.4064)
			(end -0.7874 -0.4064)
			(stroke
				(width 0.1524)
				(type default)
			)
			(layer "F.SilkS")
		)
		(fp_line
			(start 0.7874 0.4064)
			(end -0.7874 0.4064)
			(stroke
				(width 0.1524)
				(type default)
			)
			(layer "F.SilkS")
		)
		(fp_line
			(start -0.7874 -0.4064)
			(end 0.7874 -0.4064)
			(stroke
				(width 0.1524)
				(type default)
			)
			(layer "F.SilkS")
		)
		(fp_line
			(start 0.7874 -0.4064)
			(end 0.7874 0.4064)
			(stroke
				(width 0.1524)
				(type default)
			)
			(layer "F.SilkS")
		)
		(fp_line
			(start -0.67945 0.3048)
			(end -0.67945 -0.305054)
			(stroke
				(width 0.1)
				(type default)
			)
			(layer "F.Fab")
		)
		(fp_line
			(start -0.12065 0.3048)
			(end -0.67945 0.3048)
			(stroke
				(width 0.1)
				(type default)
			)
			(layer "F.Fab")
		)
		(fp_line
			(start 0.120396 0.3048)
			(end 0.120396 0.2794)
			(stroke
				(width 0.1)
				(type default)
			)
			(layer "F.Fab")
		)
		(fp_line
			(start 0.67945 0.3048)
			(end 0.120396 0.3048)
			(stroke
				(width 0.1)
				(type default)
			)
			(layer "F.Fab")
		)
		(fp_line
			(start -0.12065 0.2794)
			(end -0.12065 0.3048)
			(stroke
				(width 0.1)
				(type default)
			)
			(layer "F.Fab")
		)
		(fp_line
			(start 0.120396 0.2794)
			(end -0.12065 0.2794)
			(stroke
				(width 0.1)
				(type default)
			)
			(layer "F.Fab")
		)
		(fp_line
			(start -0.12065 -0.2794)
			(end 0.12065 -0.2794)
			(stroke
				(width 0.1)
				(type default)
			)
			(layer "F.Fab")
		)
		(fp_line
			(start 0.12065 -0.2794)
			(end 0.12065 -0.3048)
			(stroke
				(width 0.1)
				(type default)
			)
			(layer "F.Fab")
		)
		(fp_line
			(start 0.12065 -0.3048)
			(end 0.67945 -0.3048)
			(stroke
				(width 0.1)
				(type default)
			)
			(layer "F.Fab")
		)
		(fp_line
			(start 0.67945 -0.3048)
			(end 0.67945 0.3048)
			(stroke
				(width 0.1)
				(type default)
			)
			(layer "F.Fab")
		)
		(fp_line
			(start -0.67945 -0.305054)
			(end -0.12065 -0.305054)
			(stroke
				(width 0.1)
				(type default)
			)
			(layer "F.Fab")
		)
		(fp_line
			(start -0.12065 -0.305054)
			(end -0.12065 -0.2794)
			(stroke
				(width 0.1)
				(type default)
			)
			(layer "F.Fab")
		)
		(pad "1" smd circle
			(at -0.40005 0 270)
			(size 0 0)
			(layers "F.Cu" "F.Mask" "F.Paste")
			(net "P3V3_AUX")
		)
		(pad "2" smd circle
			(at 0.40005 0 270)
			(size 0 0)
			(layers "F.Cu" "F.Mask" "F.Paste")
			(net "MAX31790_U330_ADD1")
		)
	)
	(footprint ""
		(layer "F.Cu")
		(at 18.288 -160.02 -90)
		(property "Reference" "R5463"
			(at 0 0 270)
			(layer "F.SilkS")
			(hide yes)
			(effects
				(font
					(size 1.27 1.27)
				)
			)
		)
		(property "Value" ""
			(at 0 0 270)
			(layer "F.Fab")
			(effects
				(font
					(size 1.27 1.27)
				)
			)
		)
		(duplicate_pad_numbers_are_jumpers no)
		(fp_line
			(start -0.7874 0.4064)
			(end -0.7874 -0.4064)
			(stroke
				(width 0.1524)
				(type default)
			)
			(layer "F.SilkS")
		)
		(fp_line
			(start 0.7874 0.4064)
			(end -0.7874 0.4064)
			(stroke
				(width 0.1524)
				(type default)
			)
			(layer "F.SilkS")
		)
		(fp_line
			(start -0.7874 -0.4064)
			(end 0.7874 -0.4064)
			(stroke
				(width 0.1524)
				(type default)
			)
			(layer "F.SilkS")
		)
		(fp_line
			(start 0.7874 -0.4064)
			(end 0.7874 0.4064)
			(stroke
				(width 0.1524)
				(type default)
			)
			(layer "F.SilkS")
		)
		(fp_line
			(start -0.67945 0.3048)
			(end -0.67945 -0.305054)
			(stroke
				(width 0.1)
				(type default)
			)
			(layer "F.Fab")
		)
		(fp_line
			(start -0.12065 0.3048)
			(end -0.67945 0.3048)
			(stroke
				(width 0.1)
				(type default)
			)
			(layer "F.Fab")
		)
		(fp_line
			(start 0.120396 0.3048)
			(end 0.120396 0.2794)
			(stroke
				(width 0.1)
				(type default)
			)
			(layer "F.Fab")
		)
		(fp_line
			(start 0.67945 0.3048)
			(end 0.120396 0.3048)
			(stroke
				(width 0.1)
				(type default)
			)
			(layer "F.Fab")
		)
		(fp_line
			(start -0.12065 0.2794)
			(end -0.12065 0.3048)
			(stroke
				(width 0.1)
				(type default)
			)
			(layer "F.Fab")
		)
		(fp_line
			(start 0.120396 0.2794)
			(end -0.12065 0.2794)
			(stroke
				(width 0.1)
				(type default)
			)
			(layer "F.Fab")
		)
		(fp_line
			(start -0.12065 -0.2794)
			(end 0.12065 -0.2794)
			(stroke
				(width 0.1)
				(type default)
			)
			(layer "F.Fab")
		)
		(fp_line
			(start 0.12065 -0.2794)
			(end 0.12065 -0.3048)
			(stroke
				(width 0.1)
				(type default)
			)
			(layer "F.Fab")
		)
		(fp_line
			(start 0.12065 -0.3048)
			(end 0.67945 -0.3048)
			(stroke
				(width 0.1)
				(type default)
			)
			(layer "F.Fab")
		)
		(fp_line
			(start 0.67945 -0.3048)
			(end 0.67945 0.3048)
			(stroke
				(width 0.1)
				(type default)
			)
			(layer "F.Fab")
		)
		(fp_line
			(start -0.67945 -0.305054)
			(end -0.12065 -0.305054)
			(stroke
				(width 0.1)
				(type default)
			)
			(layer "F.Fab")
		)
		(fp_line
			(start -0.12065 -0.305054)
			(end -0.12065 -0.2794)
			(stroke
				(width 0.1)
				(type default)
			)
			(layer "F.Fab")
		)
		(pad "1" smd circle
			(at -0.40005 0 270)
			(size 0 0)
			(layers "F.Cu" "F.Mask" "F.Paste")
			(net "SMB_PDBV_FAN_SCL")
		)
		(pad "2" smd circle
			(at 0.40005 0 270)
			(size 0 0)
			(layers "F.Cu" "F.Mask" "F.Paste")
			(net "SMB_PDBV_FAN_R_U321_SCL")
		)
	)
	(footprint ""
		(layer "F.Cu")
		(at 11.445494 -70.542912 180)
		(property "Reference" "R5356"
			(at 0 0 180)
			(layer "F.SilkS")
			(hide yes)
			(effects
				(font
					(size 1.27 1.27)
				)
			)
		)
		(property "Value" ""
			(at 0 0 180)
			(layer "F.Fab")
			(effects
				(font
					(size 1.27 1.27)
				)
			)
		)
		(duplicate_pad_numbers_are_jumpers no)
		(fp_line
			(start 0.7874 0.4064)
			(end -0.7874 0.4064)
			(stroke
				(width 0.1524)
				(type default)
			)
			(layer "F.SilkS")
		)
		(fp_line
			(start 0.7874 -0.4064)
			(end 0.7874 0.4064)
			(stroke
				(width 0.1524)
				(type default)
			)
			(layer "F.SilkS")
		)
		(fp_line
			(start -0.7874 0.4064)
			(end -0.7874 -0.4064)
			(stroke
				(width 0.1524)
				(type default)
			)
			(layer "F.SilkS")
		)
		(fp_line
			(start -0.7874 -0.4064)
			(end 0.7874 -0.4064)
			(stroke
				(width 0.1524)
				(type default)
			)
			(layer "F.SilkS")
		)
		(fp_line
			(start 0.67945 0.3048)
			(end 0.120396 0.3048)
			(stroke
				(width 0.1)
				(type default)
			)
			(layer "F.Fab")
		)
		(fp_line
			(start 0.67945 -0.3048)
			(end 0.67945 0.3048)
			(stroke
				(width 0.1)
				(type default)
			)
			(layer "F.Fab")
		)
		(fp_line
			(start 0.12065 -0.2794)
			(end 0.12065 -0.3048)
			(stroke
				(width 0.1)
				(type default)
			)
			(layer "F.Fab")
		)
		(fp_line
			(start 0.12065 -0.3048)
			(end 0.67945 -0.3048)
			(stroke
				(width 0.1)
				(type default)
			)
			(layer "F.Fab")
		)
		(fp_line
			(start 0.120396 0.3048)
			(end 0.120396 0.2794)
			(stroke
				(width 0.1)
				(type default)
			)
			(layer "F.Fab")
		)
		(fp_line
			(start 0.120396 0.2794)
			(end -0.12065 0.2794)
			(stroke
				(width 0.1)
				(type default)
			)
			(layer "F.Fab")
		)
		(fp_line
			(start -0.12065 0.3048)
			(end -0.67945 0.3048)
			(stroke
				(width 0.1)
				(type default)
			)
			(layer "F.Fab")
		)
		(fp_line
			(start -0.12065 0.2794)
			(end -0.12065 0.3048)
			(stroke
				(width 0.1)
				(type default)
			)
			(layer "F.Fab")
		)
		(fp_line
			(start -0.12065 -0.2794)
			(end 0.12065 -0.2794)
			(stroke
				(width 0.1)
				(type default)
			)
			(layer "F.Fab")
		)
		(fp_line
			(start -0.12065 -0.305054)
			(end -0.12065 -0.2794)
			(stroke
				(width 0.1)
				(type default)
			)
			(layer "F.Fab")
		)
		(fp_line
			(start -0.67945 0.3048)
			(end -0.67945 -0.305054)
			(stroke
				(width 0.1)
				(type default)
			)
			(layer "F.Fab")
		)
		(fp_line
			(start -0.67945 -0.305054)
			(end -0.12065 -0.305054)
			(stroke
				(width 0.1)
				(type default)
			)
			(layer "F.Fab")
		)
		(pad "1" smd circle
			(at -0.40005 0 180)
			(size 0 0)
			(layers "F.Cu" "F.Mask" "F.Paste")
			(net "FAN_5_ON")
		)
		(pad "2" smd circle
			(at 0.40005 0 180)
			(size 0 0)
			(layers "F.Cu" "F.Mask" "F.Paste")
			(net "P52V_FAN_5_EN")
		)
	)
	(footprint ""
		(layer "F.Cu")
		(at 14.859 -124.587)
		(property "Reference" "R5611"
			(at 0 0 0)
			(layer "F.SilkS")
			(hide yes)
			(effects
				(font
					(size 1.27 1.27)
				)
			)
		)
		(property "Value" ""
			(at 0 0 0)
			(layer "F.Fab")
			(effects
				(font
					(size 1.27 1.27)
				)
			)
		)
		(duplicate_pad_numbers_are_jumpers no)
		(fp_line
			(start -0.7874 -0.4064)
			(end 0.7874 -0.4064)
			(stroke
				(width 0.1524)
				(type default)
			)
			(layer "F.SilkS")
		)
		(fp_line
			(start -0.7874 0.4064)
			(end -0.7874 -0.4064)
			(stroke
				(width 0.1524)
				(type default)
			)
			(layer "F.SilkS")
		)
		(fp_line
			(start 0.7874 -0.4064)
			(end 0.7874 0.4064)
			(stroke
				(width 0.1524)
				(type default)
			)
			(layer "F.SilkS")
		)
		(fp_line
			(start 0.7874 0.4064)
			(end -0.7874 0.4064)
			(stroke
				(width 0.1524)
				(type default)
			)
			(layer "F.SilkS")
		)
		(fp_line
			(start -0.67945 -0.305054)
			(end -0.12065 -0.305054)
			(stroke
				(width 0.1)
				(type default)
			)
			(layer "F.Fab")
		)
		(fp_line
			(start -0.67945 0.3048)
			(end -0.67945 -0.305054)
			(stroke
				(width 0.1)
				(type default)
			)
			(layer "F.Fab")
		)
		(fp_line
			(start -0.12065 -0.305054)
			(end -0.12065 -0.2794)
			(stroke
				(width 0.1)
				(type default)
			)
			(layer "F.Fab")
		)
		(fp_line
			(start -0.12065 -0.2794)
			(end 0.12065 -0.2794)
			(stroke
				(width 0.1)
				(type default)
			)
			(layer "F.Fab")
		)
		(fp_line
			(start -0.12065 0.2794)
			(end -0.12065 0.3048)
			(stroke
				(width 0.1)
				(type default)
			)
			(layer "F.Fab")
		)
		(fp_line
			(start -0.12065 0.3048)
			(end -0.67945 0.3048)
			(stroke
				(width 0.1)
				(type default)
			)
			(layer "F.Fab")
		)
		(fp_line
			(start 0.120396 0.2794)
			(end -0.12065 0.2794)
			(stroke
				(width 0.1)
				(type default)
			)
			(layer "F.Fab")
		)
		(fp_line
			(start 0.120396 0.3048)
			(end 0.120396 0.2794)
			(stroke
				(width 0.1)
				(type default)
			)
			(layer "F.Fab")
		)
		(fp_line
			(start 0.12065 -0.3048)
			(end 0.67945 -0.3048)
			(stroke
				(width 0.1)
				(type default)
			)
			(layer "F.Fab")
		)
		(fp_line
			(start 0.12065 -0.2794)
			(end 0.12065 -0.3048)
			(stroke
				(width 0.1)
				(type default)
			)
			(layer "F.Fab")
		)
		(fp_line
			(start 0.67945 -0.3048)
			(end 0.67945 0.3048)
			(stroke
				(width 0.1)
				(type default)
			)
			(layer "F.Fab")
		)
		(fp_line
			(start 0.67945 0.3048)
			(end 0.120396 0.3048)
			(stroke
				(width 0.1)
				(type default)
			)
			(layer "F.Fab")
		)
		(pad "1" smd rect
			(at -0.40005 0 180)
			(size 0.4572 0.508)
			(layers "F.Cu" "F.Mask" "F.Paste")
			(net "FAN_5_TACH_IL")
		)
		(pad "2" smd rect
			(at 0.40005 0 180)
			(size 0.4572 0.508)
			(layers "F.Cu" "F.Mask" "F.Paste")
			(net "FAN_5_TACH_IL_R1")
		)
	)
	(footprint ""
		(layer "F.Cu")
		(at 34.417 -291.084)
		(property "Reference" "U368"
			(at -3.556 -1.75133 0)
			(unlocked yes)
			(layer "F.SilkS")
			(effects
				(font
					(size 0.7874 0.5842)
					(thickness 0.1524)
				)
				(justify left)
			)
		)
		(property "Value" ""
			(at 0 0 0)
			(layer "F.Fab")
			(effects
				(font
					(size 1.27 1.27)
				)
			)
		)
		(duplicate_pad_numbers_are_jumpers no)
		(fp_line
			(start -1.335278 -1.100074)
			(end -1.335278 1.100074)
			(stroke
				(width 0.1524)
				(type default)
			)
			(layer "F.SilkS")
		)
		(fp_line
			(start -1.335278 1.100074)
			(end 1.335278 1.100074)
			(stroke
				(width 0.1524)
				(type default)
			)
			(layer "F.SilkS")
		)
		(fp_line
			(start 1.335278 -1.100074)
			(end -1.335278 -1.100074)
			(stroke
				(width 0.1524)
				(type default)
			)
			(layer "F.SilkS")
		)
		(fp_line
			(start 1.335278 1.100074)
			(end 1.335278 -1.100074)
			(stroke
				(width 0.1524)
				(type default)
			)
			(layer "F.SilkS")
		)
		(fp_line
			(start -0.674878 -1.100074)
			(end -0.674878 1.100074)
			(stroke
				(width 0.1)
				(type default)
			)
			(layer "F.Fab")
		)
		(fp_line
			(start -0.674878 1.100074)
			(end 0.674878 1.100074)
			(stroke
				(width 0.1)
				(type default)
			)
			(layer "F.Fab")
		)
		(fp_line
			(start 0.674878 -1.100074)
			(end -0.674878 -1.100074)
			(stroke
				(width 0.1)
				(type default)
			)
			(layer "F.Fab")
		)
		(fp_line
			(start 0.674878 1.100074)
			(end 0.674878 -1.100074)
			(stroke
				(width 0.1)
				(type default)
			)
			(layer "F.Fab")
		)
		(pad "D" smd rect
			(at 0.8001 0 270)
			(size 0.6096 0.8128)
			(layers "F.Cu" "F.Mask" "F.Paste")
			(net "FAN_0_OK_LED_R_N")
		)
		(pad "G" smd rect
			(at -0.8001 -0.649986 270)
			(size 0.6096 0.8128)
			(layers "F.Cu" "F.Mask" "F.Paste")
			(net "FAN_0_OK_R_LED")
		)
		(pad "S" smd rect
			(at -0.8001 0.649986 270)
			(size 0.6096 0.8128)
			(layers "F.Cu" "F.Mask" "F.Paste")
			(net "GND")
		)
	)
	(footprint ""
		(layer "F.Cu")
		(at 28.321 -33.401)
		(property "Reference" "U408"
			(at 0.508 2.18567 0)
			(unlocked yes)
			(layer "F.SilkS")
			(effects
				(font
					(size 0.7874 0.5842)
					(thickness 0.1524)
				)
				(justify left)
			)
		)
		(property "Value" ""
			(at 0 0 0)
			(layer "F.Fab")
			(effects
				(font
					(size 1.27 1.27)
				)
			)
		)
		(duplicate_pad_numbers_are_jumpers no)
		(fp_line
			(start -1.335278 -1.100074)
			(end -1.335278 1.100074)
			(stroke
				(width 0.1524)
				(type default)
			)
			(layer "F.SilkS")
		)
		(fp_line
			(start -1.335278 1.100074)
			(end 1.335278 1.100074)
			(stroke
				(width 0.1524)
				(type default)
			)
			(layer "F.SilkS")
		)
		(fp_line
			(start 1.335278 -1.100074)
			(end -1.335278 -1.100074)
			(stroke
				(width 0.1524)
				(type default)
			)
			(layer "F.SilkS")
		)
		(fp_line
			(start 1.335278 1.100074)
			(end 1.335278 -1.100074)
			(stroke
				(width 0.1524)
				(type default)
			)
			(layer "F.SilkS")
		)
		(fp_line
			(start -0.674878 -1.100074)
			(end -0.674878 1.100074)
			(stroke
				(width 0.1)
				(type default)
			)
			(layer "F.Fab")
		)
		(fp_line
			(start -0.674878 1.100074)
			(end 0.674878 1.100074)
			(stroke
				(width 0.1)
				(type default)
			)
			(layer "F.Fab")
		)
		(fp_line
			(start 0.674878 -1.100074)
			(end -0.674878 -1.100074)
			(stroke
				(width 0.1)
				(type default)
			)
			(layer "F.Fab")
		)
		(fp_line
			(start 0.674878 1.100074)
			(end 0.674878 -1.100074)
			(stroke
				(width 0.1)
				(type default)
			)
			(layer "F.Fab")
		)
		(pad "D" smd rect
			(at 0.8001 0 270)
			(size 0.6096 0.8128)
			(layers "F.Cu" "F.Mask" "F.Paste")
			(net "U408_D1")
		)
		(pad "G" smd rect
			(at -0.8001 -0.649986 270)
			(size 0.6096 0.8128)
			(layers "F.Cu" "F.Mask" "F.Paste")
			(net "FAN_3_PRESENT")
		)
		(pad "S" smd rect
			(at -0.8001 0.649986 270)
			(size 0.6096 0.8128)
			(layers "F.Cu" "F.Mask" "F.Paste")
			(net "GND")
		)
	)
	(footprint ""
		(layer "F.Cu")
		(at 3.7338 -35.821874 90)
		(property "Reference" "C157"
			(at 0 0 90)
			(layer "F.SilkS")
			(hide yes)
			(effects
				(font
					(size 1.27 1.27)
				)
			)
		)
		(property "Value" ""
			(at 0 0 90)
			(layer "F.Fab")
			(effects
				(font
					(size 1.27 1.27)
				)
			)
		)
		(duplicate_pad_numbers_are_jumpers no)
		(fp_line
			(start 1.524 -0.762)
			(end 1.524 0.762)
			(stroke
				(width 0.1524)
				(type default)
			)
			(layer "F.SilkS")
		)
		(fp_line
			(start -1.524 -0.762)
			(end 1.524 -0.762)
			(stroke
				(width 0.1524)
				(type default)
			)
			(layer "F.SilkS")
		)
		(fp_line
			(start 1.524 0.762)
			(end -1.524 0.762)
			(stroke
				(width 0.1524)
				(type default)
			)
			(layer "F.SilkS")
		)
		(fp_line
			(start -1.524 0.762)
			(end -1.524 -0.762)
			(stroke
				(width 0.1524)
				(type default)
			)
			(layer "F.SilkS")
		)
		(fp_line
			(start 1.1049 -0.724916)
			(end -1.1049 -0.724916)
			(stroke
				(width 0.1)
				(type default)
			)
			(layer "F.Fab")
		)
		(fp_line
			(start -1.1049 -0.724916)
			(end -1.1049 0.724916)
			(stroke
				(width 0.1)
				(type default)
			)
			(layer "F.Fab")
		)
		(fp_line
			(start 1.1049 0.724916)
			(end 1.1049 -0.724916)
			(stroke
				(width 0.1)
				(type default)
			)
			(layer "F.Fab")
		)
		(fp_line
			(start -1.1049 0.724916)
			(end 1.1049 0.724916)
			(stroke
				(width 0.1)
				(type default)
			)
			(layer "F.Fab")
		)
		(pad "1" smd rect
			(at -0.889 0 270)
			(size 1.016 1.27)
			(layers "F.Cu" "F.Mask" "F.Paste")
			(net "P12V_LED_FAN4")
		)
		(pad "2" smd rect
			(at 0.889 0 270)
			(size 1.016 1.27)
			(layers "F.Cu" "F.Mask" "F.Paste")
			(net "GND")
		)
	)
	(footprint ""
		(layer "F.Cu")
		(at 37.338 -114.738912 180)
		(property "Reference" "R5220"
			(at 0 0 180)
			(layer "F.SilkS")
			(hide yes)
			(effects
				(font
					(size 1.27 1.27)
				)
			)
		)
		(property "Value" ""
			(at 0 0 180)
			(layer "F.Fab")
			(effects
				(font
					(size 1.27 1.27)
				)
			)
		)
		(duplicate_pad_numbers_are_jumpers no)
		(fp_line
			(start 0.7874 0.4064)
			(end -0.7874 0.4064)
			(stroke
				(width 0.1524)
				(type default)
			)
			(layer "F.SilkS")
		)
		(fp_line
			(start 0.7874 -0.4064)
			(end 0.7874 0.4064)
			(stroke
				(width 0.1524)
				(type default)
			)
			(layer "F.SilkS")
		)
		(fp_line
			(start -0.7874 0.4064)
			(end -0.7874 -0.4064)
			(stroke
				(width 0.1524)
				(type default)
			)
			(layer "F.SilkS")
		)
		(fp_line
			(start -0.7874 -0.4064)
			(end 0.7874 -0.4064)
			(stroke
				(width 0.1524)
				(type default)
			)
			(layer "F.SilkS")
		)
		(fp_line
			(start 0.67945 0.3048)
			(end 0.120396 0.3048)
			(stroke
				(width 0.1)
				(type default)
			)
			(layer "F.Fab")
		)
		(fp_line
			(start 0.67945 -0.3048)
			(end 0.67945 0.3048)
			(stroke
				(width 0.1)
				(type default)
			)
			(layer "F.Fab")
		)
		(fp_line
			(start 0.12065 -0.2794)
			(end 0.12065 -0.3048)
			(stroke
				(width 0.1)
				(type default)
			)
			(layer "F.Fab")
		)
		(fp_line
			(start 0.12065 -0.3048)
			(end 0.67945 -0.3048)
			(stroke
				(width 0.1)
				(type default)
			)
			(layer "F.Fab")
		)
		(fp_line
			(start 0.120396 0.3048)
			(end 0.120396 0.2794)
			(stroke
				(width 0.1)
				(type default)
			)
			(layer "F.Fab")
		)
		(fp_line
			(start 0.120396 0.2794)
			(end -0.12065 0.2794)
			(stroke
				(width 0.1)
				(type default)
			)
			(layer "F.Fab")
		)
		(fp_line
			(start -0.12065 0.3048)
			(end -0.67945 0.3048)
			(stroke
				(width 0.1)
				(type default)
			)
			(layer "F.Fab")
		)
		(fp_line
			(start -0.12065 0.2794)
			(end -0.12065 0.3048)
			(stroke
				(width 0.1)
				(type default)
			)
			(layer "F.Fab")
		)
		(fp_line
			(start -0.12065 -0.2794)
			(end 0.12065 -0.2794)
			(stroke
				(width 0.1)
				(type default)
			)
			(layer "F.Fab")
		)
		(fp_line
			(start -0.12065 -0.305054)
			(end -0.12065 -0.2794)
			(stroke
				(width 0.1)
				(type default)
			)
			(layer "F.Fab")
		)
		(fp_line
			(start -0.67945 0.3048)
			(end -0.67945 -0.305054)
			(stroke
				(width 0.1)
				(type default)
			)
			(layer "F.Fab")
		)
		(fp_line
			(start -0.67945 -0.305054)
			(end -0.12065 -0.305054)
			(stroke
				(width 0.1)
				(type default)
			)
			(layer "F.Fab")
		)
		(pad "1" smd circle
			(at -0.40005 0 180)
			(size 0 0)
			(layers "F.Cu" "F.Mask" "F.Paste")
			(net "FAN_2_PWM_IL_R")
		)
		(pad "2" smd circle
			(at 0.40005 0 180)
			(size 0 0)
			(layers "F.Cu" "F.Mask" "F.Paste")
			(net "FAN_2_PWM_IL")
		)
	)
	(footprint ""
		(layer "F.Cu")
		(at 6.477 -172.847)
		(property "Reference" "R4860"
			(at 0 0 0)
			(layer "F.SilkS")
			(hide yes)
			(effects
				(font
					(size 1.27 1.27)
				)
			)
		)
		(property "Value" ""
			(at 0 0 0)
			(layer "F.Fab")
			(effects
				(font
					(size 1.27 1.27)
				)
			)
		)
		(duplicate_pad_numbers_are_jumpers no)
		(fp_line
			(start -0.7874 -0.4064)
			(end 0.7874 -0.4064)
			(stroke
				(width 0.1524)
				(type default)
			)
			(layer "F.SilkS")
		)
		(fp_line
			(start -0.7874 0.4064)
			(end -0.7874 -0.4064)
			(stroke
				(width 0.1524)
				(type default)
			)
			(layer "F.SilkS")
		)
		(fp_line
			(start 0.7874 -0.4064)
			(end 0.7874 0.4064)
			(stroke
				(width 0.1524)
				(type default)
			)
			(layer "F.SilkS")
		)
		(fp_line
			(start 0.7874 0.4064)
			(end -0.7874 0.4064)
			(stroke
				(width 0.1524)
				(type default)
			)
			(layer "F.SilkS")
		)
		(fp_line
			(start -0.67945 -0.305054)
			(end -0.12065 -0.305054)
			(stroke
				(width 0.1)
				(type default)
			)
			(layer "F.Fab")
		)
		(fp_line
			(start -0.67945 0.3048)
			(end -0.67945 -0.305054)
			(stroke
				(width 0.1)
				(type default)
			)
			(layer "F.Fab")
		)
		(fp_line
			(start -0.12065 -0.305054)
			(end -0.12065 -0.2794)
			(stroke
				(width 0.1)
				(type default)
			)
			(layer "F.Fab")
		)
		(fp_line
			(start -0.12065 -0.2794)
			(end 0.12065 -0.2794)
			(stroke
				(width 0.1)
				(type default)
			)
			(layer "F.Fab")
		)
		(fp_line
			(start -0.12065 0.2794)
			(end -0.12065 0.3048)
			(stroke
				(width 0.1)
				(type default)
			)
			(layer "F.Fab")
		)
		(fp_line
			(start -0.12065 0.3048)
			(end -0.67945 0.3048)
			(stroke
				(width 0.1)
				(type default)
			)
			(layer "F.Fab")
		)
		(fp_line
			(start 0.120396 0.2794)
			(end -0.12065 0.2794)
			(stroke
				(width 0.1)
				(type default)
			)
			(layer "F.Fab")
		)
		(fp_line
			(start 0.120396 0.3048)
			(end 0.120396 0.2794)
			(stroke
				(width 0.1)
				(type default)
			)
			(layer "F.Fab")
		)
		(fp_line
			(start 0.12065 -0.3048)
			(end 0.67945 -0.3048)
			(stroke
				(width 0.1)
				(type default)
			)
			(layer "F.Fab")
		)
		(fp_line
			(start 0.12065 -0.2794)
			(end 0.12065 -0.3048)
			(stroke
				(width 0.1)
				(type default)
			)
			(layer "F.Fab")
		)
		(fp_line
			(start 0.67945 -0.3048)
			(end 0.67945 0.3048)
			(stroke
				(width 0.1)
				(type default)
			)
			(layer "F.Fab")
		)
		(fp_line
			(start 0.67945 0.3048)
			(end 0.120396 0.3048)
			(stroke
				(width 0.1)
				(type default)
			)
			(layer "F.Fab")
		)
		(pad "1" smd circle
			(at -0.40005 0)
			(size 0 0)
			(layers "F.Cu" "F.Mask" "F.Paste")
			(net "P3V3_AUX")
		)
		(pad "2" smd circle
			(at 0.40005 0)
			(size 0 0)
			(layers "F.Cu" "F.Mask" "F.Paste")
			(net "FAN_6_PRSNT_BUF_R_N")
		)
	)
	(footprint ""
		(layer "F.Cu")
		(at 20.828 -177.8 180)
		(property "Reference" "R5683"
			(at 0 0 180)
			(layer "F.SilkS")
			(hide yes)
			(effects
				(font
					(size 1.27 1.27)
				)
			)
		)
		(property "Value" ""
			(at 0 0 180)
			(layer "F.Fab")
			(effects
				(font
					(size 1.27 1.27)
				)
			)
		)
		(duplicate_pad_numbers_are_jumpers no)
		(fp_line
			(start 0.7874 0.4064)
			(end -0.7874 0.4064)
			(stroke
				(width 0.1524)
				(type default)
			)
			(layer "F.SilkS")
		)
		(fp_line
			(start 0.7874 -0.4064)
			(end 0.7874 0.4064)
			(stroke
				(width 0.1524)
				(type default)
			)
			(layer "F.SilkS")
		)
		(fp_line
			(start -0.7874 0.4064)
			(end -0.7874 -0.4064)
			(stroke
				(width 0.1524)
				(type default)
			)
			(layer "F.SilkS")
		)
		(fp_line
			(start -0.7874 -0.4064)
			(end 0.7874 -0.4064)
			(stroke
				(width 0.1524)
				(type default)
			)
			(layer "F.SilkS")
		)
		(fp_line
			(start 0.67945 0.3048)
			(end 0.120396 0.3048)
			(stroke
				(width 0.1)
				(type default)
			)
			(layer "F.Fab")
		)
		(fp_line
			(start 0.67945 -0.3048)
			(end 0.67945 0.3048)
			(stroke
				(width 0.1)
				(type default)
			)
			(layer "F.Fab")
		)
		(fp_line
			(start 0.12065 -0.2794)
			(end 0.12065 -0.3048)
			(stroke
				(width 0.1)
				(type default)
			)
			(layer "F.Fab")
		)
		(fp_line
			(start 0.12065 -0.3048)
			(end 0.67945 -0.3048)
			(stroke
				(width 0.1)
				(type default)
			)
			(layer "F.Fab")
		)
		(fp_line
			(start 0.120396 0.3048)
			(end 0.120396 0.2794)
			(stroke
				(width 0.1)
				(type default)
			)
			(layer "F.Fab")
		)
		(fp_line
			(start 0.120396 0.2794)
			(end -0.12065 0.2794)
			(stroke
				(width 0.1)
				(type default)
			)
			(layer "F.Fab")
		)
		(fp_line
			(start -0.12065 0.3048)
			(end -0.67945 0.3048)
			(stroke
				(width 0.1)
				(type default)
			)
			(layer "F.Fab")
		)
		(fp_line
			(start -0.12065 0.2794)
			(end -0.12065 0.3048)
			(stroke
				(width 0.1)
				(type default)
			)
			(layer "F.Fab")
		)
		(fp_line
			(start -0.12065 -0.2794)
			(end 0.12065 -0.2794)
			(stroke
				(width 0.1)
				(type default)
			)
			(layer "F.Fab")
		)
		(fp_line
			(start -0.12065 -0.305054)
			(end -0.12065 -0.2794)
			(stroke
				(width 0.1)
				(type default)
			)
			(layer "F.Fab")
		)
		(fp_line
			(start -0.67945 0.3048)
			(end -0.67945 -0.305054)
			(stroke
				(width 0.1)
				(type default)
			)
			(layer "F.Fab")
		)
		(fp_line
			(start -0.67945 -0.305054)
			(end -0.12065 -0.305054)
			(stroke
				(width 0.1)
				(type default)
			)
			(layer "F.Fab")
		)
		(pad "1" smd circle
			(at -0.40005 0 180)
			(size 0 0)
			(layers "F.Cu" "F.Mask" "F.Paste")
			(net "P3V3_AUX")
		)
		(pad "2" smd circle
			(at 0.40005 0 180)
			(size 0 0)
			(layers "F.Cu" "F.Mask" "F.Paste")
			(net "FM_BOARD_ID0")
		)
	)
	(footprint ""
		(layer "F.Cu")
		(at 3.248914 -67.494912 90)
		(property "Reference" "C2060"
			(at 0 0 90)
			(layer "F.SilkS")
			(hide yes)
			(effects
				(font
					(size 1.27 1.27)
				)
			)
		)
		(property "Value" ""
			(at 0 0 90)
			(layer "F.Fab")
			(effects
				(font
					(size 1.27 1.27)
				)
			)
		)
		(duplicate_pad_numbers_are_jumpers no)
		(fp_line
			(start 0.7874 -0.4064)
			(end 0.7874 0.4064)
			(stroke
				(width 0.1524)
				(type default)
			)
			(layer "F.SilkS")
		)
		(fp_line
			(start -0.7874 -0.4064)
			(end 0.7874 -0.4064)
			(stroke
				(width 0.1524)
				(type default)
			)
			(layer "F.SilkS")
		)
		(fp_line
			(start 0.7874 0.4064)
			(end -0.7874 0.4064)
			(stroke
				(width 0.1524)
				(type default)
			)
			(layer "F.SilkS")
		)
		(fp_line
			(start -0.7874 0.4064)
			(end -0.7874 -0.4064)
			(stroke
				(width 0.1524)
				(type default)
			)
			(layer "F.SilkS")
		)
		(fp_line
			(start -0.12065 -0.305054)
			(end -0.12065 -0.2794)
			(stroke
				(width 0.1)
				(type default)
			)
			(layer "F.Fab")
		)
		(fp_line
			(start -0.67945 -0.305054)
			(end -0.12065 -0.305054)
			(stroke
				(width 0.1)
				(type default)
			)
			(layer "F.Fab")
		)
		(fp_line
			(start 0.67945 -0.3048)
			(end 0.67945 0.3048)
			(stroke
				(width 0.1)
				(type default)
			)
			(layer "F.Fab")
		)
		(fp_line
			(start 0.12065 -0.3048)
			(end 0.67945 -0.3048)
			(stroke
				(width 0.1)
				(type default)
			)
			(layer "F.Fab")
		)
		(fp_line
			(start 0.12065 -0.2794)
			(end 0.12065 -0.3048)
			(stroke
				(width 0.1)
				(type default)
			)
			(layer "F.Fab")
		)
		(fp_line
			(start -0.12065 -0.2794)
			(end 0.12065 -0.2794)
			(stroke
				(width 0.1)
				(type default)
			)
			(layer "F.Fab")
		)
		(fp_line
			(start 0.120396 0.2794)
			(end -0.12065 0.2794)
			(stroke
				(width 0.1)
				(type default)
			)
			(layer "F.Fab")
		)
		(fp_line
			(start -0.12065 0.2794)
			(end -0.12065 0.3048)
			(stroke
				(width 0.1)
				(type default)
			)
			(layer "F.Fab")
		)
		(fp_line
			(start 0.67945 0.3048)
			(end 0.120396 0.3048)
			(stroke
				(width 0.1)
				(type default)
			)
			(layer "F.Fab")
		)
		(fp_line
			(start 0.120396 0.3048)
			(end 0.120396 0.2794)
			(stroke
				(width 0.1)
				(type default)
			)
			(layer "F.Fab")
		)
		(fp_line
			(start -0.12065 0.3048)
			(end -0.67945 0.3048)
			(stroke
				(width 0.1)
				(type default)
			)
			(layer "F.Fab")
		)
		(fp_line
			(start -0.67945 0.3048)
			(end -0.67945 -0.305054)
			(stroke
				(width 0.1)
				(type default)
			)
			(layer "F.Fab")
		)
		(pad "1" smd circle
			(at -0.40005 0 90)
			(size 0 0)
			(layers "F.Cu" "F.Mask" "F.Paste")
			(net "P3V3_AUX")
		)
		(pad "2" smd circle
			(at 0.40005 0 90)
			(size 0 0)
			(layers "F.Cu" "F.Mask" "F.Paste")
			(net "GND")
		)
	)
	(footprint ""
		(layer "F.Cu")
		(at 3.937 -308.61)
		(property "Reference" "C2051"
			(at 0 0 0)
			(layer "F.SilkS")
			(hide yes)
			(effects
				(font
					(size 1.27 1.27)
				)
			)
		)
		(property "Value" ""
			(at 0 0 0)
			(layer "F.Fab")
			(effects
				(font
					(size 1.27 1.27)
				)
			)
		)
		(duplicate_pad_numbers_are_jumpers no)
		(fp_line
			(start -0.7874 -0.4064)
			(end 0.7874 -0.4064)
			(stroke
				(width 0.1524)
				(type default)
			)
			(layer "F.SilkS")
		)
		(fp_line
			(start -0.7874 0.4064)
			(end -0.7874 -0.4064)
			(stroke
				(width 0.1524)
				(type default)
			)
			(layer "F.SilkS")
		)
		(fp_line
			(start 0.7874 -0.4064)
			(end 0.7874 0.4064)
			(stroke
				(width 0.1524)
				(type default)
			)
			(layer "F.SilkS")
		)
		(fp_line
			(start 0.7874 0.4064)
			(end -0.7874 0.4064)
			(stroke
				(width 0.1524)
				(type default)
			)
			(layer "F.SilkS")
		)
		(fp_line
			(start -0.6858 -0.3048)
			(end -0.1016 -0.3048)
			(stroke
				(width 0.1)
				(type default)
			)
			(layer "F.Fab")
		)
		(fp_line
			(start -0.6858 0.3048)
			(end -0.6858 -0.3048)
			(stroke
				(width 0.1)
				(type default)
			)
			(layer "F.Fab")
		)
		(fp_line
			(start -0.1016 -0.3048)
			(end -0.1016 -0.2794)
			(stroke
				(width 0.1)
				(type default)
			)
			(layer "F.Fab")
		)
		(fp_line
			(start -0.1016 -0.2794)
			(end 0.1016 -0.2794)
			(stroke
				(width 0.1)
				(type default)
			)
			(layer "F.Fab")
		)
		(fp_line
			(start -0.1016 0.2794)
			(end -0.1016 0.3048)
			(stroke
				(width 0.1)
				(type default)
			)
			(layer "F.Fab")
		)
		(fp_line
			(start -0.1016 0.3048)
			(end -0.6858 0.3048)
			(stroke
				(width 0.1)
				(type default)
			)
			(layer "F.Fab")
		)
		(fp_line
			(start 0.1016 -0.3048)
			(end 0.6858 -0.3048)
			(stroke
				(width 0.1)
				(type default)
			)
			(layer "F.Fab")
		)
		(fp_line
			(start 0.1016 -0.2794)
			(end 0.1016 -0.3048)
			(stroke
				(width 0.1)
				(type default)
			)
			(layer "F.Fab")
		)
		(fp_line
			(start 0.1016 0.2794)
			(end -0.1016 0.2794)
			(stroke
				(width 0.1)
				(type default)
			)
			(layer "F.Fab")
		)
		(fp_line
			(start 0.1016 0.3048)
			(end 0.1016 0.2794)
			(stroke
				(width 0.1)
				(type default)
			)
			(layer "F.Fab")
		)
		(fp_line
			(start 0.6858 -0.3048)
			(end 0.6858 0.3048)
			(stroke
				(width 0.1)
				(type default)
			)
			(layer "F.Fab")
		)
		(fp_line
			(start 0.6858 0.3048)
			(end 0.1016 0.3048)
			(stroke
				(width 0.1)
				(type default)
			)
			(layer "F.Fab")
		)
		(pad "1" smd rect
			(at -0.40005 0 180)
			(size 0.4572 0.508)
			(layers "F.Cu" "F.Mask" "F.Paste")
			(net "GND")
		)
		(pad "2" smd rect
			(at 0.40005 0 180)
			(size 0.4572 0.508)
			(layers "F.Cu" "F.Mask" "F.Paste")
			(net "P12V_LED_FAN7")
		)
	)
	(footprint ""
		(layer "F.Cu")
		(at 31.369 -16.891)
		(property "Reference" "C2090"
			(at 0 0 0)
			(layer "F.SilkS")
			(hide yes)
			(effects
				(font
					(size 1.27 1.27)
				)
			)
		)
		(property "Value" ""
			(at 0 0 0)
			(layer "F.Fab")
			(effects
				(font
					(size 1.27 1.27)
				)
			)
		)
		(duplicate_pad_numbers_are_jumpers no)
		(fp_line
			(start -0.7874 -0.4064)
			(end 0.7874 -0.4064)
			(stroke
				(width 0.1524)
				(type default)
			)
			(layer "F.SilkS")
		)
		(fp_line
			(start -0.7874 0.4064)
			(end -0.7874 -0.4064)
			(stroke
				(width 0.1524)
				(type default)
			)
			(layer "F.SilkS")
		)
		(fp_line
			(start 0.7874 -0.4064)
			(end 0.7874 0.4064)
			(stroke
				(width 0.1524)
				(type default)
			)
			(layer "F.SilkS")
		)
		(fp_line
			(start 0.7874 0.4064)
			(end -0.7874 0.4064)
			(stroke
				(width 0.1524)
				(type default)
			)
			(layer "F.SilkS")
		)
		(fp_line
			(start -0.67945 -0.305054)
			(end -0.12065 -0.305054)
			(stroke
				(width 0.1)
				(type default)
			)
			(layer "F.Fab")
		)
		(fp_line
			(start -0.67945 0.3048)
			(end -0.67945 -0.305054)
			(stroke
				(width 0.1)
				(type default)
			)
			(layer "F.Fab")
		)
		(fp_line
			(start -0.12065 -0.305054)
			(end -0.12065 -0.2794)
			(stroke
				(width 0.1)
				(type default)
			)
			(layer "F.Fab")
		)
		(fp_line
			(start -0.12065 -0.2794)
			(end 0.12065 -0.2794)
			(stroke
				(width 0.1)
				(type default)
			)
			(layer "F.Fab")
		)
		(fp_line
			(start -0.12065 0.2794)
			(end -0.12065 0.3048)
			(stroke
				(width 0.1)
				(type default)
			)
			(layer "F.Fab")
		)
		(fp_line
			(start -0.12065 0.3048)
			(end -0.67945 0.3048)
			(stroke
				(width 0.1)
				(type default)
			)
			(layer "F.Fab")
		)
		(fp_line
			(start 0.120396 0.2794)
			(end -0.12065 0.2794)
			(stroke
				(width 0.1)
				(type default)
			)
			(layer "F.Fab")
		)
		(fp_line
			(start 0.120396 0.3048)
			(end 0.120396 0.2794)
			(stroke
				(width 0.1)
				(type default)
			)
			(layer "F.Fab")
		)
		(fp_line
			(start 0.12065 -0.3048)
			(end 0.67945 -0.3048)
			(stroke
				(width 0.1)
				(type default)
			)
			(layer "F.Fab")
		)
		(fp_line
			(start 0.12065 -0.2794)
			(end 0.12065 -0.3048)
			(stroke
				(width 0.1)
				(type default)
			)
			(layer "F.Fab")
		)
		(fp_line
			(start 0.67945 -0.3048)
			(end 0.67945 0.3048)
			(stroke
				(width 0.1)
				(type default)
			)
			(layer "F.Fab")
		)
		(fp_line
			(start 0.67945 0.3048)
			(end 0.120396 0.3048)
			(stroke
				(width 0.1)
				(type default)
			)
			(layer "F.Fab")
		)
		(pad "1" smd circle
			(at -0.40005 0)
			(size 0 0)
			(layers "F.Cu" "F.Mask" "F.Paste")
			(net "P3V3_AUX")
		)
		(pad "2" smd circle
			(at 0.40005 0)
			(size 0 0)
			(layers "F.Cu" "F.Mask" "F.Paste")
			(net "GND")
		)
	)
	(footprint ""
		(layer "F.Cu")
		(at 34.925 -200.8632)
		(property "Reference" "R5528"
			(at 0 0 0)
			(layer "F.SilkS")
			(hide yes)
			(effects
				(font
					(size 1.27 1.27)
				)
			)
		)
		(property "Value" ""
			(at 0 0 0)
			(layer "F.Fab")
			(effects
				(font
					(size 1.27 1.27)
				)
			)
		)
		(duplicate_pad_numbers_are_jumpers no)
		(fp_line
			(start -0.7874 -0.4064)
			(end 0.7874 -0.4064)
			(stroke
				(width 0.1524)
				(type default)
			)
			(layer "F.SilkS")
		)
		(fp_line
			(start -0.7874 0.4064)
			(end -0.7874 -0.4064)
			(stroke
				(width 0.1524)
				(type default)
			)
			(layer "F.SilkS")
		)
		(fp_line
			(start 0.7874 -0.4064)
			(end 0.7874 0.4064)
			(stroke
				(width 0.1524)
				(type default)
			)
			(layer "F.SilkS")
		)
		(fp_line
			(start 0.7874 0.4064)
			(end -0.7874 0.4064)
			(stroke
				(width 0.1524)
				(type default)
			)
			(layer "F.SilkS")
		)
		(fp_line
			(start -0.67945 -0.305054)
			(end -0.12065 -0.305054)
			(stroke
				(width 0.1)
				(type default)
			)
			(layer "F.Fab")
		)
		(fp_line
			(start -0.67945 0.3048)
			(end -0.67945 -0.305054)
			(stroke
				(width 0.1)
				(type default)
			)
			(layer "F.Fab")
		)
		(fp_line
			(start -0.12065 -0.305054)
			(end -0.12065 -0.2794)
			(stroke
				(width 0.1)
				(type default)
			)
			(layer "F.Fab")
		)
		(fp_line
			(start -0.12065 -0.2794)
			(end 0.12065 -0.2794)
			(stroke
				(width 0.1)
				(type default)
			)
			(layer "F.Fab")
		)
		(fp_line
			(start -0.12065 0.2794)
			(end -0.12065 0.3048)
			(stroke
				(width 0.1)
				(type default)
			)
			(layer "F.Fab")
		)
		(fp_line
			(start -0.12065 0.3048)
			(end -0.67945 0.3048)
			(stroke
				(width 0.1)
				(type default)
			)
			(layer "F.Fab")
		)
		(fp_line
			(start 0.120396 0.2794)
			(end -0.12065 0.2794)
			(stroke
				(width 0.1)
				(type default)
			)
			(layer "F.Fab")
		)
		(fp_line
			(start 0.120396 0.3048)
			(end 0.120396 0.2794)
			(stroke
				(width 0.1)
				(type default)
			)
			(layer "F.Fab")
		)
		(fp_line
			(start 0.12065 -0.3048)
			(end 0.67945 -0.3048)
			(stroke
				(width 0.1)
				(type default)
			)
			(layer "F.Fab")
		)
		(fp_line
			(start 0.12065 -0.2794)
			(end 0.12065 -0.3048)
			(stroke
				(width 0.1)
				(type default)
			)
			(layer "F.Fab")
		)
		(fp_line
			(start 0.67945 -0.3048)
			(end 0.67945 0.3048)
			(stroke
				(width 0.1)
				(type default)
			)
			(layer "F.Fab")
		)
		(fp_line
			(start 0.67945 0.3048)
			(end 0.120396 0.3048)
			(stroke
				(width 0.1)
				(type default)
			)
			(layer "F.Fab")
		)
		(pad "1" smd rect
			(at -0.40005 0 180)
			(size 0.4572 0.508)
			(layers "F.Cu" "F.Mask" "F.Paste")
			(net "P12V_LED_FAN1")
		)
		(pad "2" smd rect
			(at 0.40005 0 180)
			(size 0.4572 0.508)
			(layers "F.Cu" "F.Mask" "F.Paste")
			(net "FAN_1_OK_LED_R_N")
		)
	)
	(footprint ""
		(layer "F.Cu")
		(at 3.81 -127.508)
		(property "Reference" "R5567"
			(at 0 0 0)
			(layer "F.SilkS")
			(hide yes)
			(effects
				(font
					(size 1.27 1.27)
				)
			)
		)
		(property "Value" ""
			(at 0 0 0)
			(layer "F.Fab")
			(effects
				(font
					(size 1.27 1.27)
				)
			)
		)
		(duplicate_pad_numbers_are_jumpers no)
		(fp_line
			(start -0.7874 -0.4064)
			(end 0.7874 -0.4064)
			(stroke
				(width 0.1524)
				(type default)
			)
			(layer "F.SilkS")
		)
		(fp_line
			(start -0.7874 0.4064)
			(end -0.7874 -0.4064)
			(stroke
				(width 0.1524)
				(type default)
			)
			(layer "F.SilkS")
		)
		(fp_line
			(start 0.7874 -0.4064)
			(end 0.7874 0.4064)
			(stroke
				(width 0.1524)
				(type default)
			)
			(layer "F.SilkS")
		)
		(fp_line
			(start 0.7874 0.4064)
			(end -0.7874 0.4064)
			(stroke
				(width 0.1524)
				(type default)
			)
			(layer "F.SilkS")
		)
		(fp_line
			(start -0.67945 -0.305054)
			(end -0.12065 -0.305054)
			(stroke
				(width 0.1)
				(type default)
			)
			(layer "F.Fab")
		)
		(fp_line
			(start -0.67945 0.3048)
			(end -0.67945 -0.305054)
			(stroke
				(width 0.1)
				(type default)
			)
			(layer "F.Fab")
		)
		(fp_line
			(start -0.12065 -0.305054)
			(end -0.12065 -0.2794)
			(stroke
				(width 0.1)
				(type default)
			)
			(layer "F.Fab")
		)
		(fp_line
			(start -0.12065 -0.2794)
			(end 0.12065 -0.2794)
			(stroke
				(width 0.1)
				(type default)
			)
			(layer "F.Fab")
		)
		(fp_line
			(start -0.12065 0.2794)
			(end -0.12065 0.3048)
			(stroke
				(width 0.1)
				(type default)
			)
			(layer "F.Fab")
		)
		(fp_line
			(start -0.12065 0.3048)
			(end -0.67945 0.3048)
			(stroke
				(width 0.1)
				(type default)
			)
			(layer "F.Fab")
		)
		(fp_line
			(start 0.120396 0.2794)
			(end -0.12065 0.2794)
			(stroke
				(width 0.1)
				(type default)
			)
			(layer "F.Fab")
		)
		(fp_line
			(start 0.120396 0.3048)
			(end 0.120396 0.2794)
			(stroke
				(width 0.1)
				(type default)
			)
			(layer "F.Fab")
		)
		(fp_line
			(start 0.12065 -0.3048)
			(end 0.67945 -0.3048)
			(stroke
				(width 0.1)
				(type default)
			)
			(layer "F.Fab")
		)
		(fp_line
			(start 0.12065 -0.2794)
			(end 0.12065 -0.3048)
			(stroke
				(width 0.1)
				(type default)
			)
			(layer "F.Fab")
		)
		(fp_line
			(start 0.67945 -0.3048)
			(end 0.67945 0.3048)
			(stroke
				(width 0.1)
				(type default)
			)
			(layer "F.Fab")
		)
		(fp_line
			(start 0.67945 0.3048)
			(end 0.120396 0.3048)
			(stroke
				(width 0.1)
				(type default)
			)
			(layer "F.Fab")
		)
		(pad "1" smd circle
			(at -0.40005 0)
			(size 0 0)
			(layers "F.Cu" "F.Mask" "F.Paste")
			(net "P3V3_AUX")
		)
		(pad "2" smd circle
			(at 0.40005 0)
			(size 0 0)
			(layers "F.Cu" "F.Mask" "F.Paste")
			(net "U404_ADD2")
		)
	)
	(footprint ""
		(layer "F.Cu")
		(at 40.127428 -253.656846)
		(property "Reference" "R5419"
			(at 0 0 0)
			(layer "F.SilkS")
			(hide yes)
			(effects
				(font
					(size 1.27 1.27)
				)
			)
		)
		(property "Value" ""
			(at 0 0 0)
			(layer "F.Fab")
			(effects
				(font
					(size 1.27 1.27)
				)
			)
		)
		(duplicate_pad_numbers_are_jumpers no)
		(fp_line
			(start -0.7874 -0.4064)
			(end 0.7874 -0.4064)
			(stroke
				(width 0.1524)
				(type default)
			)
			(layer "F.SilkS")
		)
		(fp_line
			(start -0.7874 0.4064)
			(end -0.7874 -0.4064)
			(stroke
				(width 0.1524)
				(type default)
			)
			(layer "F.SilkS")
		)
		(fp_line
			(start 0.7874 -0.4064)
			(end 0.7874 0.4064)
			(stroke
				(width 0.1524)
				(type default)
			)
			(layer "F.SilkS")
		)
		(fp_line
			(start 0.7874 0.4064)
			(end -0.7874 0.4064)
			(stroke
				(width 0.1524)
				(type default)
			)
			(layer "F.SilkS")
		)
		(fp_line
			(start -0.67945 -0.305054)
			(end -0.12065 -0.305054)
			(stroke
				(width 0.1)
				(type default)
			)
			(layer "F.Fab")
		)
		(fp_line
			(start -0.67945 0.3048)
			(end -0.67945 -0.305054)
			(stroke
				(width 0.1)
				(type default)
			)
			(layer "F.Fab")
		)
		(fp_line
			(start -0.12065 -0.305054)
			(end -0.12065 -0.2794)
			(stroke
				(width 0.1)
				(type default)
			)
			(layer "F.Fab")
		)
		(fp_line
			(start -0.12065 -0.2794)
			(end 0.12065 -0.2794)
			(stroke
				(width 0.1)
				(type default)
			)
			(layer "F.Fab")
		)
		(fp_line
			(start -0.12065 0.2794)
			(end -0.12065 0.3048)
			(stroke
				(width 0.1)
				(type default)
			)
			(layer "F.Fab")
		)
		(fp_line
			(start -0.12065 0.3048)
			(end -0.67945 0.3048)
			(stroke
				(width 0.1)
				(type default)
			)
			(layer "F.Fab")
		)
		(fp_line
			(start 0.120396 0.2794)
			(end -0.12065 0.2794)
			(stroke
				(width 0.1)
				(type default)
			)
			(layer "F.Fab")
		)
		(fp_line
			(start 0.120396 0.3048)
			(end 0.120396 0.2794)
			(stroke
				(width 0.1)
				(type default)
			)
			(layer "F.Fab")
		)
		(fp_line
			(start 0.12065 -0.3048)
			(end 0.67945 -0.3048)
			(stroke
				(width 0.1)
				(type default)
			)
			(layer "F.Fab")
		)
		(fp_line
			(start 0.12065 -0.2794)
			(end 0.12065 -0.3048)
			(stroke
				(width 0.1)
				(type default)
			)
			(layer "F.Fab")
		)
		(fp_line
			(start 0.67945 -0.3048)
			(end 0.67945 0.3048)
			(stroke
				(width 0.1)
				(type default)
			)
			(layer "F.Fab")
		)
		(fp_line
			(start 0.67945 0.3048)
			(end 0.120396 0.3048)
			(stroke
				(width 0.1)
				(type default)
			)
			(layer "F.Fab")
		)
		(pad "1" smd circle
			(at -0.40005 0)
			(size 0 0)
			(layers "F.Cu" "F.Mask" "F.Paste")
			(net "FAN_1_ON")
		)
		(pad "2" smd circle
			(at 0.40005 0)
			(size 0 0)
			(layers "F.Cu" "F.Mask" "F.Paste")
			(net "P52V_FAN_1_EN")
		)
	)
	(footprint ""
		(layer "F.Cu")
		(at 38.6461 -133.858)
		(property "Reference" "R5576"
			(at 0 0 0)
			(layer "F.SilkS")
			(hide yes)
			(effects
				(font
					(size 1.27 1.27)
				)
			)
		)
		(property "Value" ""
			(at 0 0 0)
			(layer "F.Fab")
			(effects
				(font
					(size 1.27 1.27)
				)
			)
		)
		(duplicate_pad_numbers_are_jumpers no)
		(fp_line
			(start -0.7874 -0.4064)
			(end 0.7874 -0.4064)
			(stroke
				(width 0.1524)
				(type default)
			)
			(layer "F.SilkS")
		)
		(fp_line
			(start -0.7874 0.4064)
			(end -0.7874 -0.4064)
			(stroke
				(width 0.1524)
				(type default)
			)
			(layer "F.SilkS")
		)
		(fp_line
			(start 0.7874 -0.4064)
			(end 0.7874 0.4064)
			(stroke
				(width 0.1524)
				(type default)
			)
			(layer "F.SilkS")
		)
		(fp_line
			(start 0.7874 0.4064)
			(end -0.7874 0.4064)
			(stroke
				(width 0.1524)
				(type default)
			)
			(layer "F.SilkS")
		)
		(fp_line
			(start -0.67945 -0.305054)
			(end -0.12065 -0.305054)
			(stroke
				(width 0.1)
				(type default)
			)
			(layer "F.Fab")
		)
		(fp_line
			(start -0.67945 0.3048)
			(end -0.67945 -0.305054)
			(stroke
				(width 0.1)
				(type default)
			)
			(layer "F.Fab")
		)
		(fp_line
			(start -0.12065 -0.305054)
			(end -0.12065 -0.2794)
			(stroke
				(width 0.1)
				(type default)
			)
			(layer "F.Fab")
		)
		(fp_line
			(start -0.12065 -0.2794)
			(end 0.12065 -0.2794)
			(stroke
				(width 0.1)
				(type default)
			)
			(layer "F.Fab")
		)
		(fp_line
			(start -0.12065 0.2794)
			(end -0.12065 0.3048)
			(stroke
				(width 0.1)
				(type default)
			)
			(layer "F.Fab")
		)
		(fp_line
			(start -0.12065 0.3048)
			(end -0.67945 0.3048)
			(stroke
				(width 0.1)
				(type default)
			)
			(layer "F.Fab")
		)
		(fp_line
			(start 0.120396 0.2794)
			(end -0.12065 0.2794)
			(stroke
				(width 0.1)
				(type default)
			)
			(layer "F.Fab")
		)
		(fp_line
			(start 0.120396 0.3048)
			(end 0.120396 0.2794)
			(stroke
				(width 0.1)
				(type default)
			)
			(layer "F.Fab")
		)
		(fp_line
			(start 0.12065 -0.3048)
			(end 0.67945 -0.3048)
			(stroke
				(width 0.1)
				(type default)
			)
			(layer "F.Fab")
		)
		(fp_line
			(start 0.12065 -0.2794)
			(end 0.12065 -0.3048)
			(stroke
				(width 0.1)
				(type default)
			)
			(layer "F.Fab")
		)
		(fp_line
			(start 0.67945 -0.3048)
			(end 0.67945 0.3048)
			(stroke
				(width 0.1)
				(type default)
			)
			(layer "F.Fab")
		)
		(fp_line
			(start 0.67945 0.3048)
			(end 0.120396 0.3048)
			(stroke
				(width 0.1)
				(type default)
			)
			(layer "F.Fab")
		)
		(pad "1" smd rect
			(at -0.40005 0 180)
			(size 0.4572 0.508)
			(layers "F.Cu" "F.Mask" "F.Paste")
			(net "FAN_0_TACH_OL")
		)
		(pad "2" smd rect
			(at 0.40005 0 180)
			(size 0.4572 0.508)
			(layers "F.Cu" "F.Mask" "F.Paste")
			(net "FAN_0_TACH_OL_R2")
		)
	)
	(footprint ""
		(layer "F.Cu")
		(at 19.431 -298.45 -90)
		(property "Reference" "R5378"
			(at 0 0 270)
			(layer "F.SilkS")
			(hide yes)
			(effects
				(font
					(size 1.27 1.27)
				)
			)
		)
		(property "Value" ""
			(at 0 0 270)
			(layer "F.Fab")
			(effects
				(font
					(size 1.27 1.27)
				)
			)
		)
		(duplicate_pad_numbers_are_jumpers no)
		(fp_line
			(start -0.7874 0.4064)
			(end -0.7874 -0.4064)
			(stroke
				(width 0.1524)
				(type default)
			)
			(layer "F.SilkS")
		)
		(fp_line
			(start 0.7874 0.4064)
			(end -0.7874 0.4064)
			(stroke
				(width 0.1524)
				(type default)
			)
			(layer "F.SilkS")
		)
		(fp_line
			(start -0.7874 -0.4064)
			(end 0.7874 -0.4064)
			(stroke
				(width 0.1524)
				(type default)
			)
			(layer "F.SilkS")
		)
		(fp_line
			(start 0.7874 -0.4064)
			(end 0.7874 0.4064)
			(stroke
				(width 0.1524)
				(type default)
			)
			(layer "F.SilkS")
		)
		(fp_line
			(start -0.67945 0.3048)
			(end -0.67945 -0.305054)
			(stroke
				(width 0.1)
				(type default)
			)
			(layer "F.Fab")
		)
		(fp_line
			(start -0.12065 0.3048)
			(end -0.67945 0.3048)
			(stroke
				(width 0.1)
				(type default)
			)
			(layer "F.Fab")
		)
		(fp_line
			(start 0.120396 0.3048)
			(end 0.120396 0.2794)
			(stroke
				(width 0.1)
				(type default)
			)
			(layer "F.Fab")
		)
		(fp_line
			(start 0.67945 0.3048)
			(end 0.120396 0.3048)
			(stroke
				(width 0.1)
				(type default)
			)
			(layer "F.Fab")
		)
		(fp_line
			(start -0.12065 0.2794)
			(end -0.12065 0.3048)
			(stroke
				(width 0.1)
				(type default)
			)
			(layer "F.Fab")
		)
		(fp_line
			(start 0.120396 0.2794)
			(end -0.12065 0.2794)
			(stroke
				(width 0.1)
				(type default)
			)
			(layer "F.Fab")
		)
		(fp_line
			(start -0.12065 -0.2794)
			(end 0.12065 -0.2794)
			(stroke
				(width 0.1)
				(type default)
			)
			(layer "F.Fab")
		)
		(fp_line
			(start 0.12065 -0.2794)
			(end 0.12065 -0.3048)
			(stroke
				(width 0.1)
				(type default)
			)
			(layer "F.Fab")
		)
		(fp_line
			(start 0.12065 -0.3048)
			(end 0.67945 -0.3048)
			(stroke
				(width 0.1)
				(type default)
			)
			(layer "F.Fab")
		)
		(fp_line
			(start 0.67945 -0.3048)
			(end 0.67945 0.3048)
			(stroke
				(width 0.1)
				(type default)
			)
			(layer "F.Fab")
		)
		(fp_line
			(start -0.67945 -0.305054)
			(end -0.12065 -0.305054)
			(stroke
				(width 0.1)
				(type default)
			)
			(layer "F.Fab")
		)
		(fp_line
			(start -0.12065 -0.305054)
			(end -0.12065 -0.2794)
			(stroke
				(width 0.1)
				(type default)
			)
			(layer "F.Fab")
		)
		(pad "1" smd circle
			(at -0.40005 0 270)
			(size 0 0)
			(layers "F.Cu" "F.Mask" "F.Paste")
			(net "P3V3_AUX")
		)
		(pad "2" smd circle
			(at 0.40005 0 270)
			(size 0 0)
			(layers "F.Cu" "F.Mask" "F.Paste")
			(net "FAN_7_OK_R_LED")
		)
	)
	(footprint ""
		(layer "F.Cu")
		(at 15.377922 -290.2331 180)
		(property "Reference" "D260"
			(at 5.217922 -0.06477 0)
			(unlocked yes)
			(layer "F.SilkS")
			(effects
				(font
					(size 0.7874 0.5842)
					(thickness 0.1524)
				)
				(justify left)
			)
		)
		(property "Value" ""
			(at 0 0 180)
			(layer "F.Fab")
			(effects
				(font
					(size 1.27 1.27)
				)
			)
		)
		(duplicate_pad_numbers_are_jumpers no)
		(fp_line
			(start 0.94488 0.450088)
			(end 0.94488 -0.450088)
			(stroke
				(width 0.1524)
				(type default)
			)
			(layer "F.SilkS")
		)
		(fp_line
			(start 0.94488 -0.450088)
			(end -0.854964 -0.450088)
			(stroke
				(width 0.1524)
				(type default)
			)
			(layer "F.SilkS")
		)
		(fp_line
			(start 0.870458 -0.2794)
			(end 0.845058 0.4064)
			(stroke
				(width 0.1524)
				(type default)
			)
			(layer "F.SilkS")
		)
		(fp_line
			(start 0.845058 0.4064)
			(end 0.845058 -0.381)
			(stroke
				(width 0.1524)
				(type default)
			)
			(layer "F.SilkS")
		)
		(fp_line
			(start -0.854964 0.450088)
			(end 0.925068 0.450088)
			(stroke
				(width 0.1524)
				(type default)
			)
			(layer "F.SilkS")
		)
		(fp_line
			(start -0.854964 -0.450088)
			(end -0.854964 0.450088)
			(stroke
				(width 0.1524)
				(type default)
			)
			(layer "F.SilkS")
		)
		(fp_line
			(start 0.54991 0.350012)
			(end 0.54991 -0.350012)
			(stroke
				(width 0.1)
				(type default)
			)
			(layer "F.Fab")
		)
		(fp_line
			(start 0.54991 -0.350012)
			(end -0.54991 -0.350012)
			(stroke
				(width 0.1)
				(type default)
			)
			(layer "F.Fab")
		)
		(fp_line
			(start -0.54991 0.350012)
			(end 0.54991 0.350012)
			(stroke
				(width 0.1)
				(type default)
			)
			(layer "F.Fab")
		)
		(fp_line
			(start -0.54991 -0.350012)
			(end -0.54991 0.350012)
			(stroke
				(width 0.1)
				(type default)
			)
			(layer "F.Fab")
		)
		(fp_text user "-"
			(at 2.169922 -0.32385 0)
			(unlocked yes)
			(layer "F.SilkS")
			(effects
				(font
					(size 1.905 1.4224)
					(thickness 0.1524)
				)
				(justify left)
			)
		)
		(fp_text user "+"
			(at -0.808228 0.239014 0)
			(unlocked yes)
			(layer "F.SilkS")
			(effects
				(font
					(size 1.905 1.4224)
					(thickness 0.1524)
				)
				(justify left)
			)
		)
		(fp_text user "-"
			(at 2.48539 0.239014 0)
			(unlocked yes)
			(layer "F.Fab")
			(effects
				(font
					(size 1.905 1.4224)
					(thickness 0.1524)
				)
				(justify left)
			)
		)
		(fp_text user "+"
			(at -0.808228 0.239014 0)
			(unlocked yes)
			(layer "F.Fab")
			(effects
				(font
					(size 1.905 1.4224)
					(thickness 0.1524)
				)
				(justify left)
			)
		)
		(pad "A" smd rect
			(at -0.424942 0 180)
			(size 0.5588 0.6096)
			(layers "F.Cu" "F.Mask" "F.Paste")
			(net "GND")
		)
		(pad "C" smd rect
			(at 0.424942 0)
			(size 0.5588 0.6096)
			(layers "F.Cu" "F.Mask" "F.Paste")
			(net "FAN_7_TACH_IL_D")
		)
	)
	(footprint ""
		(layer "F.Cu")
		(at 15.377922 -302.4251 180)
		(property "Reference" "D144"
			(at 5.852922 -0.06477 0)
			(unlocked yes)
			(layer "F.SilkS")
			(effects
				(font
					(size 0.7874 0.5842)
					(thickness 0.1524)
				)
				(justify left)
			)
		)
		(property "Value" ""
			(at 0 0 180)
			(layer "F.Fab")
			(effects
				(font
					(size 1.27 1.27)
				)
			)
		)
		(duplicate_pad_numbers_are_jumpers no)
		(fp_line
			(start 1.778 0.6858)
			(end 1.778 -0.6858)
			(stroke
				(width 0.1524)
				(type default)
			)
			(layer "F.SilkS")
		)
		(fp_line
			(start 1.651 -0.6858)
			(end 1.651 0.6858)
			(stroke
				(width 0.1524)
				(type default)
			)
			(layer "F.SilkS")
		)
		(fp_line
			(start 0.299974 -0.500126)
			(end 0.299974 0.500126)
			(stroke
				(width 0.1524)
				(type default)
			)
			(layer "F.SilkS")
		)
		(fp_line
			(start 0.199898 0)
			(end -0.299974 -0.500126)
			(stroke
				(width 0.1524)
				(type default)
			)
			(layer "F.SilkS")
		)
		(fp_line
			(start -0.299974 0.500126)
			(end 0.199898 0)
			(stroke
				(width 0.1524)
				(type default)
			)
			(layer "F.SilkS")
		)
		(fp_line
			(start -0.299974 -0.500126)
			(end -0.299974 0.500126)
			(stroke
				(width 0.1524)
				(type default)
			)
			(layer "F.SilkS")
		)
		(fp_line
			(start 1.35001 0.175006)
			(end 0.899922 0.175006)
			(stroke
				(width 0.1)
				(type default)
			)
			(layer "F.Fab")
		)
		(fp_line
			(start 1.35001 -0.225044)
			(end 1.35001 0.175006)
			(stroke
				(width 0.1)
				(type default)
			)
			(layer "F.Fab")
		)
		(fp_line
			(start 0.899922 0.700024)
			(end -0.899922 0.700024)
			(stroke
				(width 0.1)
				(type default)
			)
			(layer "F.Fab")
		)
		(fp_line
			(start 0.899922 0.175006)
			(end 0.899922 0.700024)
			(stroke
				(width 0.1)
				(type default)
			)
			(layer "F.Fab")
		)
		(fp_line
			(start 0.899922 -0.225044)
			(end 1.35001 -0.225044)
			(stroke
				(width 0.1)
				(type default)
			)
			(layer "F.Fab")
		)
		(fp_line
			(start 0.899922 -0.700024)
			(end 0.899922 -0.225044)
			(stroke
				(width 0.1)
				(type default)
			)
			(layer "F.Fab")
		)
		(fp_line
			(start 0.299974 -0.500126)
			(end 0.299974 0.500126)
			(stroke
				(width 0.1)
				(type default)
			)
			(layer "F.Fab")
		)
		(fp_line
			(start 0.199898 0)
			(end -0.299974 -0.500126)
			(stroke
				(width 0.1)
				(type default)
			)
			(layer "F.Fab")
		)
		(fp_line
			(start -0.299974 0.500126)
			(end 0.199898 0)
			(stroke
				(width 0.1)
				(type default)
			)
			(layer "F.Fab")
		)
		(fp_line
			(start -0.299974 -0.500126)
			(end -0.299974 0.500126)
			(stroke
				(width 0.1)
				(type default)
			)
			(layer "F.Fab")
		)
		(fp_line
			(start -0.899922 0.700024)
			(end -0.899922 0.175006)
			(stroke
				(width 0.1)
				(type default)
			)
			(layer "F.Fab")
		)
		(fp_line
			(start -0.899922 0.175006)
			(end -1.35001 0.175006)
			(stroke
				(width 0.1)
				(type default)
			)
			(layer "F.Fab")
		)
		(fp_line
			(start -0.899922 -0.225044)
			(end -0.899922 -0.700024)
			(stroke
				(width 0.1)
				(type default)
			)
			(layer "F.Fab")
		)
		(fp_line
			(start -0.899922 -0.700024)
			(end 0.899922 -0.700024)
			(stroke
				(width 0.1)
				(type default)
			)
			(layer "F.Fab")
		)
		(fp_line
			(start -1.35001 0.175006)
			(end -1.35001 -0.225044)
			(stroke
				(width 0.1)
				(type default)
			)
			(layer "F.Fab")
		)
		(fp_line
			(start -1.35001 -0.225044)
			(end -0.899922 -0.225044)
			(stroke
				(width 0.1)
				(type default)
			)
			(layer "F.Fab")
		)
		(fp_text user "-"
			(at 1.928622 0.38227 180)
			(unlocked yes)
			(layer "F.SilkS")
			(effects
				(font
					(size 1.905 1.4224)
					(thickness 0.1524)
				)
				(justify left)
			)
		)
		(fp_text user "+"
			(at -2.554478 -1.09855 180)
			(unlocked yes)
			(layer "F.SilkS")
			(effects
				(font
					(size 1.905 1.4224)
					(thickness 0.1524)
				)
				(justify left)
			)
		)
		(fp_text user "-"
			(at 1.8288 -0.24765 180)
			(unlocked yes)
			(layer "F.Fab")
			(effects
				(font
					(size 1.905 1.4224)
					(thickness 0.1524)
				)
				(justify left)
			)
		)
		(fp_text user "+"
			(at -2.794 -0.19685 180)
			(unlocked yes)
			(layer "F.Fab")
			(effects
				(font
					(size 1.905 1.4224)
					(thickness 0.1524)
				)
				(justify left)
			)
		)
		(pad "1" smd rect
			(at -1.0922 0)
			(size 0.8128 0.8636)
			(layers "F.Cu" "F.Mask" "F.Paste")
			(net "FAN_7_TACH_OL_R")
		)
		(pad "2" smd rect
			(at 1.0922 0 180)
			(size 0.8128 0.8636)
			(layers "F.Cu" "F.Mask" "F.Paste")
			(net "FAN_7_TACH_OL_D")
		)
	)
	(footprint ""
		(layer "F.Cu")
		(at 46.355 -165.608)
		(property "Reference" "R5115"
			(at 0 0 0)
			(layer "F.SilkS")
			(hide yes)
			(effects
				(font
					(size 1.27 1.27)
				)
			)
		)
		(property "Value" ""
			(at 0 0 0)
			(layer "F.Fab")
			(effects
				(font
					(size 1.27 1.27)
				)
			)
		)
		(duplicate_pad_numbers_are_jumpers no)
		(fp_line
			(start -0.7874 -0.4064)
			(end 0.7874 -0.4064)
			(stroke
				(width 0.1524)
				(type default)
			)
			(layer "F.SilkS")
		)
		(fp_line
			(start -0.7874 0.4064)
			(end -0.7874 -0.4064)
			(stroke
				(width 0.1524)
				(type default)
			)
			(layer "F.SilkS")
		)
		(fp_line
			(start 0.7874 -0.4064)
			(end 0.7874 0.4064)
			(stroke
				(width 0.1524)
				(type default)
			)
			(layer "F.SilkS")
		)
		(fp_line
			(start 0.7874 0.4064)
			(end -0.7874 0.4064)
			(stroke
				(width 0.1524)
				(type default)
			)
			(layer "F.SilkS")
		)
		(fp_line
			(start -0.67945 -0.305054)
			(end -0.12065 -0.305054)
			(stroke
				(width 0.1)
				(type default)
			)
			(layer "F.Fab")
		)
		(fp_line
			(start -0.67945 0.3048)
			(end -0.67945 -0.305054)
			(stroke
				(width 0.1)
				(type default)
			)
			(layer "F.Fab")
		)
		(fp_line
			(start -0.12065 -0.305054)
			(end -0.12065 -0.2794)
			(stroke
				(width 0.1)
				(type default)
			)
			(layer "F.Fab")
		)
		(fp_line
			(start -0.12065 -0.2794)
			(end 0.12065 -0.2794)
			(stroke
				(width 0.1)
				(type default)
			)
			(layer "F.Fab")
		)
		(fp_line
			(start -0.12065 0.2794)
			(end -0.12065 0.3048)
			(stroke
				(width 0.1)
				(type default)
			)
			(layer "F.Fab")
		)
		(fp_line
			(start -0.12065 0.3048)
			(end -0.67945 0.3048)
			(stroke
				(width 0.1)
				(type default)
			)
			(layer "F.Fab")
		)
		(fp_line
			(start 0.120396 0.2794)
			(end -0.12065 0.2794)
			(stroke
				(width 0.1)
				(type default)
			)
			(layer "F.Fab")
		)
		(fp_line
			(start 0.120396 0.3048)
			(end 0.120396 0.2794)
			(stroke
				(width 0.1)
				(type default)
			)
			(layer "F.Fab")
		)
		(fp_line
			(start 0.12065 -0.3048)
			(end 0.67945 -0.3048)
			(stroke
				(width 0.1)
				(type default)
			)
			(layer "F.Fab")
		)
		(fp_line
			(start 0.12065 -0.2794)
			(end 0.12065 -0.3048)
			(stroke
				(width 0.1)
				(type default)
			)
			(layer "F.Fab")
		)
		(fp_line
			(start 0.67945 -0.3048)
			(end 0.67945 0.3048)
			(stroke
				(width 0.1)
				(type default)
			)
			(layer "F.Fab")
		)
		(fp_line
			(start 0.67945 0.3048)
			(end 0.120396 0.3048)
			(stroke
				(width 0.1)
				(type default)
			)
			(layer "F.Fab")
		)
		(pad "1" smd circle
			(at -0.40005 0)
			(size 0 0)
			(layers "F.Cu" "F.Mask" "F.Paste")
			(net "PCA9552_MB1_A0")
		)
		(pad "2" smd circle
			(at 0.40005 0)
			(size 0 0)
			(layers "F.Cu" "F.Mask" "F.Paste")
			(net "GND")
		)
	)
	(footprint ""
		(layer "F.Cu")
		(at 4.191 -162.814 180)
		(property "Reference" "R100"
			(at 0 0 180)
			(layer "F.SilkS")
			(hide yes)
			(effects
				(font
					(size 1.27 1.27)
				)
			)
		)
		(property "Value" ""
			(at 0 0 180)
			(layer "F.Fab")
			(effects
				(font
					(size 1.27 1.27)
				)
			)
		)
		(duplicate_pad_numbers_are_jumpers no)
		(fp_line
			(start 0.7874 0.4064)
			(end -0.7874 0.4064)
			(stroke
				(width 0.1524)
				(type default)
			)
			(layer "F.SilkS")
		)
		(fp_line
			(start 0.7874 -0.4064)
			(end 0.7874 0.4064)
			(stroke
				(width 0.1524)
				(type default)
			)
			(layer "F.SilkS")
		)
		(fp_line
			(start -0.7874 0.4064)
			(end -0.7874 -0.4064)
			(stroke
				(width 0.1524)
				(type default)
			)
			(layer "F.SilkS")
		)
		(fp_line
			(start -0.7874 -0.4064)
			(end 0.7874 -0.4064)
			(stroke
				(width 0.1524)
				(type default)
			)
			(layer "F.SilkS")
		)
		(fp_line
			(start 0.67945 0.3048)
			(end 0.120396 0.3048)
			(stroke
				(width 0.1)
				(type default)
			)
			(layer "F.Fab")
		)
		(fp_line
			(start 0.67945 -0.3048)
			(end 0.67945 0.3048)
			(stroke
				(width 0.1)
				(type default)
			)
			(layer "F.Fab")
		)
		(fp_line
			(start 0.12065 -0.2794)
			(end 0.12065 -0.3048)
			(stroke
				(width 0.1)
				(type default)
			)
			(layer "F.Fab")
		)
		(fp_line
			(start 0.12065 -0.3048)
			(end 0.67945 -0.3048)
			(stroke
				(width 0.1)
				(type default)
			)
			(layer "F.Fab")
		)
		(fp_line
			(start 0.120396 0.3048)
			(end 0.120396 0.2794)
			(stroke
				(width 0.1)
				(type default)
			)
			(layer "F.Fab")
		)
		(fp_line
			(start 0.120396 0.2794)
			(end -0.12065 0.2794)
			(stroke
				(width 0.1)
				(type default)
			)
			(layer "F.Fab")
		)
		(fp_line
			(start -0.12065 0.3048)
			(end -0.67945 0.3048)
			(stroke
				(width 0.1)
				(type default)
			)
			(layer "F.Fab")
		)
		(fp_line
			(start -0.12065 0.2794)
			(end -0.12065 0.3048)
			(stroke
				(width 0.1)
				(type default)
			)
			(layer "F.Fab")
		)
		(fp_line
			(start -0.12065 -0.2794)
			(end 0.12065 -0.2794)
			(stroke
				(width 0.1)
				(type default)
			)
			(layer "F.Fab")
		)
		(fp_line
			(start -0.12065 -0.305054)
			(end -0.12065 -0.2794)
			(stroke
				(width 0.1)
				(type default)
			)
			(layer "F.Fab")
		)
		(fp_line
			(start -0.67945 0.3048)
			(end -0.67945 -0.305054)
			(stroke
				(width 0.1)
				(type default)
			)
			(layer "F.Fab")
		)
		(fp_line
			(start -0.67945 -0.305054)
			(end -0.12065 -0.305054)
			(stroke
				(width 0.1)
				(type default)
			)
			(layer "F.Fab")
		)
		(pad "1" smd circle
			(at -0.40005 0 180)
			(size 0 0)
			(layers "F.Cu" "F.Mask" "F.Paste")
			(net "FAN_0_PRSNT_BUF_R_N")
		)
		(pad "2" smd circle
			(at 0.40005 0 180)
			(size 0 0)
			(layers "F.Cu" "F.Mask" "F.Paste")
			(net "FAN_0_PRSNT_BUF_N")
		)
	)
	(footprint ""
		(layer "F.Cu")
		(at 27.432 -180.594 180)
		(property "Reference" "R5488"
			(at 0 0 180)
			(layer "F.SilkS")
			(hide yes)
			(effects
				(font
					(size 1.27 1.27)
				)
			)
		)
		(property "Value" ""
			(at 0 0 180)
			(layer "F.Fab")
			(effects
				(font
					(size 1.27 1.27)
				)
			)
		)
		(duplicate_pad_numbers_are_jumpers no)
		(fp_line
			(start 0.7874 0.4064)
			(end -0.7874 0.4064)
			(stroke
				(width 0.1524)
				(type default)
			)
			(layer "F.SilkS")
		)
		(fp_line
			(start 0.7874 -0.4064)
			(end 0.7874 0.4064)
			(stroke
				(width 0.1524)
				(type default)
			)
			(layer "F.SilkS")
		)
		(fp_line
			(start -0.7874 0.4064)
			(end -0.7874 -0.4064)
			(stroke
				(width 0.1524)
				(type default)
			)
			(layer "F.SilkS")
		)
		(fp_line
			(start -0.7874 -0.4064)
			(end 0.7874 -0.4064)
			(stroke
				(width 0.1524)
				(type default)
			)
			(layer "F.SilkS")
		)
		(fp_line
			(start 0.67945 0.3048)
			(end 0.120396 0.3048)
			(stroke
				(width 0.1)
				(type default)
			)
			(layer "F.Fab")
		)
		(fp_line
			(start 0.67945 -0.3048)
			(end 0.67945 0.3048)
			(stroke
				(width 0.1)
				(type default)
			)
			(layer "F.Fab")
		)
		(fp_line
			(start 0.12065 -0.2794)
			(end 0.12065 -0.3048)
			(stroke
				(width 0.1)
				(type default)
			)
			(layer "F.Fab")
		)
		(fp_line
			(start 0.12065 -0.3048)
			(end 0.67945 -0.3048)
			(stroke
				(width 0.1)
				(type default)
			)
			(layer "F.Fab")
		)
		(fp_line
			(start 0.120396 0.3048)
			(end 0.120396 0.2794)
			(stroke
				(width 0.1)
				(type default)
			)
			(layer "F.Fab")
		)
		(fp_line
			(start 0.120396 0.2794)
			(end -0.12065 0.2794)
			(stroke
				(width 0.1)
				(type default)
			)
			(layer "F.Fab")
		)
		(fp_line
			(start -0.12065 0.3048)
			(end -0.67945 0.3048)
			(stroke
				(width 0.1)
				(type default)
			)
			(layer "F.Fab")
		)
		(fp_line
			(start -0.12065 0.2794)
			(end -0.12065 0.3048)
			(stroke
				(width 0.1)
				(type default)
			)
			(layer "F.Fab")
		)
		(fp_line
			(start -0.12065 -0.2794)
			(end 0.12065 -0.2794)
			(stroke
				(width 0.1)
				(type default)
			)
			(layer "F.Fab")
		)
		(fp_line
			(start -0.12065 -0.305054)
			(end -0.12065 -0.2794)
			(stroke
				(width 0.1)
				(type default)
			)
			(layer "F.Fab")
		)
		(fp_line
			(start -0.67945 0.3048)
			(end -0.67945 -0.305054)
			(stroke
				(width 0.1)
				(type default)
			)
			(layer "F.Fab")
		)
		(fp_line
			(start -0.67945 -0.305054)
			(end -0.12065 -0.305054)
			(stroke
				(width 0.1)
				(type default)
			)
			(layer "F.Fab")
		)
		(pad "1" smd circle
			(at -0.40005 0 180)
			(size 0 0)
			(layers "F.Cu" "F.Mask" "F.Paste")
			(net "P52V_FAN_1_BUFF_EN")
		)
		(pad "2" smd circle
			(at 0.40005 0 180)
			(size 0 0)
			(layers "F.Cu" "F.Mask" "F.Paste")
			(net "P52V_FAN_1_BUFF_EN_R")
		)
	)
	(footprint ""
		(layer "F.Cu")
		(at 48.387 -98.552)
		(property "Reference" "Q11"
			(at 0.16764 -2.42951 0)
			(unlocked yes)
			(layer "F.SilkS")
			(effects
				(font
					(size 0.7874 0.5842)
					(thickness 0.1524)
				)
				(justify left)
			)
		)
		(property "Value" ""
			(at 0 0 0)
			(layer "F.Fab")
			(effects
				(font
					(size 1.27 1.27)
				)
			)
		)
		(duplicate_pad_numbers_are_jumpers no)
		(fp_line
			(start -1.905 -1.651)
			(end 1.905 -1.651)
			(stroke
				(width 0.1524)
				(type default)
			)
			(layer "F.SilkS")
		)
		(fp_line
			(start -1.905 1.651)
			(end -1.905 -1.651)
			(stroke
				(width 0.1524)
				(type default)
			)
			(layer "F.SilkS")
		)
		(fp_line
			(start 1.905 -1.651)
			(end 1.905 1.651)
			(stroke
				(width 0.1524)
				(type default)
			)
			(layer "F.SilkS")
		)
		(fp_line
			(start 1.905 1.651)
			(end -1.905 1.651)
			(stroke
				(width 0.1524)
				(type default)
			)
			(layer "F.SilkS")
		)
		(fp_line
			(start -1.249934 -1.169924)
			(end -0.6985 -1.169924)
			(stroke
				(width 0.1)
				(type default)
			)
			(layer "F.Fab")
		)
		(fp_line
			(start -1.249934 -0.729996)
			(end -1.249934 -1.169924)
			(stroke
				(width 0.1)
				(type default)
			)
			(layer "F.Fab")
		)
		(fp_line
			(start -1.249934 0.729996)
			(end -0.6985 0.729996)
			(stroke
				(width 0.1)
				(type default)
			)
			(layer "F.Fab")
		)
		(fp_line
			(start -1.249934 1.169924)
			(end -1.249934 0.729996)
			(stroke
				(width 0.1)
				(type default)
			)
			(layer "F.Fab")
		)
		(fp_line
			(start -0.6985 -1.524)
			(end 0.6985 -1.524)
			(stroke
				(width 0.1)
				(type default)
			)
			(layer "F.Fab")
		)
		(fp_line
			(start -0.6985 -1.169924)
			(end -0.6985 -1.524)
			(stroke
				(width 0.1)
				(type default)
			)
			(layer "F.Fab")
		)
		(fp_line
			(start -0.6985 -0.729996)
			(end -1.249934 -0.729996)
			(stroke
				(width 0.1)
				(type default)
			)
			(layer "F.Fab")
		)
		(fp_line
			(start -0.6985 0.729996)
			(end -0.6985 -0.729996)
			(stroke
				(width 0.1)
				(type default)
			)
			(layer "F.Fab")
		)
		(fp_line
			(start -0.6985 1.169924)
			(end -1.249934 1.169924)
			(stroke
				(width 0.1)
				(type default)
			)
			(layer "F.Fab")
		)
		(fp_line
			(start -0.6985 1.524)
			(end -0.6985 1.169924)
			(stroke
				(width 0.1)
				(type default)
			)
			(layer "F.Fab")
		)
		(fp_line
			(start 0.6985 -1.524)
			(end 0.6985 -0.219964)
			(stroke
				(width 0.1)
				(type default)
			)
			(layer "F.Fab")
		)
		(fp_line
			(start 0.6985 -0.219964)
			(end 1.249934 -0.219964)
			(stroke
				(width 0.1)
				(type default)
			)
			(layer "F.Fab")
		)
		(fp_line
			(start 0.6985 0.219964)
			(end 0.6985 1.524)
			(stroke
				(width 0.1)
				(type default)
			)
			(layer "F.Fab")
		)
		(fp_line
			(start 0.6985 1.524)
			(end -0.6985 1.524)
			(stroke
				(width 0.1)
				(type default)
			)
			(layer "F.Fab")
		)
		(fp_line
			(start 1.249934 -0.219964)
			(end 1.249934 0.219964)
			(stroke
				(width 0.1)
				(type default)
			)
			(layer "F.Fab")
		)
		(fp_line
			(start 1.249934 0.219964)
			(end 0.6985 0.219964)
			(stroke
				(width 0.1)
				(type default)
			)
			(layer "F.Fab")
		)
		(fp_rect
			(start -0.6985 1.524)
			(end 0.6985 -1.524)
			(stroke
				(width 0)
				(type default)
			)
			(fill no)
			(layer "F.Fab")
		)
		(pad "D" smd rect
			(at 1.1176 0 270)
			(size 1.016 1.27)
			(layers "F.Cu" "F.Mask" "F.Paste")
			(net "P12V_LED_FAN2")
		)
		(pad "G" smd rect
			(at -1.1176 -1.016 270)
			(size 1.016 1.27)
			(layers "F.Cu" "F.Mask" "F.Paste")
			(net "U407_D1")
		)
		(pad "S" smd rect
			(at -1.1176 1.016 270)
			(size 1.016 1.27)
			(layers "F.Cu" "F.Mask" "F.Paste")
			(net "P12V_LED")
		)
	)
	(footprint ""
		(layer "F.Cu")
		(at 14.0589 -127.127 180)
		(property "Reference" "R5589"
			(at 0 0 180)
			(layer "F.SilkS")
			(hide yes)
			(effects
				(font
					(size 1.27 1.27)
				)
			)
		)
		(property "Value" ""
			(at 0 0 180)
			(layer "F.Fab")
			(effects
				(font
					(size 1.27 1.27)
				)
			)
		)
		(duplicate_pad_numbers_are_jumpers no)
		(fp_line
			(start 0.7874 0.4064)
			(end -0.7874 0.4064)
			(stroke
				(width 0.1524)
				(type default)
			)
			(layer "F.SilkS")
		)
		(fp_line
			(start 0.7874 -0.4064)
			(end 0.7874 0.4064)
			(stroke
				(width 0.1524)
				(type default)
			)
			(layer "F.SilkS")
		)
		(fp_line
			(start -0.7874 0.4064)
			(end -0.7874 -0.4064)
			(stroke
				(width 0.1524)
				(type default)
			)
			(layer "F.SilkS")
		)
		(fp_line
			(start -0.7874 -0.4064)
			(end 0.7874 -0.4064)
			(stroke
				(width 0.1524)
				(type default)
			)
			(layer "F.SilkS")
		)
		(fp_line
			(start 0.67945 0.3048)
			(end 0.120396 0.3048)
			(stroke
				(width 0.1)
				(type default)
			)
			(layer "F.Fab")
		)
		(fp_line
			(start 0.67945 -0.3048)
			(end 0.67945 0.3048)
			(stroke
				(width 0.1)
				(type default)
			)
			(layer "F.Fab")
		)
		(fp_line
			(start 0.12065 -0.2794)
			(end 0.12065 -0.3048)
			(stroke
				(width 0.1)
				(type default)
			)
			(layer "F.Fab")
		)
		(fp_line
			(start 0.12065 -0.3048)
			(end 0.67945 -0.3048)
			(stroke
				(width 0.1)
				(type default)
			)
			(layer "F.Fab")
		)
		(fp_line
			(start 0.120396 0.3048)
			(end 0.120396 0.2794)
			(stroke
				(width 0.1)
				(type default)
			)
			(layer "F.Fab")
		)
		(fp_line
			(start 0.120396 0.2794)
			(end -0.12065 0.2794)
			(stroke
				(width 0.1)
				(type default)
			)
			(layer "F.Fab")
		)
		(fp_line
			(start -0.12065 0.3048)
			(end -0.67945 0.3048)
			(stroke
				(width 0.1)
				(type default)
			)
			(layer "F.Fab")
		)
		(fp_line
			(start -0.12065 0.2794)
			(end -0.12065 0.3048)
			(stroke
				(width 0.1)
				(type default)
			)
			(layer "F.Fab")
		)
		(fp_line
			(start -0.12065 -0.2794)
			(end 0.12065 -0.2794)
			(stroke
				(width 0.1)
				(type default)
			)
			(layer "F.Fab")
		)
		(fp_line
			(start -0.12065 -0.305054)
			(end -0.12065 -0.2794)
			(stroke
				(width 0.1)
				(type default)
			)
			(layer "F.Fab")
		)
		(fp_line
			(start -0.67945 0.3048)
			(end -0.67945 -0.305054)
			(stroke
				(width 0.1)
				(type default)
			)
			(layer "F.Fab")
		)
		(fp_line
			(start -0.67945 -0.305054)
			(end -0.12065 -0.305054)
			(stroke
				(width 0.1)
				(type default)
			)
			(layer "F.Fab")
		)
		(pad "1" smd rect
			(at -0.40005 0)
			(size 0.4572 0.508)
			(layers "F.Cu" "F.Mask" "F.Paste")
			(net "FAN_5_PWM")
		)
		(pad "2" smd rect
			(at 0.40005 0)
			(size 0.4572 0.508)
			(layers "F.Cu" "F.Mask" "F.Paste")
			(net "FAN_5_PWM_R2")
		)
	)
	(footprint ""
		(layer "F.Cu")
		(at 20.828 -171.704 180)
		(property "Reference" "R5670"
			(at 0 0 180)
			(layer "F.SilkS")
			(hide yes)
			(effects
				(font
					(size 1.27 1.27)
				)
			)
		)
		(property "Value" ""
			(at 0 0 180)
			(layer "F.Fab")
			(effects
				(font
					(size 1.27 1.27)
				)
			)
		)
		(duplicate_pad_numbers_are_jumpers no)
		(fp_line
			(start 0.7874 0.4064)
			(end -0.7874 0.4064)
			(stroke
				(width 0.1524)
				(type default)
			)
			(layer "F.SilkS")
		)
		(fp_line
			(start 0.7874 -0.4064)
			(end 0.7874 0.4064)
			(stroke
				(width 0.1524)
				(type default)
			)
			(layer "F.SilkS")
		)
		(fp_line
			(start -0.7874 0.4064)
			(end -0.7874 -0.4064)
			(stroke
				(width 0.1524)
				(type default)
			)
			(layer "F.SilkS")
		)
		(fp_line
			(start -0.7874 -0.4064)
			(end 0.7874 -0.4064)
			(stroke
				(width 0.1524)
				(type default)
			)
			(layer "F.SilkS")
		)
		(fp_line
			(start 0.67945 0.3048)
			(end 0.120396 0.3048)
			(stroke
				(width 0.1)
				(type default)
			)
			(layer "F.Fab")
		)
		(fp_line
			(start 0.67945 -0.3048)
			(end 0.67945 0.3048)
			(stroke
				(width 0.1)
				(type default)
			)
			(layer "F.Fab")
		)
		(fp_line
			(start 0.12065 -0.2794)
			(end 0.12065 -0.3048)
			(stroke
				(width 0.1)
				(type default)
			)
			(layer "F.Fab")
		)
		(fp_line
			(start 0.12065 -0.3048)
			(end 0.67945 -0.3048)
			(stroke
				(width 0.1)
				(type default)
			)
			(layer "F.Fab")
		)
		(fp_line
			(start 0.120396 0.3048)
			(end 0.120396 0.2794)
			(stroke
				(width 0.1)
				(type default)
			)
			(layer "F.Fab")
		)
		(fp_line
			(start 0.120396 0.2794)
			(end -0.12065 0.2794)
			(stroke
				(width 0.1)
				(type default)
			)
			(layer "F.Fab")
		)
		(fp_line
			(start -0.12065 0.3048)
			(end -0.67945 0.3048)
			(stroke
				(width 0.1)
				(type default)
			)
			(layer "F.Fab")
		)
		(fp_line
			(start -0.12065 0.2794)
			(end -0.12065 0.3048)
			(stroke
				(width 0.1)
				(type default)
			)
			(layer "F.Fab")
		)
		(fp_line
			(start -0.12065 -0.2794)
			(end 0.12065 -0.2794)
			(stroke
				(width 0.1)
				(type default)
			)
			(layer "F.Fab")
		)
		(fp_line
			(start -0.12065 -0.305054)
			(end -0.12065 -0.2794)
			(stroke
				(width 0.1)
				(type default)
			)
			(layer "F.Fab")
		)
		(fp_line
			(start -0.67945 0.3048)
			(end -0.67945 -0.305054)
			(stroke
				(width 0.1)
				(type default)
			)
			(layer "F.Fab")
		)
		(fp_line
			(start -0.67945 -0.305054)
			(end -0.12065 -0.305054)
			(stroke
				(width 0.1)
				(type default)
			)
			(layer "F.Fab")
		)
		(pad "1" smd circle
			(at -0.40005 0 180)
			(size 0 0)
			(layers "F.Cu" "F.Mask" "F.Paste")
			(net "P3V3_AUX")
		)
		(pad "2" smd circle
			(at 0.40005 0 180)
			(size 0 0)
			(layers "F.Cu" "F.Mask" "F.Paste")
			(net "FM_BOARD_SKU_ID0")
		)
	)
	(footprint ""
		(layer "F.Cu")
		(at 15.113 -110.871 -90)
		(property "Reference" "R5366"
			(at 0 0 270)
			(layer "F.SilkS")
			(hide yes)
			(effects
				(font
					(size 1.27 1.27)
				)
			)
		)
		(property "Value" ""
			(at 0 0 270)
			(layer "F.Fab")
			(effects
				(font
					(size 1.27 1.27)
				)
			)
		)
		(duplicate_pad_numbers_are_jumpers no)
		(fp_line
			(start -0.7874 0.4064)
			(end -0.7874 -0.4064)
			(stroke
				(width 0.1524)
				(type default)
			)
			(layer "F.SilkS")
		)
		(fp_line
			(start 0.7874 0.4064)
			(end -0.7874 0.4064)
			(stroke
				(width 0.1524)
				(type default)
			)
			(layer "F.SilkS")
		)
		(fp_line
			(start -0.7874 -0.4064)
			(end 0.7874 -0.4064)
			(stroke
				(width 0.1524)
				(type default)
			)
			(layer "F.SilkS")
		)
		(fp_line
			(start 0.7874 -0.4064)
			(end 0.7874 0.4064)
			(stroke
				(width 0.1524)
				(type default)
			)
			(layer "F.SilkS")
		)
		(fp_line
			(start -0.67945 0.3048)
			(end -0.67945 -0.305054)
			(stroke
				(width 0.1)
				(type default)
			)
			(layer "F.Fab")
		)
		(fp_line
			(start -0.12065 0.3048)
			(end -0.67945 0.3048)
			(stroke
				(width 0.1)
				(type default)
			)
			(layer "F.Fab")
		)
		(fp_line
			(start 0.120396 0.3048)
			(end 0.120396 0.2794)
			(stroke
				(width 0.1)
				(type default)
			)
			(layer "F.Fab")
		)
		(fp_line
			(start 0.67945 0.3048)
			(end 0.120396 0.3048)
			(stroke
				(width 0.1)
				(type default)
			)
			(layer "F.Fab")
		)
		(fp_line
			(start -0.12065 0.2794)
			(end -0.12065 0.3048)
			(stroke
				(width 0.1)
				(type default)
			)
			(layer "F.Fab")
		)
		(fp_line
			(start 0.120396 0.2794)
			(end -0.12065 0.2794)
			(stroke
				(width 0.1)
				(type default)
			)
			(layer "F.Fab")
		)
		(fp_line
			(start -0.12065 -0.2794)
			(end 0.12065 -0.2794)
			(stroke
				(width 0.1)
				(type default)
			)
			(layer "F.Fab")
		)
		(fp_line
			(start 0.12065 -0.2794)
			(end 0.12065 -0.3048)
			(stroke
				(width 0.1)
				(type default)
			)
			(layer "F.Fab")
		)
		(fp_line
			(start 0.12065 -0.3048)
			(end 0.67945 -0.3048)
			(stroke
				(width 0.1)
				(type default)
			)
			(layer "F.Fab")
		)
		(fp_line
			(start 0.67945 -0.3048)
			(end 0.67945 0.3048)
			(stroke
				(width 0.1)
				(type default)
			)
			(layer "F.Fab")
		)
		(fp_line
			(start -0.67945 -0.305054)
			(end -0.12065 -0.305054)
			(stroke
				(width 0.1)
				(type default)
			)
			(layer "F.Fab")
		)
		(fp_line
			(start -0.12065 -0.305054)
			(end -0.12065 -0.2794)
			(stroke
				(width 0.1)
				(type default)
			)
			(layer "F.Fab")
		)
		(pad "1" smd rect
			(at -0.40005 0 90)
			(size 0.4572 0.508)
			(layers "F.Cu" "F.Mask" "F.Paste")
			(net "FAN_5_FAIL_LED_R_N")
		)
		(pad "2" smd rect
			(at 0.40005 0 90)
			(size 0.4572 0.508)
			(layers "F.Cu" "F.Mask" "F.Paste")
			(net "FAN_5_FAIL_R_LED_N")
		)
	)
	(footprint ""
		(layer "F.Cu")
		(at 36.322 -30.312868)
		(property "Reference" "D141"
			(at 3.302 -0.013462 0)
			(unlocked yes)
			(layer "F.SilkS")
			(effects
				(font
					(size 0.7874 0.5842)
					(thickness 0.1524)
				)
				(justify left)
			)
		)
		(property "Value" ""
			(at 0 0 0)
			(layer "F.Fab")
			(effects
				(font
					(size 1.27 1.27)
				)
			)
		)
		(duplicate_pad_numbers_are_jumpers no)
		(fp_line
			(start -1.651 -0.7112)
			(end 2.032 -0.7112)
			(stroke
				(width 0.1524)
				(type default)
			)
			(layer "F.SilkS")
		)
		(fp_line
			(start -1.651 0.7112)
			(end -1.651 -0.7112)
			(stroke
				(width 0.1524)
				(type default)
			)
			(layer "F.SilkS")
		)
		(fp_line
			(start -0.299974 -0.500126)
			(end -0.299974 0.500126)
			(stroke
				(width 0.1524)
				(type default)
			)
			(layer "F.SilkS")
		)
		(fp_line
			(start -0.299974 0.500126)
			(end 0.199898 0)
			(stroke
				(width 0.1524)
				(type default)
			)
			(layer "F.SilkS")
		)
		(fp_line
			(start 0.199898 0)
			(end -0.299974 -0.500126)
			(stroke
				(width 0.1524)
				(type default)
			)
			(layer "F.SilkS")
		)
		(fp_line
			(start 0.299974 -0.500126)
			(end 0.299974 0.500126)
			(stroke
				(width 0.1524)
				(type default)
			)
			(layer "F.SilkS")
		)
		(fp_line
			(start 1.651 -0.6858)
			(end 1.651 0.6858)
			(stroke
				(width 0.1524)
				(type default)
			)
			(layer "F.SilkS")
		)
		(fp_line
			(start 1.778 0.6858)
			(end 1.778 -0.6858)
			(stroke
				(width 0.1524)
				(type default)
			)
			(layer "F.SilkS")
		)
		(fp_line
			(start 1.905 -0.6858)
			(end 1.905 0.6858)
			(stroke
				(width 0.1524)
				(type default)
			)
			(layer "F.SilkS")
		)
		(fp_line
			(start 2.032 -0.7112)
			(end 2.032 0.7112)
			(stroke
				(width 0.1524)
				(type default)
			)
			(layer "F.SilkS")
		)
		(fp_line
			(start 2.032 0.7112)
			(end -1.651 0.7112)
			(stroke
				(width 0.1524)
				(type default)
			)
			(layer "F.SilkS")
		)
		(fp_line
			(start -1.35001 -0.225044)
			(end -0.899922 -0.225044)
			(stroke
				(width 0.1)
				(type default)
			)
			(layer "F.Fab")
		)
		(fp_line
			(start -1.35001 0.175006)
			(end -1.35001 -0.225044)
			(stroke
				(width 0.1)
				(type default)
			)
			(layer "F.Fab")
		)
		(fp_line
			(start -0.899922 -0.700024)
			(end 0.899922 -0.700024)
			(stroke
				(width 0.1)
				(type default)
			)
			(layer "F.Fab")
		)
		(fp_line
			(start -0.899922 -0.225044)
			(end -0.899922 -0.700024)
			(stroke
				(width 0.1)
				(type default)
			)
			(layer "F.Fab")
		)
		(fp_line
			(start -0.899922 0.175006)
			(end -1.35001 0.175006)
			(stroke
				(width 0.1)
				(type default)
			)
			(layer "F.Fab")
		)
		(fp_line
			(start -0.899922 0.700024)
			(end -0.899922 0.175006)
			(stroke
				(width 0.1)
				(type default)
			)
			(layer "F.Fab")
		)
		(fp_line
			(start -0.299974 -0.500126)
			(end -0.299974 0.500126)
			(stroke
				(width 0.1)
				(type default)
			)
			(layer "F.Fab")
		)
		(fp_line
			(start -0.299974 0.500126)
			(end 0.199898 0)
			(stroke
				(width 0.1)
				(type default)
			)
			(layer "F.Fab")
		)
		(fp_line
			(start 0.199898 0)
			(end -0.299974 -0.500126)
			(stroke
				(width 0.1)
				(type default)
			)
			(layer "F.Fab")
		)
		(fp_line
			(start 0.299974 -0.500126)
			(end 0.299974 0.500126)
			(stroke
				(width 0.1)
				(type default)
			)
			(layer "F.Fab")
		)
		(fp_line
			(start 0.899922 -0.700024)
			(end 0.899922 -0.225044)
			(stroke
				(width 0.1)
				(type default)
			)
			(layer "F.Fab")
		)
		(fp_line
			(start 0.899922 -0.225044)
			(end 1.35001 -0.225044)
			(stroke
				(width 0.1)
				(type default)
			)
			(layer "F.Fab")
		)
		(fp_line
			(start 0.899922 0.175006)
			(end 0.899922 0.700024)
			(stroke
				(width 0.1)
				(type default)
			)
			(layer "F.Fab")
		)
		(fp_line
			(start 0.899922 0.700024)
			(end -0.899922 0.700024)
			(stroke
				(width 0.1)
				(type default)
			)
			(layer "F.Fab")
		)
		(fp_line
			(start 1.35001 -0.225044)
			(end 1.35001 0.175006)
			(stroke
				(width 0.1)
				(type default)
			)
			(layer "F.Fab")
		)
		(fp_line
			(start 1.35001 0.175006)
			(end 0.899922 0.175006)
			(stroke
				(width 0.1)
				(type default)
			)
			(layer "F.Fab")
		)
		(fp_text user "+"
			(at -2.921 0.372618 0)
			(unlocked yes)
			(layer "F.SilkS")
			(effects
				(font
					(size 1.905 1.4224)
					(thickness 0.1524)
				)
				(justify left)
			)
		)
		(fp_text user "-"
			(at 1.8288 -0.24765 0)
			(unlocked yes)
			(layer "F.SilkS")
			(effects
				(font
					(size 1.905 1.4224)
					(thickness 0.1524)
				)
				(justify left)
			)
		)
		(fp_text user "+"
			(at -2.794 -0.19685 0)
			(unlocked yes)
			(layer "F.Fab")
			(effects
				(font
					(size 1.905 1.4224)
					(thickness 0.1524)
				)
				(justify left)
			)
		)
		(fp_text user "-"
			(at 1.8288 -0.24765 0)
			(unlocked yes)
			(layer "F.Fab")
			(effects
				(font
					(size 1.905 1.4224)
					(thickness 0.1524)
				)
				(justify left)
			)
		)
		(pad "1" smd rect
			(at -1.0922 0 180)
			(size 0.8128 0.8636)
			(layers "F.Cu" "F.Mask" "F.Paste")
			(net "FAN_3_TACH_IL_R")
		)
		(pad "2" smd rect
			(at 1.0922 0)
			(size 0.8128 0.8636)
			(layers "F.Cu" "F.Mask" "F.Paste")
			(net "FAN_3_TACH_IL_D")
		)
	)
	(footprint ""
		(layer "F.Cu")
		(at 14.0589 -128.524 180)
		(property "Reference" "R5590"
			(at 0 0 180)
			(layer "F.SilkS")
			(hide yes)
			(effects
				(font
					(size 1.27 1.27)
				)
			)
		)
		(property "Value" ""
			(at 0 0 180)
			(layer "F.Fab")
			(effects
				(font
					(size 1.27 1.27)
				)
			)
		)
		(duplicate_pad_numbers_are_jumpers no)
		(fp_line
			(start 0.7874 0.4064)
			(end -0.7874 0.4064)
			(stroke
				(width 0.1524)
				(type default)
			)
			(layer "F.SilkS")
		)
		(fp_line
			(start 0.7874 -0.4064)
			(end 0.7874 0.4064)
			(stroke
				(width 0.1524)
				(type default)
			)
			(layer "F.SilkS")
		)
		(fp_line
			(start -0.7874 0.4064)
			(end -0.7874 -0.4064)
			(stroke
				(width 0.1524)
				(type default)
			)
			(layer "F.SilkS")
		)
		(fp_line
			(start -0.7874 -0.4064)
			(end 0.7874 -0.4064)
			(stroke
				(width 0.1524)
				(type default)
			)
			(layer "F.SilkS")
		)
		(fp_line
			(start 0.67945 0.3048)
			(end 0.120396 0.3048)
			(stroke
				(width 0.1)
				(type default)
			)
			(layer "F.Fab")
		)
		(fp_line
			(start 0.67945 -0.3048)
			(end 0.67945 0.3048)
			(stroke
				(width 0.1)
				(type default)
			)
			(layer "F.Fab")
		)
		(fp_line
			(start 0.12065 -0.2794)
			(end 0.12065 -0.3048)
			(stroke
				(width 0.1)
				(type default)
			)
			(layer "F.Fab")
		)
		(fp_line
			(start 0.12065 -0.3048)
			(end 0.67945 -0.3048)
			(stroke
				(width 0.1)
				(type default)
			)
			(layer "F.Fab")
		)
		(fp_line
			(start 0.120396 0.3048)
			(end 0.120396 0.2794)
			(stroke
				(width 0.1)
				(type default)
			)
			(layer "F.Fab")
		)
		(fp_line
			(start 0.120396 0.2794)
			(end -0.12065 0.2794)
			(stroke
				(width 0.1)
				(type default)
			)
			(layer "F.Fab")
		)
		(fp_line
			(start -0.12065 0.3048)
			(end -0.67945 0.3048)
			(stroke
				(width 0.1)
				(type default)
			)
			(layer "F.Fab")
		)
		(fp_line
			(start -0.12065 0.2794)
			(end -0.12065 0.3048)
			(stroke
				(width 0.1)
				(type default)
			)
			(layer "F.Fab")
		)
		(fp_line
			(start -0.12065 -0.2794)
			(end 0.12065 -0.2794)
			(stroke
				(width 0.1)
				(type default)
			)
			(layer "F.Fab")
		)
		(fp_line
			(start -0.12065 -0.305054)
			(end -0.12065 -0.2794)
			(stroke
				(width 0.1)
				(type default)
			)
			(layer "F.Fab")
		)
		(fp_line
			(start -0.67945 0.3048)
			(end -0.67945 -0.305054)
			(stroke
				(width 0.1)
				(type default)
			)
			(layer "F.Fab")
		)
		(fp_line
			(start -0.67945 -0.305054)
			(end -0.12065 -0.305054)
			(stroke
				(width 0.1)
				(type default)
			)
			(layer "F.Fab")
		)
		(pad "1" smd rect
			(at -0.40005 0)
			(size 0.4572 0.508)
			(layers "F.Cu" "F.Mask" "F.Paste")
			(net "FAN_5_TACH_OL")
		)
		(pad "2" smd rect
			(at 0.40005 0)
			(size 0.4572 0.508)
			(layers "F.Cu" "F.Mask" "F.Paste")
			(net "FAN_5_TACH_OL_R2")
		)
	)
	(footprint ""
		(layer "F.Cu")
		(at 19.558 -110.236 -90)
		(property "Reference" "R5362"
			(at 0 0 270)
			(layer "F.SilkS")
			(hide yes)
			(effects
				(font
					(size 1.27 1.27)
				)
			)
		)
		(property "Value" ""
			(at 0 0 270)
			(layer "F.Fab")
			(effects
				(font
					(size 1.27 1.27)
				)
			)
		)
		(duplicate_pad_numbers_are_jumpers no)
		(fp_line
			(start -0.7874 0.4064)
			(end -0.7874 -0.4064)
			(stroke
				(width 0.1524)
				(type default)
			)
			(layer "F.SilkS")
		)
		(fp_line
			(start 0.7874 0.4064)
			(end -0.7874 0.4064)
			(stroke
				(width 0.1524)
				(type default)
			)
			(layer "F.SilkS")
		)
		(fp_line
			(start -0.7874 -0.4064)
			(end 0.7874 -0.4064)
			(stroke
				(width 0.1524)
				(type default)
			)
			(layer "F.SilkS")
		)
		(fp_line
			(start 0.7874 -0.4064)
			(end 0.7874 0.4064)
			(stroke
				(width 0.1524)
				(type default)
			)
			(layer "F.SilkS")
		)
		(fp_line
			(start -0.67945 0.3048)
			(end -0.67945 -0.305054)
			(stroke
				(width 0.1)
				(type default)
			)
			(layer "F.Fab")
		)
		(fp_line
			(start -0.12065 0.3048)
			(end -0.67945 0.3048)
			(stroke
				(width 0.1)
				(type default)
			)
			(layer "F.Fab")
		)
		(fp_line
			(start 0.120396 0.3048)
			(end 0.120396 0.2794)
			(stroke
				(width 0.1)
				(type default)
			)
			(layer "F.Fab")
		)
		(fp_line
			(start 0.67945 0.3048)
			(end 0.120396 0.3048)
			(stroke
				(width 0.1)
				(type default)
			)
			(layer "F.Fab")
		)
		(fp_line
			(start -0.12065 0.2794)
			(end -0.12065 0.3048)
			(stroke
				(width 0.1)
				(type default)
			)
			(layer "F.Fab")
		)
		(fp_line
			(start 0.120396 0.2794)
			(end -0.12065 0.2794)
			(stroke
				(width 0.1)
				(type default)
			)
			(layer "F.Fab")
		)
		(fp_line
			(start -0.12065 -0.2794)
			(end 0.12065 -0.2794)
			(stroke
				(width 0.1)
				(type default)
			)
			(layer "F.Fab")
		)
		(fp_line
			(start 0.12065 -0.2794)
			(end 0.12065 -0.3048)
			(stroke
				(width 0.1)
				(type default)
			)
			(layer "F.Fab")
		)
		(fp_line
			(start 0.12065 -0.3048)
			(end 0.67945 -0.3048)
			(stroke
				(width 0.1)
				(type default)
			)
			(layer "F.Fab")
		)
		(fp_line
			(start 0.67945 -0.3048)
			(end 0.67945 0.3048)
			(stroke
				(width 0.1)
				(type default)
			)
			(layer "F.Fab")
		)
		(fp_line
			(start -0.67945 -0.305054)
			(end -0.12065 -0.305054)
			(stroke
				(width 0.1)
				(type default)
			)
			(layer "F.Fab")
		)
		(fp_line
			(start -0.12065 -0.305054)
			(end -0.12065 -0.2794)
			(stroke
				(width 0.1)
				(type default)
			)
			(layer "F.Fab")
		)
		(pad "1" smd circle
			(at -0.40005 0 270)
			(size 0 0)
			(layers "F.Cu" "F.Mask" "F.Paste")
			(net "P3V3_AUX")
		)
		(pad "2" smd circle
			(at 0.40005 0 270)
			(size 0 0)
			(layers "F.Cu" "F.Mask" "F.Paste")
			(net "FAN_5_FAIL_R_LED")
		)
	)
	(footprint ""
		(layer "F.Cu")
		(at 48.26 -217.424)
		(property "Reference" "Q10"
			(at -0.75692 2.67335 0)
			(unlocked yes)
			(layer "F.SilkS")
			(effects
				(font
					(size 0.7874 0.5842)
					(thickness 0.1524)
				)
				(justify left)
			)
		)
		(property "Value" ""
			(at 0 0 0)
			(layer "F.Fab")
			(effects
				(font
					(size 1.27 1.27)
				)
			)
		)
		(duplicate_pad_numbers_are_jumpers no)
		(fp_line
			(start -1.905 -1.651)
			(end 1.905 -1.651)
			(stroke
				(width 0.1524)
				(type default)
			)
			(layer "F.SilkS")
		)
		(fp_line
			(start -1.905 1.651)
			(end -1.905 -1.651)
			(stroke
				(width 0.1524)
				(type default)
			)
			(layer "F.SilkS")
		)
		(fp_line
			(start 1.905 -1.651)
			(end 1.905 1.651)
			(stroke
				(width 0.1524)
				(type default)
			)
			(layer "F.SilkS")
		)
		(fp_line
			(start 1.905 1.651)
			(end -1.905 1.651)
			(stroke
				(width 0.1524)
				(type default)
			)
			(layer "F.SilkS")
		)
		(fp_line
			(start -1.249934 -1.169924)
			(end -0.6985 -1.169924)
			(stroke
				(width 0.1)
				(type default)
			)
			(layer "F.Fab")
		)
		(fp_line
			(start -1.249934 -0.729996)
			(end -1.249934 -1.169924)
			(stroke
				(width 0.1)
				(type default)
			)
			(layer "F.Fab")
		)
		(fp_line
			(start -1.249934 0.729996)
			(end -0.6985 0.729996)
			(stroke
				(width 0.1)
				(type default)
			)
			(layer "F.Fab")
		)
		(fp_line
			(start -1.249934 1.169924)
			(end -1.249934 0.729996)
			(stroke
				(width 0.1)
				(type default)
			)
			(layer "F.Fab")
		)
		(fp_line
			(start -0.6985 -1.524)
			(end 0.6985 -1.524)
			(stroke
				(width 0.1)
				(type default)
			)
			(layer "F.Fab")
		)
		(fp_line
			(start -0.6985 -1.169924)
			(end -0.6985 -1.524)
			(stroke
				(width 0.1)
				(type default)
			)
			(layer "F.Fab")
		)
		(fp_line
			(start -0.6985 -0.729996)
			(end -1.249934 -0.729996)
			(stroke
				(width 0.1)
				(type default)
			)
			(layer "F.Fab")
		)
		(fp_line
			(start -0.6985 0.729996)
			(end -0.6985 -0.729996)
			(stroke
				(width 0.1)
				(type default)
			)
			(layer "F.Fab")
		)
		(fp_line
			(start -0.6985 1.169924)
			(end -1.249934 1.169924)
			(stroke
				(width 0.1)
				(type default)
			)
			(layer "F.Fab")
		)
		(fp_line
			(start -0.6985 1.524)
			(end -0.6985 1.169924)
			(stroke
				(width 0.1)
				(type default)
			)
			(layer "F.Fab")
		)
		(fp_line
			(start 0.6985 -1.524)
			(end 0.6985 -0.219964)
			(stroke
				(width 0.1)
				(type default)
			)
			(layer "F.Fab")
		)
		(fp_line
			(start 0.6985 -0.219964)
			(end 1.249934 -0.219964)
			(stroke
				(width 0.1)
				(type default)
			)
			(layer "F.Fab")
		)
		(fp_line
			(start 0.6985 0.219964)
			(end 0.6985 1.524)
			(stroke
				(width 0.1)
				(type default)
			)
			(layer "F.Fab")
		)
		(fp_line
			(start 0.6985 1.524)
			(end -0.6985 1.524)
			(stroke
				(width 0.1)
				(type default)
			)
			(layer "F.Fab")
		)
		(fp_line
			(start 1.249934 -0.219964)
			(end 1.249934 0.219964)
			(stroke
				(width 0.1)
				(type default)
			)
			(layer "F.Fab")
		)
		(fp_line
			(start 1.249934 0.219964)
			(end 0.6985 0.219964)
			(stroke
				(width 0.1)
				(type default)
			)
			(layer "F.Fab")
		)
		(fp_rect
			(start -0.6985 1.524)
			(end 0.6985 -1.524)
			(stroke
				(width 0)
				(type default)
			)
			(fill no)
			(layer "F.Fab")
		)
		(pad "D" smd rect
			(at 1.1176 0 270)
			(size 1.016 1.27)
			(layers "F.Cu" "F.Mask" "F.Paste")
			(net "P12V_LED_FAN1")
		)
		(pad "G" smd rect
			(at -1.1176 -1.016 270)
			(size 1.016 1.27)
			(layers "F.Cu" "F.Mask" "F.Paste")
			(net "U406_D1")
		)
		(pad "S" smd rect
			(at -1.1176 1.016 270)
			(size 1.016 1.27)
			(layers "F.Cu" "F.Mask" "F.Paste")
			(net "P12V_LED")
		)
	)
	(footprint ""
		(layer "F.Cu")
		(at 33.401 -141.351 -90)
		(property "Reference" "R5283"
			(at 0 0 270)
			(layer "F.SilkS")
			(hide yes)
			(effects
				(font
					(size 1.27 1.27)
				)
			)
		)
		(property "Value" ""
			(at 0 0 270)
			(layer "F.Fab")
			(effects
				(font
					(size 1.27 1.27)
				)
			)
		)
		(duplicate_pad_numbers_are_jumpers no)
		(fp_line
			(start -0.7874 0.4064)
			(end -0.7874 -0.4064)
			(stroke
				(width 0.1524)
				(type default)
			)
			(layer "F.SilkS")
		)
		(fp_line
			(start 0.7874 0.4064)
			(end -0.7874 0.4064)
			(stroke
				(width 0.1524)
				(type default)
			)
			(layer "F.SilkS")
		)
		(fp_line
			(start -0.7874 -0.4064)
			(end 0.7874 -0.4064)
			(stroke
				(width 0.1524)
				(type default)
			)
			(layer "F.SilkS")
		)
		(fp_line
			(start 0.7874 -0.4064)
			(end 0.7874 0.4064)
			(stroke
				(width 0.1524)
				(type default)
			)
			(layer "F.SilkS")
		)
		(fp_line
			(start -0.67945 0.3048)
			(end -0.67945 -0.305054)
			(stroke
				(width 0.1)
				(type default)
			)
			(layer "F.Fab")
		)
		(fp_line
			(start -0.12065 0.3048)
			(end -0.67945 0.3048)
			(stroke
				(width 0.1)
				(type default)
			)
			(layer "F.Fab")
		)
		(fp_line
			(start 0.120396 0.3048)
			(end 0.120396 0.2794)
			(stroke
				(width 0.1)
				(type default)
			)
			(layer "F.Fab")
		)
		(fp_line
			(start 0.67945 0.3048)
			(end 0.120396 0.3048)
			(stroke
				(width 0.1)
				(type default)
			)
			(layer "F.Fab")
		)
		(fp_line
			(start -0.12065 0.2794)
			(end -0.12065 0.3048)
			(stroke
				(width 0.1)
				(type default)
			)
			(layer "F.Fab")
		)
		(fp_line
			(start 0.120396 0.2794)
			(end -0.12065 0.2794)
			(stroke
				(width 0.1)
				(type default)
			)
			(layer "F.Fab")
		)
		(fp_line
			(start -0.12065 -0.2794)
			(end 0.12065 -0.2794)
			(stroke
				(width 0.1)
				(type default)
			)
			(layer "F.Fab")
		)
		(fp_line
			(start 0.12065 -0.2794)
			(end 0.12065 -0.3048)
			(stroke
				(width 0.1)
				(type default)
			)
			(layer "F.Fab")
		)
		(fp_line
			(start 0.12065 -0.3048)
			(end 0.67945 -0.3048)
			(stroke
				(width 0.1)
				(type default)
			)
			(layer "F.Fab")
		)
		(fp_line
			(start 0.67945 -0.3048)
			(end 0.67945 0.3048)
			(stroke
				(width 0.1)
				(type default)
			)
			(layer "F.Fab")
		)
		(fp_line
			(start -0.67945 -0.305054)
			(end -0.12065 -0.305054)
			(stroke
				(width 0.1)
				(type default)
			)
			(layer "F.Fab")
		)
		(fp_line
			(start -0.12065 -0.305054)
			(end -0.12065 -0.2794)
			(stroke
				(width 0.1)
				(type default)
			)
			(layer "F.Fab")
		)
		(pad "1" smd circle
			(at -0.40005 0 270)
			(size 0 0)
			(layers "F.Cu" "F.Mask" "F.Paste")
			(net "SMB_FAN3_R_SDA")
		)
		(pad "2" smd circle
			(at 0.40005 0 270)
			(size 0 0)
			(layers "F.Cu" "F.Mask" "F.Paste")
			(net "P3V3_AUX")
		)
	)
	(footprint ""
		(layer "F.Cu")
		(at 36.449 -14.351 -90)
		(property "Reference" "C2055"
			(at 0 0 270)
			(layer "F.SilkS")
			(hide yes)
			(effects
				(font
					(size 1.27 1.27)
				)
			)
		)
		(property "Value" ""
			(at 0 0 270)
			(layer "F.Fab")
			(effects
				(font
					(size 1.27 1.27)
				)
			)
		)
		(duplicate_pad_numbers_are_jumpers no)
		(fp_line
			(start -0.7874 0.4064)
			(end -0.7874 -0.4064)
			(stroke
				(width 0.1524)
				(type default)
			)
			(layer "F.SilkS")
		)
		(fp_line
			(start 0.7874 0.4064)
			(end -0.7874 0.4064)
			(stroke
				(width 0.1524)
				(type default)
			)
			(layer "F.SilkS")
		)
		(fp_line
			(start -0.7874 -0.4064)
			(end 0.7874 -0.4064)
			(stroke
				(width 0.1524)
				(type default)
			)
			(layer "F.SilkS")
		)
		(fp_line
			(start 0.7874 -0.4064)
			(end 0.7874 0.4064)
			(stroke
				(width 0.1524)
				(type default)
			)
			(layer "F.SilkS")
		)
		(fp_line
			(start -0.67945 0.3048)
			(end -0.67945 -0.305054)
			(stroke
				(width 0.1)
				(type default)
			)
			(layer "F.Fab")
		)
		(fp_line
			(start -0.12065 0.3048)
			(end -0.67945 0.3048)
			(stroke
				(width 0.1)
				(type default)
			)
			(layer "F.Fab")
		)
		(fp_line
			(start 0.120396 0.3048)
			(end 0.120396 0.2794)
			(stroke
				(width 0.1)
				(type default)
			)
			(layer "F.Fab")
		)
		(fp_line
			(start 0.67945 0.3048)
			(end 0.120396 0.3048)
			(stroke
				(width 0.1)
				(type default)
			)
			(layer "F.Fab")
		)
		(fp_line
			(start -0.12065 0.2794)
			(end -0.12065 0.3048)
			(stroke
				(width 0.1)
				(type default)
			)
			(layer "F.Fab")
		)
		(fp_line
			(start 0.120396 0.2794)
			(end -0.12065 0.2794)
			(stroke
				(width 0.1)
				(type default)
			)
			(layer "F.Fab")
		)
		(fp_line
			(start -0.12065 -0.2794)
			(end 0.12065 -0.2794)
			(stroke
				(width 0.1)
				(type default)
			)
			(layer "F.Fab")
		)
		(fp_line
			(start 0.12065 -0.2794)
			(end 0.12065 -0.3048)
			(stroke
				(width 0.1)
				(type default)
			)
			(layer "F.Fab")
		)
		(fp_line
			(start 0.12065 -0.3048)
			(end 0.67945 -0.3048)
			(stroke
				(width 0.1)
				(type default)
			)
			(layer "F.Fab")
		)
		(fp_line
			(start 0.67945 -0.3048)
			(end 0.67945 0.3048)
			(stroke
				(width 0.1)
				(type default)
			)
			(layer "F.Fab")
		)
		(fp_line
			(start -0.67945 -0.305054)
			(end -0.12065 -0.305054)
			(stroke
				(width 0.1)
				(type default)
			)
			(layer "F.Fab")
		)
		(fp_line
			(start -0.12065 -0.305054)
			(end -0.12065 -0.2794)
			(stroke
				(width 0.1)
				(type default)
			)
			(layer "F.Fab")
		)
		(pad "1" smd circle
			(at -0.40005 0 270)
			(size 0 0)
			(layers "F.Cu" "F.Mask" "F.Paste")
			(net "FAN_3_TACH_OL_R")
		)
		(pad "2" smd circle
			(at 0.40005 0 270)
			(size 0 0)
			(layers "F.Cu" "F.Mask" "F.Paste")
			(net "GND")
		)
	)
	(footprint ""
		(layer "F.Cu")
		(at 36.322 -189.484)
		(property "Reference" "U389"
			(at -0.635 3.20167 0)
			(unlocked yes)
			(layer "F.SilkS")
			(effects
				(font
					(size 0.7874 0.5842)
					(thickness 0.1524)
				)
				(justify left)
			)
		)
		(property "Value" ""
			(at 0 0 0)
			(layer "F.Fab")
			(effects
				(font
					(size 1.27 1.27)
				)
			)
		)
		(duplicate_pad_numbers_are_jumpers no)
		(fp_line
			(start -2.0066 -2.5527)
			(end -0.5715 -2.5527)
			(stroke
				(width 0.1524)
				(type default)
			)
			(layer "F.SilkS")
		)
		(fp_line
			(start -2.0066 2.5527)
			(end -2.0066 -2.5527)
			(stroke
				(width 0.1524)
				(type default)
			)
			(layer "F.SilkS")
		)
		(fp_line
			(start -0.5715 -2.5527)
			(end 0 -1.9812)
			(stroke
				(width 0.1524)
				(type default)
			)
			(layer "F.SilkS")
		)
		(fp_line
			(start 0 -1.9812)
			(end 0.5715 -2.5527)
			(stroke
				(width 0.1524)
				(type default)
			)
			(layer "F.SilkS")
		)
		(fp_line
			(start 0.5715 -2.5527)
			(end 2.0066 -2.5527)
			(stroke
				(width 0.1524)
				(type default)
			)
			(layer "F.SilkS")
		)
		(fp_line
			(start 2.0066 -2.5527)
			(end 2.0066 2.5527)
			(stroke
				(width 0.1524)
				(type default)
			)
			(layer "F.SilkS")
		)
		(fp_line
			(start 2.0066 2.5527)
			(end -2.0066 2.5527)
			(stroke
				(width 0.1524)
				(type default)
			)
			(layer "F.SilkS")
		)
		(fp_poly
			(pts
				(xy -4.36372 -1.608328) (xy -4.36372 -2.233168) (xy -3.81 -1.905)
			)
			(stroke
				(width 0)
				(type default)
			)
			(fill yes)
			(layer "F.SilkS")
		)
		(fp_line
			(start -2.249932 -2.549906)
			(end 2.249932 -2.549906)
			(stroke
				(width 0.1)
				(type default)
			)
			(layer "F.Fab")
		)
		(fp_line
			(start -2.249932 2.549906)
			(end -2.249932 -2.549906)
			(stroke
				(width 0.1)
				(type default)
			)
			(layer "F.Fab")
		)
		(fp_line
			(start 2.249932 -2.549906)
			(end 2.249932 2.549906)
			(stroke
				(width 0.1)
				(type default)
			)
			(layer "F.Fab")
		)
		(fp_line
			(start 2.249932 2.549906)
			(end -2.249932 2.549906)
			(stroke
				(width 0.1)
				(type default)
			)
			(layer "F.Fab")
		)
		(fp_poly
			(pts
				(xy -4.36372 -1.608328) (xy -4.36372 -2.233168) (xy -3.81 -1.905)
			)
			(stroke
				(width 0)
				(type default)
			)
			(fill yes)
			(layer "F.Fab")
		)
		(pad "1" smd rect
			(at -2.921 -1.949958 270)
			(size 0.3556 1.4986)
			(layers "F.Cu" "F.Mask" "F.Paste")
			(net "P52V_FAN_BUFF_EN_R")
		)
		(pad "2" smd rect
			(at -2.921 -1.299972 270)
			(size 0.3556 1.4986)
			(layers "F.Cu" "F.Mask" "F.Paste")
			(net "P52V_FAN_4_BUFF_EN")
		)
		(pad "3" smd rect
			(at -2.921 -0.649986 270)
			(size 0.3556 1.4986)
			(layers "F.Cu" "F.Mask" "F.Paste")
			(net "P52V_FAN_BUFF_EN_R")
		)
		(pad "4" smd rect
			(at -2.921 0 270)
			(size 0.3556 1.4986)
			(layers "F.Cu" "F.Mask" "F.Paste")
			(net "P52V_FAN_5_BUFF_EN")
		)
		(pad "5" smd rect
			(at -2.921 0.649986 270)
			(size 0.3556 1.4986)
			(layers "F.Cu" "F.Mask" "F.Paste")
			(net "P52V_FAN_BUFF_EN_R")
		)
		(pad "6" smd rect
			(at -2.921 1.299972 270)
			(size 0.3556 1.4986)
			(layers "F.Cu" "F.Mask" "F.Paste")
			(net "P52V_FAN_6_BUFF_EN")
		)
		(pad "7" smd rect
			(at -2.921 1.949958 270)
			(size 0.3556 1.4986)
			(layers "F.Cu" "F.Mask" "F.Paste")
			(net "GND")
		)
		(pad "8" smd rect
			(at 2.921 1.949958 270)
			(size 0.3556 1.4986)
			(layers "F.Cu" "F.Mask" "F.Paste")
			(net "P52V_FAN_7_BUFF_EN")
		)
		(pad "9" smd rect
			(at 2.921 1.299972 270)
			(size 0.3556 1.4986)
			(layers "F.Cu" "F.Mask" "F.Paste")
			(net "P52V_FAN_BUFF_EN_R")
		)
		(pad "10" smd rect
			(at 2.921 0.649986 270)
			(size 0.3556 1.4986)
			(layers "F.Cu" "F.Mask" "F.Paste")
			(net "NC_U389_E")
		)
		(pad "11" smd rect
			(at 2.921 0 270)
			(size 0.3556 1.4986)
			(layers "F.Cu" "F.Mask" "F.Paste")
			(net "PD_FAN_BUFF_INPUT_U337E")
		)
		(pad "12" smd rect
			(at 2.921 -0.649986 270)
			(size 0.3556 1.4986)
			(layers "F.Cu" "F.Mask" "F.Paste")
			(net "NC_U389_F")
		)
		(pad "13" smd rect
			(at 2.921 -1.299972 270)
			(size 0.3556 1.4986)
			(layers "F.Cu" "F.Mask" "F.Paste")
			(net "PD_FAN_BUFF_INPUT_U337F")
		)
		(pad "14" smd rect
			(at 2.921 -1.949958 270)
			(size 0.3556 1.4986)
			(layers "F.Cu" "F.Mask" "F.Paste")
			(net "P3V3_AUX")
		)
	)
	(footprint ""
		(layer "F.Cu")
		(at 23.495 -215.265 90)
		(property "Reference" "R5668"
			(at 0 0 90)
			(layer "F.SilkS")
			(hide yes)
			(effects
				(font
					(size 1.27 1.27)
				)
			)
		)
		(property "Value" ""
			(at 0 0 90)
			(layer "F.Fab")
			(effects
				(font
					(size 1.27 1.27)
				)
			)
		)
		(duplicate_pad_numbers_are_jumpers no)
		(fp_line
			(start 0.7874 -0.4064)
			(end 0.7874 0.4064)
			(stroke
				(width 0.1524)
				(type default)
			)
			(layer "F.SilkS")
		)
		(fp_line
			(start -0.7874 -0.4064)
			(end 0.7874 -0.4064)
			(stroke
				(width 0.1524)
				(type default)
			)
			(layer "F.SilkS")
		)
		(fp_line
			(start 0.7874 0.4064)
			(end -0.7874 0.4064)
			(stroke
				(width 0.1524)
				(type default)
			)
			(layer "F.SilkS")
		)
		(fp_line
			(start -0.7874 0.4064)
			(end -0.7874 -0.4064)
			(stroke
				(width 0.1524)
				(type default)
			)
			(layer "F.SilkS")
		)
		(fp_line
			(start -0.12065 -0.305054)
			(end -0.12065 -0.2794)
			(stroke
				(width 0.1)
				(type default)
			)
			(layer "F.Fab")
		)
		(fp_line
			(start -0.67945 -0.305054)
			(end -0.12065 -0.305054)
			(stroke
				(width 0.1)
				(type default)
			)
			(layer "F.Fab")
		)
		(fp_line
			(start 0.67945 -0.3048)
			(end 0.67945 0.3048)
			(stroke
				(width 0.1)
				(type default)
			)
			(layer "F.Fab")
		)
		(fp_line
			(start 0.12065 -0.3048)
			(end 0.67945 -0.3048)
			(stroke
				(width 0.1)
				(type default)
			)
			(layer "F.Fab")
		)
		(fp_line
			(start 0.12065 -0.2794)
			(end 0.12065 -0.3048)
			(stroke
				(width 0.1)
				(type default)
			)
			(layer "F.Fab")
		)
		(fp_line
			(start -0.12065 -0.2794)
			(end 0.12065 -0.2794)
			(stroke
				(width 0.1)
				(type default)
			)
			(layer "F.Fab")
		)
		(fp_line
			(start 0.120396 0.2794)
			(end -0.12065 0.2794)
			(stroke
				(width 0.1)
				(type default)
			)
			(layer "F.Fab")
		)
		(fp_line
			(start -0.12065 0.2794)
			(end -0.12065 0.3048)
			(stroke
				(width 0.1)
				(type default)
			)
			(layer "F.Fab")
		)
		(fp_line
			(start 0.67945 0.3048)
			(end 0.120396 0.3048)
			(stroke
				(width 0.1)
				(type default)
			)
			(layer "F.Fab")
		)
		(fp_line
			(start 0.120396 0.3048)
			(end 0.120396 0.2794)
			(stroke
				(width 0.1)
				(type default)
			)
			(layer "F.Fab")
		)
		(fp_line
			(start -0.12065 0.3048)
			(end -0.67945 0.3048)
			(stroke
				(width 0.1)
				(type default)
			)
			(layer "F.Fab")
		)
		(fp_line
			(start -0.67945 0.3048)
			(end -0.67945 -0.305054)
			(stroke
				(width 0.1)
				(type default)
			)
			(layer "F.Fab")
		)
		(pad "1" smd circle
			(at -0.40005 0 90)
			(size 0 0)
			(layers "F.Cu" "F.Mask" "F.Paste")
			(net "FAN_6_PRESENT")
		)
		(pad "2" smd circle
			(at 0.40005 0 90)
			(size 0 0)
			(layers "F.Cu" "F.Mask" "F.Paste")
			(net "GND")
		)
	)
	(footprint ""
		(layer "F.Cu")
		(at 40.127428 -66.986912 180)
		(property "Reference" "C172"
			(at 0 0 180)
			(layer "F.SilkS")
			(hide yes)
			(effects
				(font
					(size 1.27 1.27)
				)
			)
		)
		(property "Value" ""
			(at 0 0 180)
			(layer "F.Fab")
			(effects
				(font
					(size 1.27 1.27)
				)
			)
		)
		(duplicate_pad_numbers_are_jumpers no)
		(fp_line
			(start 0.7874 0.4064)
			(end -0.7874 0.4064)
			(stroke
				(width 0.1524)
				(type default)
			)
			(layer "F.SilkS")
		)
		(fp_line
			(start 0.7874 -0.4064)
			(end 0.7874 0.4064)
			(stroke
				(width 0.1524)
				(type default)
			)
			(layer "F.SilkS")
		)
		(fp_line
			(start -0.7874 0.4064)
			(end -0.7874 -0.4064)
			(stroke
				(width 0.1524)
				(type default)
			)
			(layer "F.SilkS")
		)
		(fp_line
			(start -0.7874 -0.4064)
			(end 0.7874 -0.4064)
			(stroke
				(width 0.1524)
				(type default)
			)
			(layer "F.SilkS")
		)
		(fp_line
			(start 0.67945 0.3048)
			(end 0.120396 0.3048)
			(stroke
				(width 0.1)
				(type default)
			)
			(layer "F.Fab")
		)
		(fp_line
			(start 0.67945 -0.3048)
			(end 0.67945 0.3048)
			(stroke
				(width 0.1)
				(type default)
			)
			(layer "F.Fab")
		)
		(fp_line
			(start 0.12065 -0.2794)
			(end 0.12065 -0.3048)
			(stroke
				(width 0.1)
				(type default)
			)
			(layer "F.Fab")
		)
		(fp_line
			(start 0.12065 -0.3048)
			(end 0.67945 -0.3048)
			(stroke
				(width 0.1)
				(type default)
			)
			(layer "F.Fab")
		)
		(fp_line
			(start 0.120396 0.3048)
			(end 0.120396 0.2794)
			(stroke
				(width 0.1)
				(type default)
			)
			(layer "F.Fab")
		)
		(fp_line
			(start 0.120396 0.2794)
			(end -0.12065 0.2794)
			(stroke
				(width 0.1)
				(type default)
			)
			(layer "F.Fab")
		)
		(fp_line
			(start -0.12065 0.3048)
			(end -0.67945 0.3048)
			(stroke
				(width 0.1)
				(type default)
			)
			(layer "F.Fab")
		)
		(fp_line
			(start -0.12065 0.2794)
			(end -0.12065 0.3048)
			(stroke
				(width 0.1)
				(type default)
			)
			(layer "F.Fab")
		)
		(fp_line
			(start -0.12065 -0.2794)
			(end 0.12065 -0.2794)
			(stroke
				(width 0.1)
				(type default)
			)
			(layer "F.Fab")
		)
		(fp_line
			(start -0.12065 -0.305054)
			(end -0.12065 -0.2794)
			(stroke
				(width 0.1)
				(type default)
			)
			(layer "F.Fab")
		)
		(fp_line
			(start -0.67945 0.3048)
			(end -0.67945 -0.305054)
			(stroke
				(width 0.1)
				(type default)
			)
			(layer "F.Fab")
		)
		(fp_line
			(start -0.67945 -0.305054)
			(end -0.12065 -0.305054)
			(stroke
				(width 0.1)
				(type default)
			)
			(layer "F.Fab")
		)
		(pad "1" smd circle
			(at -0.40005 0 180)
			(size 0 0)
			(layers "F.Cu" "F.Mask" "F.Paste")
			(net "P3V3_AUX")
		)
		(pad "2" smd circle
			(at 0.40005 0 180)
			(size 0 0)
			(layers "F.Cu" "F.Mask" "F.Paste")
			(net "GND")
		)
	)
	(footprint ""
		(layer "F.Cu")
		(at 14.859 -134.874)
		(property "Reference" "R5619"
			(at 0 0 0)
			(layer "F.SilkS")
			(hide yes)
			(effects
				(font
					(size 1.27 1.27)
				)
			)
		)
		(property "Value" ""
			(at 0 0 0)
			(layer "F.Fab")
			(effects
				(font
					(size 1.27 1.27)
				)
			)
		)
		(duplicate_pad_numbers_are_jumpers no)
		(fp_line
			(start -0.7874 -0.4064)
			(end 0.7874 -0.4064)
			(stroke
				(width 0.1524)
				(type default)
			)
			(layer "F.SilkS")
		)
		(fp_line
			(start -0.7874 0.4064)
			(end -0.7874 -0.4064)
			(stroke
				(width 0.1524)
				(type default)
			)
			(layer "F.SilkS")
		)
		(fp_line
			(start 0.7874 -0.4064)
			(end 0.7874 0.4064)
			(stroke
				(width 0.1524)
				(type default)
			)
			(layer "F.SilkS")
		)
		(fp_line
			(start 0.7874 0.4064)
			(end -0.7874 0.4064)
			(stroke
				(width 0.1524)
				(type default)
			)
			(layer "F.SilkS")
		)
		(fp_line
			(start -0.67945 -0.305054)
			(end -0.12065 -0.305054)
			(stroke
				(width 0.1)
				(type default)
			)
			(layer "F.Fab")
		)
		(fp_line
			(start -0.67945 0.3048)
			(end -0.67945 -0.305054)
			(stroke
				(width 0.1)
				(type default)
			)
			(layer "F.Fab")
		)
		(fp_line
			(start -0.12065 -0.305054)
			(end -0.12065 -0.2794)
			(stroke
				(width 0.1)
				(type default)
			)
			(layer "F.Fab")
		)
		(fp_line
			(start -0.12065 -0.2794)
			(end 0.12065 -0.2794)
			(stroke
				(width 0.1)
				(type default)
			)
			(layer "F.Fab")
		)
		(fp_line
			(start -0.12065 0.2794)
			(end -0.12065 0.3048)
			(stroke
				(width 0.1)
				(type default)
			)
			(layer "F.Fab")
		)
		(fp_line
			(start -0.12065 0.3048)
			(end -0.67945 0.3048)
			(stroke
				(width 0.1)
				(type default)
			)
			(layer "F.Fab")
		)
		(fp_line
			(start 0.120396 0.2794)
			(end -0.12065 0.2794)
			(stroke
				(width 0.1)
				(type default)
			)
			(layer "F.Fab")
		)
		(fp_line
			(start 0.120396 0.3048)
			(end 0.120396 0.2794)
			(stroke
				(width 0.1)
				(type default)
			)
			(layer "F.Fab")
		)
		(fp_line
			(start 0.12065 -0.3048)
			(end 0.67945 -0.3048)
			(stroke
				(width 0.1)
				(type default)
			)
			(layer "F.Fab")
		)
		(fp_line
			(start 0.12065 -0.2794)
			(end 0.12065 -0.3048)
			(stroke
				(width 0.1)
				(type default)
			)
			(layer "F.Fab")
		)
		(fp_line
			(start 0.67945 -0.3048)
			(end 0.67945 0.3048)
			(stroke
				(width 0.1)
				(type default)
			)
			(layer "F.Fab")
		)
		(fp_line
			(start 0.67945 0.3048)
			(end 0.120396 0.3048)
			(stroke
				(width 0.1)
				(type default)
			)
			(layer "F.Fab")
		)
		(pad "1" smd rect
			(at -0.40005 0 180)
			(size 0.4572 0.508)
			(layers "F.Cu" "F.Mask" "F.Paste")
			(net "FAN_7_PWM")
		)
		(pad "2" smd rect
			(at 0.40005 0 180)
			(size 0.4572 0.508)
			(layers "F.Cu" "F.Mask" "F.Paste")
			(net "FAN_7_PWM_R1")
		)
	)
	(footprint ""
		(layer "F.Cu")
		(at 15.377922 -16.215868 180)
		(property "Reference" "D113"
			(at 5.217922 -1.002538 0)
			(unlocked yes)
			(layer "F.SilkS")
			(effects
				(font
					(size 0.7874 0.5842)
					(thickness 0.1524)
				)
				(justify left)
			)
		)
		(property "Value" ""
			(at 0 0 180)
			(layer "F.Fab")
			(effects
				(font
					(size 1.27 1.27)
				)
			)
		)
		(duplicate_pad_numbers_are_jumpers no)
		(fp_line
			(start 2.032 0.7112)
			(end -1.651 0.7112)
			(stroke
				(width 0.1524)
				(type default)
			)
			(layer "F.SilkS")
		)
		(fp_line
			(start 2.032 -0.7112)
			(end 2.032 0.7112)
			(stroke
				(width 0.1524)
				(type default)
			)
			(layer "F.SilkS")
		)
		(fp_line
			(start 1.905 -0.6858)
			(end 1.905 0.6858)
			(stroke
				(width 0.1524)
				(type default)
			)
			(layer "F.SilkS")
		)
		(fp_line
			(start 1.778 0.6858)
			(end 1.778 -0.6858)
			(stroke
				(width 0.1524)
				(type default)
			)
			(layer "F.SilkS")
		)
		(fp_line
			(start 1.651 -0.6858)
			(end 1.651 0.6858)
			(stroke
				(width 0.1524)
				(type default)
			)
			(layer "F.SilkS")
		)
		(fp_line
			(start 0.299974 -0.500126)
			(end 0.299974 0.500126)
			(stroke
				(width 0.1524)
				(type default)
			)
			(layer "F.SilkS")
		)
		(fp_line
			(start 0.199898 0)
			(end -0.299974 -0.500126)
			(stroke
				(width 0.1524)
				(type default)
			)
			(layer "F.SilkS")
		)
		(fp_line
			(start -0.299974 0.500126)
			(end 0.199898 0)
			(stroke
				(width 0.1524)
				(type default)
			)
			(layer "F.SilkS")
		)
		(fp_line
			(start -0.299974 -0.500126)
			(end -0.299974 0.500126)
			(stroke
				(width 0.1524)
				(type default)
			)
			(layer "F.SilkS")
		)
		(fp_line
			(start -1.651 0.7112)
			(end -1.651 -0.7112)
			(stroke
				(width 0.1524)
				(type default)
			)
			(layer "F.SilkS")
		)
		(fp_line
			(start -1.651 -0.7112)
			(end 2.032 -0.7112)
			(stroke
				(width 0.1524)
				(type default)
			)
			(layer "F.SilkS")
		)
		(fp_line
			(start 1.35001 0.175006)
			(end 0.899922 0.175006)
			(stroke
				(width 0.1)
				(type default)
			)
			(layer "F.Fab")
		)
		(fp_line
			(start 1.35001 -0.225044)
			(end 1.35001 0.175006)
			(stroke
				(width 0.1)
				(type default)
			)
			(layer "F.Fab")
		)
		(fp_line
			(start 0.899922 0.700024)
			(end -0.899922 0.700024)
			(stroke
				(width 0.1)
				(type default)
			)
			(layer "F.Fab")
		)
		(fp_line
			(start 0.899922 0.175006)
			(end 0.899922 0.700024)
			(stroke
				(width 0.1)
				(type default)
			)
			(layer "F.Fab")
		)
		(fp_line
			(start 0.899922 -0.225044)
			(end 1.35001 -0.225044)
			(stroke
				(width 0.1)
				(type default)
			)
			(layer "F.Fab")
		)
		(fp_line
			(start 0.899922 -0.700024)
			(end 0.899922 -0.225044)
			(stroke
				(width 0.1)
				(type default)
			)
			(layer "F.Fab")
		)
		(fp_line
			(start 0.299974 -0.500126)
			(end 0.299974 0.500126)
			(stroke
				(width 0.1)
				(type default)
			)
			(layer "F.Fab")
		)
		(fp_line
			(start 0.199898 0)
			(end -0.299974 -0.500126)
			(stroke
				(width 0.1)
				(type default)
			)
			(layer "F.Fab")
		)
		(fp_line
			(start -0.299974 0.500126)
			(end 0.199898 0)
			(stroke
				(width 0.1)
				(type default)
			)
			(layer "F.Fab")
		)
		(fp_line
			(start -0.299974 -0.500126)
			(end -0.299974 0.500126)
			(stroke
				(width 0.1)
				(type default)
			)
			(layer "F.Fab")
		)
		(fp_line
			(start -0.899922 0.700024)
			(end -0.899922 0.175006)
			(stroke
				(width 0.1)
				(type default)
			)
			(layer "F.Fab")
		)
		(fp_line
			(start -0.899922 0.175006)
			(end -1.35001 0.175006)
			(stroke
				(width 0.1)
				(type default)
			)
			(layer "F.Fab")
		)
		(fp_line
			(start -0.899922 -0.225044)
			(end -0.899922 -0.700024)
			(stroke
				(width 0.1)
				(type default)
			)
			(layer "F.Fab")
		)
		(fp_line
			(start -0.899922 -0.700024)
			(end 0.899922 -0.700024)
			(stroke
				(width 0.1)
				(type default)
			)
			(layer "F.Fab")
		)
		(fp_line
			(start -1.35001 0.175006)
			(end -1.35001 -0.225044)
			(stroke
				(width 0.1)
				(type default)
			)
			(layer "F.Fab")
		)
		(fp_line
			(start -1.35001 -0.225044)
			(end -0.899922 -0.225044)
			(stroke
				(width 0.1)
				(type default)
			)
			(layer "F.Fab")
		)
		(fp_text user "-"
			(at 1.915922 0.452882 180)
			(unlocked yes)
			(layer "F.SilkS")
			(effects
				(font
					(size 1.905 1.4224)
					(thickness 0.1524)
				)
				(justify left)
			)
		)
		(fp_text user "+"
			(at -2.783078 0.833882 180)
			(unlocked yes)
			(layer "F.SilkS")
			(effects
				(font
					(size 1.905 1.4224)
					(thickness 0.1524)
				)
				(justify left)
			)
		)
		(fp_text user "-"
			(at 1.8288 -0.24765 180)
			(unlocked yes)
			(layer "F.Fab")
			(effects
				(font
					(size 1.905 1.4224)
					(thickness 0.1524)
				)
				(justify left)
			)
		)
		(fp_text user "+"
			(at -2.794 -0.19685 180)
			(unlocked yes)
			(layer "F.Fab")
			(effects
				(font
					(size 1.905 1.4224)
					(thickness 0.1524)
				)
				(justify left)
			)
		)
		(pad "1" smd rect
			(at -1.0922 0)
			(size 0.8128 0.8636)
			(layers "F.Cu" "F.Mask" "F.Paste")
			(net "FAN_4_TACH_IL_R")
		)
		(pad "2" smd rect
			(at 1.0922 0 180)
			(size 0.8128 0.8636)
			(layers "F.Cu" "F.Mask" "F.Paste")
			(net "FAN_4_TACH_IL_D")
		)
	)
	(footprint ""
		(layer "F.Cu")
		(at 19.177 -105.41 180)
		(property "Reference" "R5312"
			(at 0 0 180)
			(layer "F.SilkS")
			(hide yes)
			(effects
				(font
					(size 1.27 1.27)
				)
			)
		)
		(property "Value" ""
			(at 0 0 180)
			(layer "F.Fab")
			(effects
				(font
					(size 1.27 1.27)
				)
			)
		)
		(duplicate_pad_numbers_are_jumpers no)
		(fp_line
			(start 1.2954 0.5842)
			(end -1.2954 0.5842)
			(stroke
				(width 0.1524)
				(type default)
			)
			(layer "F.SilkS")
		)
		(fp_line
			(start 1.2954 -0.5842)
			(end 1.2954 0.5842)
			(stroke
				(width 0.1524)
				(type default)
			)
			(layer "F.SilkS")
		)
		(fp_line
			(start -1.2954 0.5842)
			(end -1.2954 -0.5842)
			(stroke
				(width 0.1524)
				(type default)
			)
			(layer "F.SilkS")
		)
		(fp_line
			(start -1.2954 -0.5842)
			(end 1.2954 -0.5842)
			(stroke
				(width 0.1524)
				(type default)
			)
			(layer "F.SilkS")
		)
		(fp_line
			(start 1.1938 0.4064)
			(end 0.8636 0.4064)
			(stroke
				(width 0.1)
				(type default)
			)
			(layer "F.Fab")
		)
		(fp_line
			(start 1.1938 -0.406654)
			(end 1.1938 0.4064)
			(stroke
				(width 0.1)
				(type default)
			)
			(layer "F.Fab")
		)
		(fp_line
			(start 0.8636 0.4572)
			(end -0.8636 0.4572)
			(stroke
				(width 0.1)
				(type default)
			)
			(layer "F.Fab")
		)
		(fp_line
			(start 0.8636 0.4064)
			(end 0.8636 0.4572)
			(stroke
				(width 0.1)
				(type default)
			)
			(layer "F.Fab")
		)
		(fp_line
			(start 0.8636 -0.406654)
			(end 1.1938 -0.406654)
			(stroke
				(width 0.1)
				(type default)
			)
			(layer "F.Fab")
		)
		(fp_line
			(start 0.8636 -0.4572)
			(end 0.8636 -0.406654)
			(stroke
				(width 0.1)
				(type default)
			)
			(layer "F.Fab")
		)
		(fp_line
			(start -0.8636 0.4572)
			(end -0.8636 0.4318)
			(stroke
				(width 0.1)
				(type default)
			)
			(layer "F.Fab")
		)
		(fp_line
			(start -0.8636 0.4318)
			(end -0.8636 0.4064)
			(stroke
				(width 0.1)
				(type default)
			)
			(layer "F.Fab")
		)
		(fp_line
			(start -0.8636 0.4064)
			(end -1.1938 0.4064)
			(stroke
				(width 0.1)
				(type default)
			)
			(layer "F.Fab")
		)
		(fp_line
			(start -0.8636 -0.406654)
			(end -0.8636 -0.4572)
			(stroke
				(width 0.1)
				(type default)
			)
			(layer "F.Fab")
		)
		(fp_line
			(start -0.8636 -0.4572)
			(end 0.8636 -0.4572)
			(stroke
				(width 0.1)
				(type default)
			)
			(layer "F.Fab")
		)
		(fp_line
			(start -1.1938 0.4064)
			(end -1.1938 -0.406654)
			(stroke
				(width 0.1)
				(type default)
			)
			(layer "F.Fab")
		)
		(fp_line
			(start -1.1938 -0.406654)
			(end -0.8636 -0.406654)
			(stroke
				(width 0.1)
				(type default)
			)
			(layer "F.Fab")
		)
		(pad "1" smd rect
			(at -0.7366 0 90)
			(size 0.7112 0.8128)
			(layers "F.Cu" "F.Mask" "F.Paste")
			(net "P52V_FAN_5")
		)
		(pad "2" smd rect
			(at 0.7366 0 90)
			(size 0.7112 0.8128)
			(layers "F.Cu" "F.Mask" "F.Paste")
			(net "FAN_5_TACH_IL_R")
		)
	)
	(footprint ""
		(layer "F.Cu")
		(at 4.7244 -219.329 90)
		(property "Reference" "C2038"
			(at 0 0 90)
			(layer "F.SilkS")
			(hide yes)
			(effects
				(font
					(size 1.27 1.27)
				)
			)
		)
		(property "Value" ""
			(at 0 0 90)
			(layer "F.Fab")
			(effects
				(font
					(size 1.27 1.27)
				)
			)
		)
		(duplicate_pad_numbers_are_jumpers no)
		(fp_line
			(start 1.524 -0.762)
			(end 1.524 0.762)
			(stroke
				(width 0.1524)
				(type default)
			)
			(layer "F.SilkS")
		)
		(fp_line
			(start -1.524 -0.762)
			(end 1.524 -0.762)
			(stroke
				(width 0.1524)
				(type default)
			)
			(layer "F.SilkS")
		)
		(fp_line
			(start 1.524 0.762)
			(end -1.524 0.762)
			(stroke
				(width 0.1524)
				(type default)
			)
			(layer "F.SilkS")
		)
		(fp_line
			(start -1.524 0.762)
			(end -1.524 -0.762)
			(stroke
				(width 0.1524)
				(type default)
			)
			(layer "F.SilkS")
		)
		(fp_line
			(start 1.1049 -0.724916)
			(end -1.1049 -0.724916)
			(stroke
				(width 0.1)
				(type default)
			)
			(layer "F.Fab")
		)
		(fp_line
			(start -1.1049 -0.724916)
			(end -1.1049 0.724916)
			(stroke
				(width 0.1)
				(type default)
			)
			(layer "F.Fab")
		)
		(fp_line
			(start 1.1049 0.724916)
			(end 1.1049 -0.724916)
			(stroke
				(width 0.1)
				(type default)
			)
			(layer "F.Fab")
		)
		(fp_line
			(start -1.1049 0.724916)
			(end 1.1049 0.724916)
			(stroke
				(width 0.1)
				(type default)
			)
			(layer "F.Fab")
		)
		(pad "1" smd rect
			(at -0.889 0 270)
			(size 1.016 1.27)
			(layers "F.Cu" "F.Mask" "F.Paste")
			(net "P12V_LED_FAN6")
		)
		(pad "2" smd rect
			(at 0.889 0 270)
			(size 1.016 1.27)
			(layers "F.Cu" "F.Mask" "F.Paste")
			(net "GND")
		)
	)
	(footprint ""
		(layer "F.Cu")
		(at 13.335 -164.338 180)
		(property "Reference" "R5508"
			(at 0 0 180)
			(layer "F.SilkS")
			(hide yes)
			(effects
				(font
					(size 1.27 1.27)
				)
			)
		)
		(property "Value" ""
			(at 0 0 180)
			(layer "F.Fab")
			(effects
				(font
					(size 1.27 1.27)
				)
			)
		)
		(duplicate_pad_numbers_are_jumpers no)
		(fp_line
			(start 0.7874 0.4064)
			(end -0.7874 0.4064)
			(stroke
				(width 0.1524)
				(type default)
			)
			(layer "F.SilkS")
		)
		(fp_line
			(start 0.7874 -0.4064)
			(end 0.7874 0.4064)
			(stroke
				(width 0.1524)
				(type default)
			)
			(layer "F.SilkS")
		)
		(fp_line
			(start -0.7874 0.4064)
			(end -0.7874 -0.4064)
			(stroke
				(width 0.1524)
				(type default)
			)
			(layer "F.SilkS")
		)
		(fp_line
			(start -0.7874 -0.4064)
			(end 0.7874 -0.4064)
			(stroke
				(width 0.1524)
				(type default)
			)
			(layer "F.SilkS")
		)
		(fp_line
			(start 0.67945 0.3048)
			(end 0.120396 0.3048)
			(stroke
				(width 0.1)
				(type default)
			)
			(layer "F.Fab")
		)
		(fp_line
			(start 0.67945 -0.3048)
			(end 0.67945 0.3048)
			(stroke
				(width 0.1)
				(type default)
			)
			(layer "F.Fab")
		)
		(fp_line
			(start 0.12065 -0.2794)
			(end 0.12065 -0.3048)
			(stroke
				(width 0.1)
				(type default)
			)
			(layer "F.Fab")
		)
		(fp_line
			(start 0.12065 -0.3048)
			(end 0.67945 -0.3048)
			(stroke
				(width 0.1)
				(type default)
			)
			(layer "F.Fab")
		)
		(fp_line
			(start 0.120396 0.3048)
			(end 0.120396 0.2794)
			(stroke
				(width 0.1)
				(type default)
			)
			(layer "F.Fab")
		)
		(fp_line
			(start 0.120396 0.2794)
			(end -0.12065 0.2794)
			(stroke
				(width 0.1)
				(type default)
			)
			(layer "F.Fab")
		)
		(fp_line
			(start -0.12065 0.3048)
			(end -0.67945 0.3048)
			(stroke
				(width 0.1)
				(type default)
			)
			(layer "F.Fab")
		)
		(fp_line
			(start -0.12065 0.2794)
			(end -0.12065 0.3048)
			(stroke
				(width 0.1)
				(type default)
			)
			(layer "F.Fab")
		)
		(fp_line
			(start -0.12065 -0.2794)
			(end 0.12065 -0.2794)
			(stroke
				(width 0.1)
				(type default)
			)
			(layer "F.Fab")
		)
		(fp_line
			(start -0.12065 -0.305054)
			(end -0.12065 -0.2794)
			(stroke
				(width 0.1)
				(type default)
			)
			(layer "F.Fab")
		)
		(fp_line
			(start -0.67945 0.3048)
			(end -0.67945 -0.305054)
			(stroke
				(width 0.1)
				(type default)
			)
			(layer "F.Fab")
		)
		(fp_line
			(start -0.67945 -0.305054)
			(end -0.12065 -0.305054)
			(stroke
				(width 0.1)
				(type default)
			)
			(layer "F.Fab")
		)
		(pad "1" smd circle
			(at -0.40005 0 180)
			(size 0 0)
			(layers "F.Cu" "F.Mask" "F.Paste")
			(net "P3V3_AUX")
		)
		(pad "2" smd circle
			(at 0.40005 0 180)
			(size 0 0)
			(layers "F.Cu" "F.Mask" "F.Paste")
			(net "FAN_1_PRESENT_N")
		)
	)
	(footprint ""
		(layer "F.Cu")
		(at 6.477 -169.291)
		(property "Reference" "R4852"
			(at 0 0 0)
			(layer "F.SilkS")
			(hide yes)
			(effects
				(font
					(size 1.27 1.27)
				)
			)
		)
		(property "Value" ""
			(at 0 0 0)
			(layer "F.Fab")
			(effects
				(font
					(size 1.27 1.27)
				)
			)
		)
		(duplicate_pad_numbers_are_jumpers no)
		(fp_line
			(start -0.7874 -0.4064)
			(end 0.7874 -0.4064)
			(stroke
				(width 0.1524)
				(type default)
			)
			(layer "F.SilkS")
		)
		(fp_line
			(start -0.7874 0.4064)
			(end -0.7874 -0.4064)
			(stroke
				(width 0.1524)
				(type default)
			)
			(layer "F.SilkS")
		)
		(fp_line
			(start 0.7874 -0.4064)
			(end 0.7874 0.4064)
			(stroke
				(width 0.1524)
				(type default)
			)
			(layer "F.SilkS")
		)
		(fp_line
			(start 0.7874 0.4064)
			(end -0.7874 0.4064)
			(stroke
				(width 0.1524)
				(type default)
			)
			(layer "F.SilkS")
		)
		(fp_line
			(start -0.67945 -0.305054)
			(end -0.12065 -0.305054)
			(stroke
				(width 0.1)
				(type default)
			)
			(layer "F.Fab")
		)
		(fp_line
			(start -0.67945 0.3048)
			(end -0.67945 -0.305054)
			(stroke
				(width 0.1)
				(type default)
			)
			(layer "F.Fab")
		)
		(fp_line
			(start -0.12065 -0.305054)
			(end -0.12065 -0.2794)
			(stroke
				(width 0.1)
				(type default)
			)
			(layer "F.Fab")
		)
		(fp_line
			(start -0.12065 -0.2794)
			(end 0.12065 -0.2794)
			(stroke
				(width 0.1)
				(type default)
			)
			(layer "F.Fab")
		)
		(fp_line
			(start -0.12065 0.2794)
			(end -0.12065 0.3048)
			(stroke
				(width 0.1)
				(type default)
			)
			(layer "F.Fab")
		)
		(fp_line
			(start -0.12065 0.3048)
			(end -0.67945 0.3048)
			(stroke
				(width 0.1)
				(type default)
			)
			(layer "F.Fab")
		)
		(fp_line
			(start 0.120396 0.2794)
			(end -0.12065 0.2794)
			(stroke
				(width 0.1)
				(type default)
			)
			(layer "F.Fab")
		)
		(fp_line
			(start 0.120396 0.3048)
			(end 0.120396 0.2794)
			(stroke
				(width 0.1)
				(type default)
			)
			(layer "F.Fab")
		)
		(fp_line
			(start 0.12065 -0.3048)
			(end 0.67945 -0.3048)
			(stroke
				(width 0.1)
				(type default)
			)
			(layer "F.Fab")
		)
		(fp_line
			(start 0.12065 -0.2794)
			(end 0.12065 -0.3048)
			(stroke
				(width 0.1)
				(type default)
			)
			(layer "F.Fab")
		)
		(fp_line
			(start 0.67945 -0.3048)
			(end 0.67945 0.3048)
			(stroke
				(width 0.1)
				(type default)
			)
			(layer "F.Fab")
		)
		(fp_line
			(start 0.67945 0.3048)
			(end 0.120396 0.3048)
			(stroke
				(width 0.1)
				(type default)
			)
			(layer "F.Fab")
		)
		(pad "1" smd circle
			(at -0.40005 0)
			(size 0 0)
			(layers "F.Cu" "F.Mask" "F.Paste")
			(net "P3V3_AUX")
		)
		(pad "2" smd circle
			(at 0.40005 0)
			(size 0 0)
			(layers "F.Cu" "F.Mask" "F.Paste")
			(net "FAN_4_PRSNT_BUF_R_N")
		)
	)
	(footprint ""
		(layer "F.Cu")
		(at 37.338 -205.895956)
		(property "Reference" "R5202"
			(at 0 0 0)
			(layer "F.SilkS")
			(hide yes)
			(effects
				(font
					(size 1.27 1.27)
				)
			)
		)
		(property "Value" ""
			(at 0 0 0)
			(layer "F.Fab")
			(effects
				(font
					(size 1.27 1.27)
				)
			)
		)
		(duplicate_pad_numbers_are_jumpers no)
		(fp_line
			(start -0.7874 -0.4064)
			(end 0.7874 -0.4064)
			(stroke
				(width 0.1524)
				(type default)
			)
			(layer "F.SilkS")
		)
		(fp_line
			(start -0.7874 0.4064)
			(end -0.7874 -0.4064)
			(stroke
				(width 0.1524)
				(type default)
			)
			(layer "F.SilkS")
		)
		(fp_line
			(start 0.7874 -0.4064)
			(end 0.7874 0.4064)
			(stroke
				(width 0.1524)
				(type default)
			)
			(layer "F.SilkS")
		)
		(fp_line
			(start 0.7874 0.4064)
			(end -0.7874 0.4064)
			(stroke
				(width 0.1524)
				(type default)
			)
			(layer "F.SilkS")
		)
		(fp_line
			(start -0.67945 -0.305054)
			(end -0.12065 -0.305054)
			(stroke
				(width 0.1)
				(type default)
			)
			(layer "F.Fab")
		)
		(fp_line
			(start -0.67945 0.3048)
			(end -0.67945 -0.305054)
			(stroke
				(width 0.1)
				(type default)
			)
			(layer "F.Fab")
		)
		(fp_line
			(start -0.12065 -0.305054)
			(end -0.12065 -0.2794)
			(stroke
				(width 0.1)
				(type default)
			)
			(layer "F.Fab")
		)
		(fp_line
			(start -0.12065 -0.2794)
			(end 0.12065 -0.2794)
			(stroke
				(width 0.1)
				(type default)
			)
			(layer "F.Fab")
		)
		(fp_line
			(start -0.12065 0.2794)
			(end -0.12065 0.3048)
			(stroke
				(width 0.1)
				(type default)
			)
			(layer "F.Fab")
		)
		(fp_line
			(start -0.12065 0.3048)
			(end -0.67945 0.3048)
			(stroke
				(width 0.1)
				(type default)
			)
			(layer "F.Fab")
		)
		(fp_line
			(start 0.120396 0.2794)
			(end -0.12065 0.2794)
			(stroke
				(width 0.1)
				(type default)
			)
			(layer "F.Fab")
		)
		(fp_line
			(start 0.120396 0.3048)
			(end 0.120396 0.2794)
			(stroke
				(width 0.1)
				(type default)
			)
			(layer "F.Fab")
		)
		(fp_line
			(start 0.12065 -0.3048)
			(end 0.67945 -0.3048)
			(stroke
				(width 0.1)
				(type default)
			)
			(layer "F.Fab")
		)
		(fp_line
			(start 0.12065 -0.2794)
			(end 0.12065 -0.3048)
			(stroke
				(width 0.1)
				(type default)
			)
			(layer "F.Fab")
		)
		(fp_line
			(start 0.67945 -0.3048)
			(end 0.67945 0.3048)
			(stroke
				(width 0.1)
				(type default)
			)
			(layer "F.Fab")
		)
		(fp_line
			(start 0.67945 0.3048)
			(end 0.120396 0.3048)
			(stroke
				(width 0.1)
				(type default)
			)
			(layer "F.Fab")
		)
		(pad "1" smd circle
			(at -0.40005 0)
			(size 0 0)
			(layers "F.Cu" "F.Mask" "F.Paste")
			(net "SMB_FAN1_SCL")
		)
		(pad "2" smd circle
			(at 0.40005 0)
			(size 0 0)
			(layers "F.Cu" "F.Mask" "F.Paste")
			(net "SMB_FAN1_SCL_R")
		)
	)
	(footprint ""
		(layer "F.Cu")
		(at 7.112 -65.913)
		(property "Reference" "PR47"
			(at 0 0 0)
			(layer "F.SilkS")
			(hide yes)
			(effects
				(font
					(size 1.27 1.27)
				)
			)
		)
		(property "Value" ""
			(at 0 0 0)
			(layer "F.Fab")
			(effects
				(font
					(size 1.27 1.27)
				)
			)
		)
		(duplicate_pad_numbers_are_jumpers no)
		(fp_line
			(start -0.7874 -0.4064)
			(end 0.7874 -0.4064)
			(stroke
				(width 0.1524)
				(type default)
			)
			(layer "F.SilkS")
		)
		(fp_line
			(start -0.7874 0.4064)
			(end -0.7874 -0.4064)
			(stroke
				(width 0.1524)
				(type default)
			)
			(layer "F.SilkS")
		)
		(fp_line
			(start 0.7874 -0.4064)
			(end 0.7874 0.4064)
			(stroke
				(width 0.1524)
				(type default)
			)
			(layer "F.SilkS")
		)
		(fp_line
			(start 0.7874 0.4064)
			(end -0.7874 0.4064)
			(stroke
				(width 0.1524)
				(type default)
			)
			(layer "F.SilkS")
		)
		(fp_line
			(start -0.67945 -0.305054)
			(end -0.12065 -0.305054)
			(stroke
				(width 0.1)
				(type default)
			)
			(layer "F.Fab")
		)
		(fp_line
			(start -0.67945 0.3048)
			(end -0.67945 -0.305054)
			(stroke
				(width 0.1)
				(type default)
			)
			(layer "F.Fab")
		)
		(fp_line
			(start -0.12065 -0.305054)
			(end -0.12065 -0.2794)
			(stroke
				(width 0.1)
				(type default)
			)
			(layer "F.Fab")
		)
		(fp_line
			(start -0.12065 -0.2794)
			(end 0.12065 -0.2794)
			(stroke
				(width 0.1)
				(type default)
			)
			(layer "F.Fab")
		)
		(fp_line
			(start -0.12065 0.2794)
			(end -0.12065 0.3048)
			(stroke
				(width 0.1)
				(type default)
			)
			(layer "F.Fab")
		)
		(fp_line
			(start -0.12065 0.3048)
			(end -0.67945 0.3048)
			(stroke
				(width 0.1)
				(type default)
			)
			(layer "F.Fab")
		)
		(fp_line
			(start 0.120396 0.2794)
			(end -0.12065 0.2794)
			(stroke
				(width 0.1)
				(type default)
			)
			(layer "F.Fab")
		)
		(fp_line
			(start 0.120396 0.3048)
			(end 0.120396 0.2794)
			(stroke
				(width 0.1)
				(type default)
			)
			(layer "F.Fab")
		)
		(fp_line
			(start 0.12065 -0.3048)
			(end 0.67945 -0.3048)
			(stroke
				(width 0.1)
				(type default)
			)
			(layer "F.Fab")
		)
		(fp_line
			(start 0.12065 -0.2794)
			(end 0.12065 -0.3048)
			(stroke
				(width 0.1)
				(type default)
			)
			(layer "F.Fab")
		)
		(fp_line
			(start 0.67945 -0.3048)
			(end 0.67945 0.3048)
			(stroke
				(width 0.1)
				(type default)
			)
			(layer "F.Fab")
		)
		(fp_line
			(start 0.67945 0.3048)
			(end 0.120396 0.3048)
			(stroke
				(width 0.1)
				(type default)
			)
			(layer "F.Fab")
		)
		(pad "1" smd circle
			(at -0.40005 0)
			(size 0 0)
			(layers "F.Cu" "F.Mask" "F.Paste")
			(net "FAN_4_FAULT_R")
		)
		(pad "2" smd circle
			(at 0.40005 0)
			(size 0 0)
			(layers "F.Cu" "F.Mask" "F.Paste")
			(net "FAN_4_P3V_R")
		)
	)
	(footprint ""
		(layer "F.Cu")
		(at 5.969 -250.317)
		(property "Reference" "PR63"
			(at 0 0 0)
			(layer "F.SilkS")
			(hide yes)
			(effects
				(font
					(size 1.27 1.27)
				)
			)
		)
		(property "Value" ""
			(at 0 0 0)
			(layer "F.Fab")
			(effects
				(font
					(size 1.27 1.27)
				)
			)
		)
		(duplicate_pad_numbers_are_jumpers no)
		(fp_line
			(start -0.7874 -0.4064)
			(end 0.7874 -0.4064)
			(stroke
				(width 0.1524)
				(type default)
			)
			(layer "F.SilkS")
		)
		(fp_line
			(start -0.7874 0.4064)
			(end -0.7874 -0.4064)
			(stroke
				(width 0.1524)
				(type default)
			)
			(layer "F.SilkS")
		)
		(fp_line
			(start 0.7874 -0.4064)
			(end 0.7874 0.4064)
			(stroke
				(width 0.1524)
				(type default)
			)
			(layer "F.SilkS")
		)
		(fp_line
			(start 0.7874 0.4064)
			(end -0.7874 0.4064)
			(stroke
				(width 0.1524)
				(type default)
			)
			(layer "F.SilkS")
		)
		(fp_line
			(start -0.67945 -0.305054)
			(end -0.12065 -0.305054)
			(stroke
				(width 0.1)
				(type default)
			)
			(layer "F.Fab")
		)
		(fp_line
			(start -0.67945 0.3048)
			(end -0.67945 -0.305054)
			(stroke
				(width 0.1)
				(type default)
			)
			(layer "F.Fab")
		)
		(fp_line
			(start -0.12065 -0.305054)
			(end -0.12065 -0.2794)
			(stroke
				(width 0.1)
				(type default)
			)
			(layer "F.Fab")
		)
		(fp_line
			(start -0.12065 -0.2794)
			(end 0.12065 -0.2794)
			(stroke
				(width 0.1)
				(type default)
			)
			(layer "F.Fab")
		)
		(fp_line
			(start -0.12065 0.2794)
			(end -0.12065 0.3048)
			(stroke
				(width 0.1)
				(type default)
			)
			(layer "F.Fab")
		)
		(fp_line
			(start -0.12065 0.3048)
			(end -0.67945 0.3048)
			(stroke
				(width 0.1)
				(type default)
			)
			(layer "F.Fab")
		)
		(fp_line
			(start 0.120396 0.2794)
			(end -0.12065 0.2794)
			(stroke
				(width 0.1)
				(type default)
			)
			(layer "F.Fab")
		)
		(fp_line
			(start 0.120396 0.3048)
			(end 0.120396 0.2794)
			(stroke
				(width 0.1)
				(type default)
			)
			(layer "F.Fab")
		)
		(fp_line
			(start 0.12065 -0.3048)
			(end 0.67945 -0.3048)
			(stroke
				(width 0.1)
				(type default)
			)
			(layer "F.Fab")
		)
		(fp_line
			(start 0.12065 -0.2794)
			(end 0.12065 -0.3048)
			(stroke
				(width 0.1)
				(type default)
			)
			(layer "F.Fab")
		)
		(fp_line
			(start 0.67945 -0.3048)
			(end 0.67945 0.3048)
			(stroke
				(width 0.1)
				(type default)
			)
			(layer "F.Fab")
		)
		(fp_line
			(start 0.67945 0.3048)
			(end 0.120396 0.3048)
			(stroke
				(width 0.1)
				(type default)
			)
			(layer "F.Fab")
		)
		(pad "1" smd circle
			(at -0.40005 0)
			(size 0 0)
			(layers "F.Cu" "F.Mask" "F.Paste")
			(net "FAN_6_FAULT_R")
		)
		(pad "2" smd circle
			(at 0.40005 0)
			(size 0 0)
			(layers "F.Cu" "F.Mask" "F.Paste")
			(net "FAN_6_P3V_R")
		)
	)
	(footprint ""
		(layer "F.Cu")
		(at 11.572494 -256.413)
		(property "Reference" "C2073"
			(at 0 0 0)
			(layer "F.SilkS")
			(hide yes)
			(effects
				(font
					(size 1.27 1.27)
				)
			)
		)
		(property "Value" ""
			(at 0 0 0)
			(layer "F.Fab")
			(effects
				(font
					(size 1.27 1.27)
				)
			)
		)
		(duplicate_pad_numbers_are_jumpers no)
		(fp_line
			(start -0.7874 -0.4064)
			(end 0.7874 -0.4064)
			(stroke
				(width 0.1524)
				(type default)
			)
			(layer "F.SilkS")
		)
		(fp_line
			(start -0.7874 0.4064)
			(end -0.7874 -0.4064)
			(stroke
				(width 0.1524)
				(type default)
			)
			(layer "F.SilkS")
		)
		(fp_line
			(start 0.7874 -0.4064)
			(end 0.7874 0.4064)
			(stroke
				(width 0.1524)
				(type default)
			)
			(layer "F.SilkS")
		)
		(fp_line
			(start 0.7874 0.4064)
			(end -0.7874 0.4064)
			(stroke
				(width 0.1524)
				(type default)
			)
			(layer "F.SilkS")
		)
		(fp_line
			(start -0.67945 -0.305054)
			(end -0.12065 -0.305054)
			(stroke
				(width 0.1)
				(type default)
			)
			(layer "F.Fab")
		)
		(fp_line
			(start -0.67945 0.3048)
			(end -0.67945 -0.305054)
			(stroke
				(width 0.1)
				(type default)
			)
			(layer "F.Fab")
		)
		(fp_line
			(start -0.12065 -0.305054)
			(end -0.12065 -0.2794)
			(stroke
				(width 0.1)
				(type default)
			)
			(layer "F.Fab")
		)
		(fp_line
			(start -0.12065 -0.2794)
			(end 0.12065 -0.2794)
			(stroke
				(width 0.1)
				(type default)
			)
			(layer "F.Fab")
		)
		(fp_line
			(start -0.12065 0.2794)
			(end -0.12065 0.3048)
			(stroke
				(width 0.1)
				(type default)
			)
			(layer "F.Fab")
		)
		(fp_line
			(start -0.12065 0.3048)
			(end -0.67945 0.3048)
			(stroke
				(width 0.1)
				(type default)
			)
			(layer "F.Fab")
		)
		(fp_line
			(start 0.120396 0.2794)
			(end -0.12065 0.2794)
			(stroke
				(width 0.1)
				(type default)
			)
			(layer "F.Fab")
		)
		(fp_line
			(start 0.120396 0.3048)
			(end 0.120396 0.2794)
			(stroke
				(width 0.1)
				(type default)
			)
			(layer "F.Fab")
		)
		(fp_line
			(start 0.12065 -0.3048)
			(end 0.67945 -0.3048)
			(stroke
				(width 0.1)
				(type default)
			)
			(layer "F.Fab")
		)
		(fp_line
			(start 0.12065 -0.2794)
			(end 0.12065 -0.3048)
			(stroke
				(width 0.1)
				(type default)
			)
			(layer "F.Fab")
		)
		(fp_line
			(start 0.67945 -0.3048)
			(end 0.67945 0.3048)
			(stroke
				(width 0.1)
				(type default)
			)
			(layer "F.Fab")
		)
		(fp_line
			(start 0.67945 0.3048)
			(end 0.120396 0.3048)
			(stroke
				(width 0.1)
				(type default)
			)
			(layer "F.Fab")
		)
		(pad "1" smd circle
			(at -0.40005 0)
			(size 0 0)
			(layers "F.Cu" "F.Mask" "F.Paste")
			(net "P3V3_AUX")
		)
		(pad "2" smd circle
			(at 0.40005 0)
			(size 0 0)
			(layers "F.Cu" "F.Mask" "F.Paste")
			(net "GND")
		)
	)
	(footprint ""
		(layer "F.Cu")
		(at 15.113 -114.427 -90)
		(property "Reference" "R5364"
			(at 0 0 270)
			(layer "F.SilkS")
			(hide yes)
			(effects
				(font
					(size 1.27 1.27)
				)
			)
		)
		(property "Value" ""
			(at 0 0 270)
			(layer "F.Fab")
			(effects
				(font
					(size 1.27 1.27)
				)
			)
		)
		(duplicate_pad_numbers_are_jumpers no)
		(fp_line
			(start -0.7874 0.4064)
			(end -0.7874 -0.4064)
			(stroke
				(width 0.1524)
				(type default)
			)
			(layer "F.SilkS")
		)
		(fp_line
			(start 0.7874 0.4064)
			(end -0.7874 0.4064)
			(stroke
				(width 0.1524)
				(type default)
			)
			(layer "F.SilkS")
		)
		(fp_line
			(start -0.7874 -0.4064)
			(end 0.7874 -0.4064)
			(stroke
				(width 0.1524)
				(type default)
			)
			(layer "F.SilkS")
		)
		(fp_line
			(start 0.7874 -0.4064)
			(end 0.7874 0.4064)
			(stroke
				(width 0.1524)
				(type default)
			)
			(layer "F.SilkS")
		)
		(fp_line
			(start -0.67945 0.3048)
			(end -0.67945 -0.305054)
			(stroke
				(width 0.1)
				(type default)
			)
			(layer "F.Fab")
		)
		(fp_line
			(start -0.12065 0.3048)
			(end -0.67945 0.3048)
			(stroke
				(width 0.1)
				(type default)
			)
			(layer "F.Fab")
		)
		(fp_line
			(start 0.120396 0.3048)
			(end 0.120396 0.2794)
			(stroke
				(width 0.1)
				(type default)
			)
			(layer "F.Fab")
		)
		(fp_line
			(start 0.67945 0.3048)
			(end 0.120396 0.3048)
			(stroke
				(width 0.1)
				(type default)
			)
			(layer "F.Fab")
		)
		(fp_line
			(start -0.12065 0.2794)
			(end -0.12065 0.3048)
			(stroke
				(width 0.1)
				(type default)
			)
			(layer "F.Fab")
		)
		(fp_line
			(start 0.120396 0.2794)
			(end -0.12065 0.2794)
			(stroke
				(width 0.1)
				(type default)
			)
			(layer "F.Fab")
		)
		(fp_line
			(start -0.12065 -0.2794)
			(end 0.12065 -0.2794)
			(stroke
				(width 0.1)
				(type default)
			)
			(layer "F.Fab")
		)
		(fp_line
			(start 0.12065 -0.2794)
			(end 0.12065 -0.3048)
			(stroke
				(width 0.1)
				(type default)
			)
			(layer "F.Fab")
		)
		(fp_line
			(start 0.12065 -0.3048)
			(end 0.67945 -0.3048)
			(stroke
				(width 0.1)
				(type default)
			)
			(layer "F.Fab")
		)
		(fp_line
			(start 0.67945 -0.3048)
			(end 0.67945 0.3048)
			(stroke
				(width 0.1)
				(type default)
			)
			(layer "F.Fab")
		)
		(fp_line
			(start -0.67945 -0.305054)
			(end -0.12065 -0.305054)
			(stroke
				(width 0.1)
				(type default)
			)
			(layer "F.Fab")
		)
		(fp_line
			(start -0.12065 -0.305054)
			(end -0.12065 -0.2794)
			(stroke
				(width 0.1)
				(type default)
			)
			(layer "F.Fab")
		)
		(pad "1" smd rect
			(at -0.40005 0 90)
			(size 0.4572 0.508)
			(layers "F.Cu" "F.Mask" "F.Paste")
			(net "FAN_5_OK_LED_R_N")
		)
		(pad "2" smd rect
			(at 0.40005 0 90)
			(size 0.4572 0.508)
			(layers "F.Cu" "F.Mask" "F.Paste")
			(net "FAN_5_OK_R_LED_N")
		)
	)
	(footprint ""
		(layer "F.Cu")
		(at 17.033494 -255.905 -90)
		(property "Reference" "C2072"
			(at 0 0 270)
			(layer "F.SilkS")
			(hide yes)
			(effects
				(font
					(size 1.27 1.27)
				)
			)
		)
		(property "Value" ""
			(at 0 0 270)
			(layer "F.Fab")
			(effects
				(font
					(size 1.27 1.27)
				)
			)
		)
		(duplicate_pad_numbers_are_jumpers no)
		(fp_line
			(start -0.7874 0.4064)
			(end -0.7874 -0.4064)
			(stroke
				(width 0.1524)
				(type default)
			)
			(layer "F.SilkS")
		)
		(fp_line
			(start 0.7874 0.4064)
			(end -0.7874 0.4064)
			(stroke
				(width 0.1524)
				(type default)
			)
			(layer "F.SilkS")
		)
		(fp_line
			(start -0.7874 -0.4064)
			(end 0.7874 -0.4064)
			(stroke
				(width 0.1524)
				(type default)
			)
			(layer "F.SilkS")
		)
		(fp_line
			(start 0.7874 -0.4064)
			(end 0.7874 0.4064)
			(stroke
				(width 0.1524)
				(type default)
			)
			(layer "F.SilkS")
		)
		(fp_line
			(start -0.67945 0.3048)
			(end -0.67945 -0.305054)
			(stroke
				(width 0.1)
				(type default)
			)
			(layer "F.Fab")
		)
		(fp_line
			(start -0.12065 0.3048)
			(end -0.67945 0.3048)
			(stroke
				(width 0.1)
				(type default)
			)
			(layer "F.Fab")
		)
		(fp_line
			(start 0.120396 0.3048)
			(end 0.120396 0.2794)
			(stroke
				(width 0.1)
				(type default)
			)
			(layer "F.Fab")
		)
		(fp_line
			(start 0.67945 0.3048)
			(end 0.120396 0.3048)
			(stroke
				(width 0.1)
				(type default)
			)
			(layer "F.Fab")
		)
		(fp_line
			(start -0.12065 0.2794)
			(end -0.12065 0.3048)
			(stroke
				(width 0.1)
				(type default)
			)
			(layer "F.Fab")
		)
		(fp_line
			(start 0.120396 0.2794)
			(end -0.12065 0.2794)
			(stroke
				(width 0.1)
				(type default)
			)
			(layer "F.Fab")
		)
		(fp_line
			(start -0.12065 -0.2794)
			(end 0.12065 -0.2794)
			(stroke
				(width 0.1)
				(type default)
			)
			(layer "F.Fab")
		)
		(fp_line
			(start 0.12065 -0.2794)
			(end 0.12065 -0.3048)
			(stroke
				(width 0.1)
				(type default)
			)
			(layer "F.Fab")
		)
		(fp_line
			(start 0.12065 -0.3048)
			(end 0.67945 -0.3048)
			(stroke
				(width 0.1)
				(type default)
			)
			(layer "F.Fab")
		)
		(fp_line
			(start 0.67945 -0.3048)
			(end 0.67945 0.3048)
			(stroke
				(width 0.1)
				(type default)
			)
			(layer "F.Fab")
		)
		(fp_line
			(start -0.67945 -0.305054)
			(end -0.12065 -0.305054)
			(stroke
				(width 0.1)
				(type default)
			)
			(layer "F.Fab")
		)
		(fp_line
			(start -0.12065 -0.305054)
			(end -0.12065 -0.2794)
			(stroke
				(width 0.1)
				(type default)
			)
			(layer "F.Fab")
		)
		(pad "1" smd circle
			(at -0.40005 0 270)
			(size 0 0)
			(layers "F.Cu" "F.Mask" "F.Paste")
			(net "P3V3_AUX")
		)
		(pad "2" smd circle
			(at 0.40005 0 270)
			(size 0 0)
			(layers "F.Cu" "F.Mask" "F.Paste")
			(net "GND")
		)
	)
	(footprint ""
		(layer "F.Cu")
		(at 22.479 -25.654 90)
		(property "Reference" "U66"
			(at -0.762 -1.75133 90)
			(unlocked yes)
			(layer "F.SilkS")
			(effects
				(font
					(size 0.7874 0.5842)
					(thickness 0.1524)
				)
				(justify left)
			)
		)
		(property "Value" ""
			(at 0 0 90)
			(layer "F.Fab")
			(effects
				(font
					(size 1.27 1.27)
				)
			)
		)
		(duplicate_pad_numbers_are_jumpers no)
		(fp_line
			(start 1.33096 -1.100074)
			(end 1.33096 1.100074)
			(stroke
				(width 0.1524)
				(type default)
			)
			(layer "F.SilkS")
		)
		(fp_line
			(start 0.381 -1.100074)
			(end 1.33096 -1.100074)
			(stroke
				(width 0.1524)
				(type default)
			)
			(layer "F.SilkS")
		)
		(fp_line
			(start -0.381 -1.100074)
			(end 0 -0.649986)
			(stroke
				(width 0.1524)
				(type default)
			)
			(layer "F.SilkS")
		)
		(fp_line
			(start -1.33096 -1.100074)
			(end -0.381 -1.100074)
			(stroke
				(width 0.1524)
				(type default)
			)
			(layer "F.SilkS")
		)
		(fp_line
			(start 0 -0.649986)
			(end 0.381 -1.100074)
			(stroke
				(width 0.1524)
				(type default)
			)
			(layer "F.SilkS")
		)
		(fp_line
			(start 1.33096 1.100074)
			(end -1.33096 1.100074)
			(stroke
				(width 0.1524)
				(type default)
			)
			(layer "F.SilkS")
		)
		(fp_line
			(start -1.33096 1.100074)
			(end -1.33096 -1.100074)
			(stroke
				(width 0.1524)
				(type default)
			)
			(layer "F.SilkS")
		)
		(fp_poly
			(pts
				(xy -1.884934 -1.383792) (xy -2.24409 -1.024636) (xy -1.525524 -0.665226)
			)
			(stroke
				(width 0)
				(type default)
			)
			(fill yes)
			(layer "F.SilkS")
		)
		(fp_line
			(start 0.674878 -1.100074)
			(end 0.674878 1.100074)
			(stroke
				(width 0.1)
				(type default)
			)
			(layer "F.Fab")
		)
		(fp_line
			(start -0.674878 -1.100074)
			(end 0.674878 -1.100074)
			(stroke
				(width 0.1)
				(type default)
			)
			(layer "F.Fab")
		)
		(fp_line
			(start 0.674878 1.100074)
			(end -0.674878 1.100074)
			(stroke
				(width 0.1)
				(type default)
			)
			(layer "F.Fab")
		)
		(fp_line
			(start -0.674878 1.100074)
			(end -0.674878 -1.100074)
			(stroke
				(width 0.1)
				(type default)
			)
			(layer "F.Fab")
		)
		(fp_poly
			(pts
				(xy -2.209292 -0.902462) (xy -2.209292 -0.394462) (xy -1.447292 -0.648462)
			)
			(stroke
				(width 0)
				(type default)
			)
			(fill yes)
			(layer "F.Fab")
		)
		(pad "1" smd rect
			(at -0.94996 -0.649986 180)
			(size 0.4064 0.508)
			(layers "F.Cu" "F.Mask" "F.Paste")
			(net "NC_U66_P1")
		)
		(pad "2" smd rect
			(at -0.94996 0 180)
			(size 0.4064 0.508)
			(layers "F.Cu" "F.Mask" "F.Paste")
			(net "FAN_3_PWM")
		)
		(pad "3" smd rect
			(at -0.94996 0.649986 180)
			(size 0.4064 0.508)
			(layers "F.Cu" "F.Mask" "F.Paste")
			(net "GND")
		)
		(pad "4" smd rect
			(at 0.94996 0.649986 180)
			(size 0.4064 0.508)
			(layers "F.Cu" "F.Mask" "F.Paste")
			(net "FAN_3_PWM_BUF")
		)
		(pad "5" smd rect
			(at 0.94996 -0.649986 180)
			(size 0.4064 0.508)
			(layers "F.Cu" "F.Mask" "F.Paste")
			(net "P3V3_AUX")
		)
	)
	(footprint ""
		(layer "F.Cu")
		(at 14.097 -98.552 90)
		(property "Reference" "R5667"
			(at 0 0 90)
			(layer "F.SilkS")
			(hide yes)
			(effects
				(font
					(size 1.27 1.27)
				)
			)
		)
		(property "Value" ""
			(at 0 0 90)
			(layer "F.Fab")
			(effects
				(font
					(size 1.27 1.27)
				)
			)
		)
		(duplicate_pad_numbers_are_jumpers no)
		(fp_line
			(start 0.7874 -0.4064)
			(end 0.7874 0.4064)
			(stroke
				(width 0.1524)
				(type default)
			)
			(layer "F.SilkS")
		)
		(fp_line
			(start -0.7874 -0.4064)
			(end 0.7874 -0.4064)
			(stroke
				(width 0.1524)
				(type default)
			)
			(layer "F.SilkS")
		)
		(fp_line
			(start 0.7874 0.4064)
			(end -0.7874 0.4064)
			(stroke
				(width 0.1524)
				(type default)
			)
			(layer "F.SilkS")
		)
		(fp_line
			(start -0.7874 0.4064)
			(end -0.7874 -0.4064)
			(stroke
				(width 0.1524)
				(type default)
			)
			(layer "F.SilkS")
		)
		(fp_line
			(start -0.12065 -0.305054)
			(end -0.12065 -0.2794)
			(stroke
				(width 0.1)
				(type default)
			)
			(layer "F.Fab")
		)
		(fp_line
			(start -0.67945 -0.305054)
			(end -0.12065 -0.305054)
			(stroke
				(width 0.1)
				(type default)
			)
			(layer "F.Fab")
		)
		(fp_line
			(start 0.67945 -0.3048)
			(end 0.67945 0.3048)
			(stroke
				(width 0.1)
				(type default)
			)
			(layer "F.Fab")
		)
		(fp_line
			(start 0.12065 -0.3048)
			(end 0.67945 -0.3048)
			(stroke
				(width 0.1)
				(type default)
			)
			(layer "F.Fab")
		)
		(fp_line
			(start 0.12065 -0.2794)
			(end 0.12065 -0.3048)
			(stroke
				(width 0.1)
				(type default)
			)
			(layer "F.Fab")
		)
		(fp_line
			(start -0.12065 -0.2794)
			(end 0.12065 -0.2794)
			(stroke
				(width 0.1)
				(type default)
			)
			(layer "F.Fab")
		)
		(fp_line
			(start 0.120396 0.2794)
			(end -0.12065 0.2794)
			(stroke
				(width 0.1)
				(type default)
			)
			(layer "F.Fab")
		)
		(fp_line
			(start -0.12065 0.2794)
			(end -0.12065 0.3048)
			(stroke
				(width 0.1)
				(type default)
			)
			(layer "F.Fab")
		)
		(fp_line
			(start 0.67945 0.3048)
			(end 0.120396 0.3048)
			(stroke
				(width 0.1)
				(type default)
			)
			(layer "F.Fab")
		)
		(fp_line
			(start 0.120396 0.3048)
			(end 0.120396 0.2794)
			(stroke
				(width 0.1)
				(type default)
			)
			(layer "F.Fab")
		)
		(fp_line
			(start -0.12065 0.3048)
			(end -0.67945 0.3048)
			(stroke
				(width 0.1)
				(type default)
			)
			(layer "F.Fab")
		)
		(fp_line
			(start -0.67945 0.3048)
			(end -0.67945 -0.305054)
			(stroke
				(width 0.1)
				(type default)
			)
			(layer "F.Fab")
		)
		(pad "1" smd circle
			(at -0.40005 0 90)
			(size 0 0)
			(layers "F.Cu" "F.Mask" "F.Paste")
			(net "FAN_5_PRESENT")
		)
		(pad "2" smd circle
			(at 0.40005 0 90)
			(size 0 0)
			(layers "F.Cu" "F.Mask" "F.Paste")
			(net "GND")
		)
	)
	(footprint ""
		(layer "F.Cu")
		(at 37.846 -126.238 180)
		(property "Reference" "R5606"
			(at 0 0 180)
			(layer "F.SilkS")
			(hide yes)
			(effects
				(font
					(size 1.27 1.27)
				)
			)
		)
		(property "Value" ""
			(at 0 0 180)
			(layer "F.Fab")
			(effects
				(font
					(size 1.27 1.27)
				)
			)
		)
		(duplicate_pad_numbers_are_jumpers no)
		(fp_line
			(start 0.7874 0.4064)
			(end -0.7874 0.4064)
			(stroke
				(width 0.1524)
				(type default)
			)
			(layer "F.SilkS")
		)
		(fp_line
			(start 0.7874 -0.4064)
			(end 0.7874 0.4064)
			(stroke
				(width 0.1524)
				(type default)
			)
			(layer "F.SilkS")
		)
		(fp_line
			(start -0.7874 0.4064)
			(end -0.7874 -0.4064)
			(stroke
				(width 0.1524)
				(type default)
			)
			(layer "F.SilkS")
		)
		(fp_line
			(start -0.7874 -0.4064)
			(end 0.7874 -0.4064)
			(stroke
				(width 0.1524)
				(type default)
			)
			(layer "F.SilkS")
		)
		(fp_line
			(start 0.67945 0.3048)
			(end 0.120396 0.3048)
			(stroke
				(width 0.1)
				(type default)
			)
			(layer "F.Fab")
		)
		(fp_line
			(start 0.67945 -0.3048)
			(end 0.67945 0.3048)
			(stroke
				(width 0.1)
				(type default)
			)
			(layer "F.Fab")
		)
		(fp_line
			(start 0.12065 -0.2794)
			(end 0.12065 -0.3048)
			(stroke
				(width 0.1)
				(type default)
			)
			(layer "F.Fab")
		)
		(fp_line
			(start 0.12065 -0.3048)
			(end 0.67945 -0.3048)
			(stroke
				(width 0.1)
				(type default)
			)
			(layer "F.Fab")
		)
		(fp_line
			(start 0.120396 0.3048)
			(end 0.120396 0.2794)
			(stroke
				(width 0.1)
				(type default)
			)
			(layer "F.Fab")
		)
		(fp_line
			(start 0.120396 0.2794)
			(end -0.12065 0.2794)
			(stroke
				(width 0.1)
				(type default)
			)
			(layer "F.Fab")
		)
		(fp_line
			(start -0.12065 0.3048)
			(end -0.67945 0.3048)
			(stroke
				(width 0.1)
				(type default)
			)
			(layer "F.Fab")
		)
		(fp_line
			(start -0.12065 0.2794)
			(end -0.12065 0.3048)
			(stroke
				(width 0.1)
				(type default)
			)
			(layer "F.Fab")
		)
		(fp_line
			(start -0.12065 -0.2794)
			(end 0.12065 -0.2794)
			(stroke
				(width 0.1)
				(type default)
			)
			(layer "F.Fab")
		)
		(fp_line
			(start -0.12065 -0.305054)
			(end -0.12065 -0.2794)
			(stroke
				(width 0.1)
				(type default)
			)
			(layer "F.Fab")
		)
		(fp_line
			(start -0.67945 0.3048)
			(end -0.67945 -0.305054)
			(stroke
				(width 0.1)
				(type default)
			)
			(layer "F.Fab")
		)
		(fp_line
			(start -0.67945 -0.305054)
			(end -0.12065 -0.305054)
			(stroke
				(width 0.1)
				(type default)
			)
			(layer "F.Fab")
		)
		(pad "1" smd rect
			(at -0.40005 0)
			(size 0.4572 0.508)
			(layers "F.Cu" "F.Mask" "F.Paste")
			(net "FAN_2_TACH_OL")
		)
		(pad "2" smd rect
			(at 0.40005 0)
			(size 0.4572 0.508)
			(layers "F.Cu" "F.Mask" "F.Paste")
			(net "FAN_2_TACH_OL_R1")
		)
	)
	(footprint ""
		(layer "F.Cu")
		(at 25.781 -300.99 180)
		(property "Reference" "U61"
			(at 1.00838 -1.94945 0)
			(unlocked yes)
			(layer "F.SilkS")
			(effects
				(font
					(size 0.7874 0.5842)
					(thickness 0.1524)
				)
				(justify left)
			)
		)
		(property "Value" ""
			(at 0 0 180)
			(layer "F.Fab")
			(effects
				(font
					(size 1.27 1.27)
				)
			)
		)
		(duplicate_pad_numbers_are_jumpers no)
		(fp_line
			(start 1.538478 1.150874)
			(end 1.538478 -1.150874)
			(stroke
				(width 0.1524)
				(type default)
			)
			(layer "F.SilkS")
		)
		(fp_line
			(start 1.538478 -1.150874)
			(end -1.538478 -1.150874)
			(stroke
				(width 0.1524)
				(type default)
			)
			(layer "F.SilkS")
		)
		(fp_line
			(start -1.538478 1.150874)
			(end 1.538478 1.150874)
			(stroke
				(width 0.1524)
				(type default)
			)
			(layer "F.SilkS")
		)
		(fp_line
			(start -1.538478 -1.150874)
			(end -1.538478 1.150874)
			(stroke
				(width 0.1524)
				(type default)
			)
			(layer "F.SilkS")
		)
		(fp_line
			(start 0.674878 1.100074)
			(end 0.674878 -1.100074)
			(stroke
				(width 0.1)
				(type default)
			)
			(layer "F.Fab")
		)
		(fp_line
			(start 0.674878 -1.100074)
			(end -0.674878 -1.100074)
			(stroke
				(width 0.1)
				(type default)
			)
			(layer "F.Fab")
		)
		(fp_line
			(start -0.674878 1.100074)
			(end 0.674878 1.100074)
			(stroke
				(width 0.1)
				(type default)
			)
			(layer "F.Fab")
		)
		(fp_line
			(start -0.674878 -1.100074)
			(end -0.674878 1.100074)
			(stroke
				(width 0.1)
				(type default)
			)
			(layer "F.Fab")
		)
		(pad "1" smd rect
			(at -0.94996 -0.649986 270)
			(size 0.7112 0.9144)
			(layers "F.Cu" "F.Mask" "F.Paste")
			(net "FAN_0_PWM_IL")
		)
		(pad "2" smd rect
			(at -0.94996 0.649986 270)
			(size 0.7112 0.9144)
			(layers "F.Cu" "F.Mask" "F.Paste")
			(net "FAN_0_PWM_OL")
		)
		(pad "3" smd rect
			(at 0.94996 0 270)
			(size 0.7112 0.9144)
			(layers "F.Cu" "F.Mask" "F.Paste")
			(net "FAN_0_PWM_BUF")
		)
	)
	(footprint ""
		(layer "F.Cu")
		(at 36.698428 -252.132846 180)
		(property "Reference" "R5418"
			(at 0 0 180)
			(layer "F.SilkS")
			(hide yes)
			(effects
				(font
					(size 1.27 1.27)
				)
			)
		)
		(property "Value" ""
			(at 0 0 180)
			(layer "F.Fab")
			(effects
				(font
					(size 1.27 1.27)
				)
			)
		)
		(duplicate_pad_numbers_are_jumpers no)
		(fp_line
			(start 0.7874 0.4064)
			(end -0.7874 0.4064)
			(stroke
				(width 0.1524)
				(type default)
			)
			(layer "F.SilkS")
		)
		(fp_line
			(start 0.7874 -0.4064)
			(end 0.7874 0.4064)
			(stroke
				(width 0.1524)
				(type default)
			)
			(layer "F.SilkS")
		)
		(fp_line
			(start -0.7874 0.4064)
			(end -0.7874 -0.4064)
			(stroke
				(width 0.1524)
				(type default)
			)
			(layer "F.SilkS")
		)
		(fp_line
			(start -0.7874 -0.4064)
			(end 0.7874 -0.4064)
			(stroke
				(width 0.1524)
				(type default)
			)
			(layer "F.SilkS")
		)
		(fp_line
			(start 0.67945 0.3048)
			(end 0.120396 0.3048)
			(stroke
				(width 0.1)
				(type default)
			)
			(layer "F.Fab")
		)
		(fp_line
			(start 0.67945 -0.3048)
			(end 0.67945 0.3048)
			(stroke
				(width 0.1)
				(type default)
			)
			(layer "F.Fab")
		)
		(fp_line
			(start 0.12065 -0.2794)
			(end 0.12065 -0.3048)
			(stroke
				(width 0.1)
				(type default)
			)
			(layer "F.Fab")
		)
		(fp_line
			(start 0.12065 -0.3048)
			(end 0.67945 -0.3048)
			(stroke
				(width 0.1)
				(type default)
			)
			(layer "F.Fab")
		)
		(fp_line
			(start 0.120396 0.3048)
			(end 0.120396 0.2794)
			(stroke
				(width 0.1)
				(type default)
			)
			(layer "F.Fab")
		)
		(fp_line
			(start 0.120396 0.2794)
			(end -0.12065 0.2794)
			(stroke
				(width 0.1)
				(type default)
			)
			(layer "F.Fab")
		)
		(fp_line
			(start -0.12065 0.3048)
			(end -0.67945 0.3048)
			(stroke
				(width 0.1)
				(type default)
			)
			(layer "F.Fab")
		)
		(fp_line
			(start -0.12065 0.2794)
			(end -0.12065 0.3048)
			(stroke
				(width 0.1)
				(type default)
			)
			(layer "F.Fab")
		)
		(fp_line
			(start -0.12065 -0.2794)
			(end 0.12065 -0.2794)
			(stroke
				(width 0.1)
				(type default)
			)
			(layer "F.Fab")
		)
		(fp_line
			(start -0.12065 -0.305054)
			(end -0.12065 -0.2794)
			(stroke
				(width 0.1)
				(type default)
			)
			(layer "F.Fab")
		)
		(fp_line
			(start -0.67945 0.3048)
			(end -0.67945 -0.305054)
			(stroke
				(width 0.1)
				(type default)
			)
			(layer "F.Fab")
		)
		(fp_line
			(start -0.67945 -0.305054)
			(end -0.12065 -0.305054)
			(stroke
				(width 0.1)
				(type default)
			)
			(layer "F.Fab")
		)
		(pad "1" smd circle
			(at -0.40005 0 180)
			(size 0 0)
			(layers "F.Cu" "F.Mask" "F.Paste")
			(net "FAN_1_PRESENT_R")
		)
		(pad "2" smd circle
			(at 0.40005 0 180)
			(size 0 0)
			(layers "F.Cu" "F.Mask" "F.Paste")
			(net "FAN_1_PRESENT")
		)
	)
	(footprint ""
		(layer "F.Cu")
		(at 29.845 -194.818 -90)
		(property "Reference" "C2092"
			(at 0 0 270)
			(layer "F.SilkS")
			(hide yes)
			(effects
				(font
					(size 1.27 1.27)
				)
			)
		)
		(property "Value" ""
			(at 0 0 270)
			(layer "F.Fab")
			(effects
				(font
					(size 1.27 1.27)
				)
			)
		)
		(duplicate_pad_numbers_are_jumpers no)
		(fp_line
			(start -0.7874 0.4064)
			(end -0.7874 -0.4064)
			(stroke
				(width 0.1524)
				(type default)
			)
			(layer "F.SilkS")
		)
		(fp_line
			(start 0.7874 0.4064)
			(end -0.7874 0.4064)
			(stroke
				(width 0.1524)
				(type default)
			)
			(layer "F.SilkS")
		)
		(fp_line
			(start -0.7874 -0.4064)
			(end 0.7874 -0.4064)
			(stroke
				(width 0.1524)
				(type default)
			)
			(layer "F.SilkS")
		)
		(fp_line
			(start 0.7874 -0.4064)
			(end 0.7874 0.4064)
			(stroke
				(width 0.1524)
				(type default)
			)
			(layer "F.SilkS")
		)
		(fp_line
			(start -0.67945 0.3048)
			(end -0.67945 -0.305054)
			(stroke
				(width 0.1)
				(type default)
			)
			(layer "F.Fab")
		)
		(fp_line
			(start -0.12065 0.3048)
			(end -0.67945 0.3048)
			(stroke
				(width 0.1)
				(type default)
			)
			(layer "F.Fab")
		)
		(fp_line
			(start 0.120396 0.3048)
			(end 0.120396 0.2794)
			(stroke
				(width 0.1)
				(type default)
			)
			(layer "F.Fab")
		)
		(fp_line
			(start 0.67945 0.3048)
			(end 0.120396 0.3048)
			(stroke
				(width 0.1)
				(type default)
			)
			(layer "F.Fab")
		)
		(fp_line
			(start -0.12065 0.2794)
			(end -0.12065 0.3048)
			(stroke
				(width 0.1)
				(type default)
			)
			(layer "F.Fab")
		)
		(fp_line
			(start 0.120396 0.2794)
			(end -0.12065 0.2794)
			(stroke
				(width 0.1)
				(type default)
			)
			(layer "F.Fab")
		)
		(fp_line
			(start -0.12065 -0.2794)
			(end 0.12065 -0.2794)
			(stroke
				(width 0.1)
				(type default)
			)
			(layer "F.Fab")
		)
		(fp_line
			(start 0.12065 -0.2794)
			(end 0.12065 -0.3048)
			(stroke
				(width 0.1)
				(type default)
			)
			(layer "F.Fab")
		)
		(fp_line
			(start 0.12065 -0.3048)
			(end 0.67945 -0.3048)
			(stroke
				(width 0.1)
				(type default)
			)
			(layer "F.Fab")
		)
		(fp_line
			(start 0.67945 -0.3048)
			(end 0.67945 0.3048)
			(stroke
				(width 0.1)
				(type default)
			)
			(layer "F.Fab")
		)
		(fp_line
			(start -0.67945 -0.305054)
			(end -0.12065 -0.305054)
			(stroke
				(width 0.1)
				(type default)
			)
			(layer "F.Fab")
		)
		(fp_line
			(start -0.12065 -0.305054)
			(end -0.12065 -0.2794)
			(stroke
				(width 0.1)
				(type default)
			)
			(layer "F.Fab")
		)
		(pad "1" smd circle
			(at -0.40005 0 270)
			(size 0 0)
			(layers "F.Cu" "F.Mask" "F.Paste")
			(net "P3V3_AUX")
		)
		(pad "2" smd circle
			(at 0.40005 0 270)
			(size 0 0)
			(layers "F.Cu" "F.Mask" "F.Paste")
			(net "GND")
		)
	)
	(footprint ""
		(layer "F.Cu")
		(at 18.415 -188.595 180)
		(property "Reference" "R308"
			(at 0 0 180)
			(layer "F.SilkS")
			(hide yes)
			(effects
				(font
					(size 1.27 1.27)
				)
			)
		)
		(property "Value" ""
			(at 0 0 180)
			(layer "F.Fab")
			(effects
				(font
					(size 1.27 1.27)
				)
			)
		)
		(duplicate_pad_numbers_are_jumpers no)
		(fp_line
			(start 0.7874 0.4064)
			(end -0.7874 0.4064)
			(stroke
				(width 0.1524)
				(type default)
			)
			(layer "F.SilkS")
		)
		(fp_line
			(start 0.7874 -0.4064)
			(end 0.7874 0.4064)
			(stroke
				(width 0.1524)
				(type default)
			)
			(layer "F.SilkS")
		)
		(fp_line
			(start -0.7874 0.4064)
			(end -0.7874 -0.4064)
			(stroke
				(width 0.1524)
				(type default)
			)
			(layer "F.SilkS")
		)
		(fp_line
			(start -0.7874 -0.4064)
			(end 0.7874 -0.4064)
			(stroke
				(width 0.1524)
				(type default)
			)
			(layer "F.SilkS")
		)
		(fp_line
			(start 0.67945 0.3048)
			(end 0.120396 0.3048)
			(stroke
				(width 0.1)
				(type default)
			)
			(layer "F.Fab")
		)
		(fp_line
			(start 0.67945 -0.3048)
			(end 0.67945 0.3048)
			(stroke
				(width 0.1)
				(type default)
			)
			(layer "F.Fab")
		)
		(fp_line
			(start 0.12065 -0.2794)
			(end 0.12065 -0.3048)
			(stroke
				(width 0.1)
				(type default)
			)
			(layer "F.Fab")
		)
		(fp_line
			(start 0.12065 -0.3048)
			(end 0.67945 -0.3048)
			(stroke
				(width 0.1)
				(type default)
			)
			(layer "F.Fab")
		)
		(fp_line
			(start 0.120396 0.3048)
			(end 0.120396 0.2794)
			(stroke
				(width 0.1)
				(type default)
			)
			(layer "F.Fab")
		)
		(fp_line
			(start 0.120396 0.2794)
			(end -0.12065 0.2794)
			(stroke
				(width 0.1)
				(type default)
			)
			(layer "F.Fab")
		)
		(fp_line
			(start -0.12065 0.3048)
			(end -0.67945 0.3048)
			(stroke
				(width 0.1)
				(type default)
			)
			(layer "F.Fab")
		)
		(fp_line
			(start -0.12065 0.2794)
			(end -0.12065 0.3048)
			(stroke
				(width 0.1)
				(type default)
			)
			(layer "F.Fab")
		)
		(fp_line
			(start -0.12065 -0.2794)
			(end 0.12065 -0.2794)
			(stroke
				(width 0.1)
				(type default)
			)
			(layer "F.Fab")
		)
		(fp_line
			(start -0.12065 -0.305054)
			(end -0.12065 -0.2794)
			(stroke
				(width 0.1)
				(type default)
			)
			(layer "F.Fab")
		)
		(fp_line
			(start -0.67945 0.3048)
			(end -0.67945 -0.305054)
			(stroke
				(width 0.1)
				(type default)
			)
			(layer "F.Fab")
		)
		(fp_line
			(start -0.67945 -0.305054)
			(end -0.12065 -0.305054)
			(stroke
				(width 0.1)
				(type default)
			)
			(layer "F.Fab")
		)
		(pad "1" smd circle
			(at -0.40005 0 180)
			(size 0 0)
			(layers "F.Cu" "F.Mask" "F.Paste")
			(net "P3V3_AUX")
		)
		(pad "2" smd circle
			(at 0.40005 0 180)
			(size 0 0)
			(layers "F.Cu" "F.Mask" "F.Paste")
			(net "FRU_WP_N")
		)
	)
	(footprint ""
		(layer "F.Cu")
		(at 34.798 -24.638)
		(property "Reference" "R5531"
			(at 0 0 0)
			(layer "F.SilkS")
			(hide yes)
			(effects
				(font
					(size 1.27 1.27)
				)
			)
		)
		(property "Value" ""
			(at 0 0 0)
			(layer "F.Fab")
			(effects
				(font
					(size 1.27 1.27)
				)
			)
		)
		(duplicate_pad_numbers_are_jumpers no)
		(fp_line
			(start -0.7874 -0.4064)
			(end 0.7874 -0.4064)
			(stroke
				(width 0.1524)
				(type default)
			)
			(layer "F.SilkS")
		)
		(fp_line
			(start -0.7874 0.4064)
			(end -0.7874 -0.4064)
			(stroke
				(width 0.1524)
				(type default)
			)
			(layer "F.SilkS")
		)
		(fp_line
			(start 0.7874 -0.4064)
			(end 0.7874 0.4064)
			(stroke
				(width 0.1524)
				(type default)
			)
			(layer "F.SilkS")
		)
		(fp_line
			(start 0.7874 0.4064)
			(end -0.7874 0.4064)
			(stroke
				(width 0.1524)
				(type default)
			)
			(layer "F.SilkS")
		)
		(fp_line
			(start -0.67945 -0.305054)
			(end -0.12065 -0.305054)
			(stroke
				(width 0.1)
				(type default)
			)
			(layer "F.Fab")
		)
		(fp_line
			(start -0.67945 0.3048)
			(end -0.67945 -0.305054)
			(stroke
				(width 0.1)
				(type default)
			)
			(layer "F.Fab")
		)
		(fp_line
			(start -0.12065 -0.305054)
			(end -0.12065 -0.2794)
			(stroke
				(width 0.1)
				(type default)
			)
			(layer "F.Fab")
		)
		(fp_line
			(start -0.12065 -0.2794)
			(end 0.12065 -0.2794)
			(stroke
				(width 0.1)
				(type default)
			)
			(layer "F.Fab")
		)
		(fp_line
			(start -0.12065 0.2794)
			(end -0.12065 0.3048)
			(stroke
				(width 0.1)
				(type default)
			)
			(layer "F.Fab")
		)
		(fp_line
			(start -0.12065 0.3048)
			(end -0.67945 0.3048)
			(stroke
				(width 0.1)
				(type default)
			)
			(layer "F.Fab")
		)
		(fp_line
			(start 0.120396 0.2794)
			(end -0.12065 0.2794)
			(stroke
				(width 0.1)
				(type default)
			)
			(layer "F.Fab")
		)
		(fp_line
			(start 0.120396 0.3048)
			(end 0.120396 0.2794)
			(stroke
				(width 0.1)
				(type default)
			)
			(layer "F.Fab")
		)
		(fp_line
			(start 0.12065 -0.3048)
			(end 0.67945 -0.3048)
			(stroke
				(width 0.1)
				(type default)
			)
			(layer "F.Fab")
		)
		(fp_line
			(start 0.12065 -0.2794)
			(end 0.12065 -0.3048)
			(stroke
				(width 0.1)
				(type default)
			)
			(layer "F.Fab")
		)
		(fp_line
			(start 0.67945 -0.3048)
			(end 0.67945 0.3048)
			(stroke
				(width 0.1)
				(type default)
			)
			(layer "F.Fab")
		)
		(fp_line
			(start 0.67945 0.3048)
			(end 0.120396 0.3048)
			(stroke
				(width 0.1)
				(type default)
			)
			(layer "F.Fab")
		)
		(pad "1" smd rect
			(at -0.40005 0 180)
			(size 0.4572 0.508)
			(layers "F.Cu" "F.Mask" "F.Paste")
			(net "P12V_LED_FAN3")
		)
		(pad "2" smd rect
			(at 0.40005 0 180)
			(size 0.4572 0.508)
			(layers "F.Cu" "F.Mask" "F.Paste")
			(net "FAN_3_FAIL_LED_R_N")
		)
	)
	(footprint ""
		(layer "F.Cu")
		(at 15.377922 -17.866868 180)
		(property "Reference" "D242"
			(at 5.852922 -0.436118 0)
			(unlocked yes)
			(layer "F.SilkS")
			(effects
				(font
					(size 0.635 0.4064)
					(thickness 0.1524)
				)
				(justify left)
			)
		)
		(property "Value" ""
			(at 0 0 180)
			(layer "F.Fab")
			(effects
				(font
					(size 1.27 1.27)
				)
			)
		)
		(duplicate_pad_numbers_are_jumpers no)
		(fp_line
			(start 0.94488 0.450088)
			(end 0.94488 -0.450088)
			(stroke
				(width 0.1524)
				(type default)
			)
			(layer "F.SilkS")
		)
		(fp_line
			(start 0.94488 -0.450088)
			(end -0.854964 -0.450088)
			(stroke
				(width 0.1524)
				(type default)
			)
			(layer "F.SilkS")
		)
		(fp_line
			(start 0.870458 -0.2794)
			(end 0.845058 0.4064)
			(stroke
				(width 0.1524)
				(type default)
			)
			(layer "F.SilkS")
		)
		(fp_line
			(start 0.845058 0.4064)
			(end 0.845058 -0.381)
			(stroke
				(width 0.1524)
				(type default)
			)
			(layer "F.SilkS")
		)
		(fp_line
			(start -0.854964 0.450088)
			(end 0.925068 0.450088)
			(stroke
				(width 0.1524)
				(type default)
			)
			(layer "F.SilkS")
		)
		(fp_line
			(start -0.854964 -0.450088)
			(end -0.854964 0.450088)
			(stroke
				(width 0.1524)
				(type default)
			)
			(layer "F.SilkS")
		)
		(fp_line
			(start 0.54991 0.350012)
			(end 0.54991 -0.350012)
			(stroke
				(width 0.1)
				(type default)
			)
			(layer "F.Fab")
		)
		(fp_line
			(start 0.54991 -0.350012)
			(end -0.54991 -0.350012)
			(stroke
				(width 0.1)
				(type default)
			)
			(layer "F.Fab")
		)
		(fp_line
			(start -0.54991 0.350012)
			(end 0.54991 0.350012)
			(stroke
				(width 0.1)
				(type default)
			)
			(layer "F.Fab")
		)
		(fp_line
			(start -0.54991 -0.350012)
			(end -0.54991 0.350012)
			(stroke
				(width 0.1)
				(type default)
			)
			(layer "F.Fab")
		)
		(fp_text user "-"
			(at 2.296922 0.262382 0)
			(unlocked yes)
			(layer "F.SilkS")
			(effects
				(font
					(size 1.905 1.4224)
					(thickness 0.1524)
				)
				(justify left)
			)
		)
		(fp_text user "+"
			(at -0.624078 0.262382 0)
			(unlocked yes)
			(layer "F.SilkS")
			(effects
				(font
					(size 1.905 1.4224)
					(thickness 0.1524)
				)
				(justify left)
			)
		)
		(fp_text user "-"
			(at 2.48539 0.239014 0)
			(unlocked yes)
			(layer "F.Fab")
			(effects
				(font
					(size 1.905 1.4224)
					(thickness 0.1524)
				)
				(justify left)
			)
		)
		(fp_text user "+"
			(at -0.808228 0.239014 0)
			(unlocked yes)
			(layer "F.Fab")
			(effects
				(font
					(size 1.905 1.4224)
					(thickness 0.1524)
				)
				(justify left)
			)
		)
		(pad "A" smd rect
			(at -0.424942 0 180)
			(size 0.5588 0.6096)
			(layers "F.Cu" "F.Mask" "F.Paste")
			(net "GND")
		)
		(pad "C" smd rect
			(at 0.424942 0)
			(size 0.5588 0.6096)
			(layers "F.Cu" "F.Mask" "F.Paste")
			(net "FAN_4_TACH_IL_D")
		)
	)
	(footprint ""
		(layer "F.Cu")
		(at 37.846 -131.318 180)
		(property "Reference" "R5602"
			(at 0 0 180)
			(layer "F.SilkS")
			(hide yes)
			(effects
				(font
					(size 1.27 1.27)
				)
			)
		)
		(property "Value" ""
			(at 0 0 180)
			(layer "F.Fab")
			(effects
				(font
					(size 1.27 1.27)
				)
			)
		)
		(duplicate_pad_numbers_are_jumpers no)
		(fp_line
			(start 0.7874 0.4064)
			(end -0.7874 0.4064)
			(stroke
				(width 0.1524)
				(type default)
			)
			(layer "F.SilkS")
		)
		(fp_line
			(start 0.7874 -0.4064)
			(end 0.7874 0.4064)
			(stroke
				(width 0.1524)
				(type default)
			)
			(layer "F.SilkS")
		)
		(fp_line
			(start -0.7874 0.4064)
			(end -0.7874 -0.4064)
			(stroke
				(width 0.1524)
				(type default)
			)
			(layer "F.SilkS")
		)
		(fp_line
			(start -0.7874 -0.4064)
			(end 0.7874 -0.4064)
			(stroke
				(width 0.1524)
				(type default)
			)
			(layer "F.SilkS")
		)
		(fp_line
			(start 0.67945 0.3048)
			(end 0.120396 0.3048)
			(stroke
				(width 0.1)
				(type default)
			)
			(layer "F.Fab")
		)
		(fp_line
			(start 0.67945 -0.3048)
			(end 0.67945 0.3048)
			(stroke
				(width 0.1)
				(type default)
			)
			(layer "F.Fab")
		)
		(fp_line
			(start 0.12065 -0.2794)
			(end 0.12065 -0.3048)
			(stroke
				(width 0.1)
				(type default)
			)
			(layer "F.Fab")
		)
		(fp_line
			(start 0.12065 -0.3048)
			(end 0.67945 -0.3048)
			(stroke
				(width 0.1)
				(type default)
			)
			(layer "F.Fab")
		)
		(fp_line
			(start 0.120396 0.3048)
			(end 0.120396 0.2794)
			(stroke
				(width 0.1)
				(type default)
			)
			(layer "F.Fab")
		)
		(fp_line
			(start 0.120396 0.2794)
			(end -0.12065 0.2794)
			(stroke
				(width 0.1)
				(type default)
			)
			(layer "F.Fab")
		)
		(fp_line
			(start -0.12065 0.3048)
			(end -0.67945 0.3048)
			(stroke
				(width 0.1)
				(type default)
			)
			(layer "F.Fab")
		)
		(fp_line
			(start -0.12065 0.2794)
			(end -0.12065 0.3048)
			(stroke
				(width 0.1)
				(type default)
			)
			(layer "F.Fab")
		)
		(fp_line
			(start -0.12065 -0.2794)
			(end 0.12065 -0.2794)
			(stroke
				(width 0.1)
				(type default)
			)
			(layer "F.Fab")
		)
		(fp_line
			(start -0.12065 -0.305054)
			(end -0.12065 -0.2794)
			(stroke
				(width 0.1)
				(type default)
			)
			(layer "F.Fab")
		)
		(fp_line
			(start -0.67945 0.3048)
			(end -0.67945 -0.305054)
			(stroke
				(width 0.1)
				(type default)
			)
			(layer "F.Fab")
		)
		(fp_line
			(start -0.67945 -0.305054)
			(end -0.12065 -0.305054)
			(stroke
				(width 0.1)
				(type default)
			)
			(layer "F.Fab")
		)
		(pad "1" smd rect
			(at -0.40005 0)
			(size 0.4572 0.508)
			(layers "F.Cu" "F.Mask" "F.Paste")
			(net "FAN_1_TACH_OL")
		)
		(pad "2" smd rect
			(at 0.40005 0)
			(size 0.4572 0.508)
			(layers "F.Cu" "F.Mask" "F.Paste")
			(net "FAN_1_TACH_OL_R1")
		)
	)
	(footprint ""
		(layer "F.Cu")
		(at 3.81 -132.08)
		(property "Reference" "C2095"
			(at 0 0 0)
			(layer "F.SilkS")
			(hide yes)
			(effects
				(font
					(size 1.27 1.27)
				)
			)
		)
		(property "Value" ""
			(at 0 0 0)
			(layer "F.Fab")
			(effects
				(font
					(size 1.27 1.27)
				)
			)
		)
		(duplicate_pad_numbers_are_jumpers no)
		(fp_line
			(start -0.7874 -0.4064)
			(end 0.7874 -0.4064)
			(stroke
				(width 0.1524)
				(type default)
			)
			(layer "F.SilkS")
		)
		(fp_line
			(start -0.7874 0.4064)
			(end -0.7874 -0.4064)
			(stroke
				(width 0.1524)
				(type default)
			)
			(layer "F.SilkS")
		)
		(fp_line
			(start 0.7874 -0.4064)
			(end 0.7874 0.4064)
			(stroke
				(width 0.1524)
				(type default)
			)
			(layer "F.SilkS")
		)
		(fp_line
			(start 0.7874 0.4064)
			(end -0.7874 0.4064)
			(stroke
				(width 0.1524)
				(type default)
			)
			(layer "F.SilkS")
		)
		(fp_line
			(start -0.67945 -0.305054)
			(end -0.12065 -0.305054)
			(stroke
				(width 0.1)
				(type default)
			)
			(layer "F.Fab")
		)
		(fp_line
			(start -0.67945 0.3048)
			(end -0.67945 -0.305054)
			(stroke
				(width 0.1)
				(type default)
			)
			(layer "F.Fab")
		)
		(fp_line
			(start -0.12065 -0.305054)
			(end -0.12065 -0.2794)
			(stroke
				(width 0.1)
				(type default)
			)
			(layer "F.Fab")
		)
		(fp_line
			(start -0.12065 -0.2794)
			(end 0.12065 -0.2794)
			(stroke
				(width 0.1)
				(type default)
			)
			(layer "F.Fab")
		)
		(fp_line
			(start -0.12065 0.2794)
			(end -0.12065 0.3048)
			(stroke
				(width 0.1)
				(type default)
			)
			(layer "F.Fab")
		)
		(fp_line
			(start -0.12065 0.3048)
			(end -0.67945 0.3048)
			(stroke
				(width 0.1)
				(type default)
			)
			(layer "F.Fab")
		)
		(fp_line
			(start 0.120396 0.2794)
			(end -0.12065 0.2794)
			(stroke
				(width 0.1)
				(type default)
			)
			(layer "F.Fab")
		)
		(fp_line
			(start 0.120396 0.3048)
			(end 0.120396 0.2794)
			(stroke
				(width 0.1)
				(type default)
			)
			(layer "F.Fab")
		)
		(fp_line
			(start 0.12065 -0.3048)
			(end 0.67945 -0.3048)
			(stroke
				(width 0.1)
				(type default)
			)
			(layer "F.Fab")
		)
		(fp_line
			(start 0.12065 -0.2794)
			(end 0.12065 -0.3048)
			(stroke
				(width 0.1)
				(type default)
			)
			(layer "F.Fab")
		)
		(fp_line
			(start 0.67945 -0.3048)
			(end 0.67945 0.3048)
			(stroke
				(width 0.1)
				(type default)
			)
			(layer "F.Fab")
		)
		(fp_line
			(start 0.67945 0.3048)
			(end 0.120396 0.3048)
			(stroke
				(width 0.1)
				(type default)
			)
			(layer "F.Fab")
		)
		(pad "1" smd circle
			(at -0.40005 0)
			(size 0 0)
			(layers "F.Cu" "F.Mask" "F.Paste")
			(net "GND")
		)
		(pad "2" smd circle
			(at 0.40005 0)
			(size 0 0)
			(layers "F.Cu" "F.Mask" "F.Paste")
			(net "P3V3_AUX")
		)
	)
	(footprint ""
		(layer "F.Cu")
		(at 25.019 -162.941 90)
		(property "Reference" "R5272"
			(at 0 0 90)
			(layer "F.SilkS")
			(hide yes)
			(effects
				(font
					(size 1.27 1.27)
				)
			)
		)
		(property "Value" ""
			(at 0 0 90)
			(layer "F.Fab")
			(effects
				(font
					(size 1.27 1.27)
				)
			)
		)
		(duplicate_pad_numbers_are_jumpers no)
		(fp_line
			(start 0.7874 -0.4064)
			(end 0.7874 0.4064)
			(stroke
				(width 0.1524)
				(type default)
			)
			(layer "F.SilkS")
		)
		(fp_line
			(start -0.7874 -0.4064)
			(end 0.7874 -0.4064)
			(stroke
				(width 0.1524)
				(type default)
			)
			(layer "F.SilkS")
		)
		(fp_line
			(start 0.7874 0.4064)
			(end -0.7874 0.4064)
			(stroke
				(width 0.1524)
				(type default)
			)
			(layer "F.SilkS")
		)
		(fp_line
			(start -0.7874 0.4064)
			(end -0.7874 -0.4064)
			(stroke
				(width 0.1524)
				(type default)
			)
			(layer "F.SilkS")
		)
		(fp_line
			(start -0.12065 -0.305054)
			(end -0.12065 -0.2794)
			(stroke
				(width 0.1)
				(type default)
			)
			(layer "F.Fab")
		)
		(fp_line
			(start -0.67945 -0.305054)
			(end -0.12065 -0.305054)
			(stroke
				(width 0.1)
				(type default)
			)
			(layer "F.Fab")
		)
		(fp_line
			(start 0.67945 -0.3048)
			(end 0.67945 0.3048)
			(stroke
				(width 0.1)
				(type default)
			)
			(layer "F.Fab")
		)
		(fp_line
			(start 0.12065 -0.3048)
			(end 0.67945 -0.3048)
			(stroke
				(width 0.1)
				(type default)
			)
			(layer "F.Fab")
		)
		(fp_line
			(start 0.12065 -0.2794)
			(end 0.12065 -0.3048)
			(stroke
				(width 0.1)
				(type default)
			)
			(layer "F.Fab")
		)
		(fp_line
			(start -0.12065 -0.2794)
			(end 0.12065 -0.2794)
			(stroke
				(width 0.1)
				(type default)
			)
			(layer "F.Fab")
		)
		(fp_line
			(start 0.120396 0.2794)
			(end -0.12065 0.2794)
			(stroke
				(width 0.1)
				(type default)
			)
			(layer "F.Fab")
		)
		(fp_line
			(start -0.12065 0.2794)
			(end -0.12065 0.3048)
			(stroke
				(width 0.1)
				(type default)
			)
			(layer "F.Fab")
		)
		(fp_line
			(start 0.67945 0.3048)
			(end 0.120396 0.3048)
			(stroke
				(width 0.1)
				(type default)
			)
			(layer "F.Fab")
		)
		(fp_line
			(start 0.120396 0.3048)
			(end 0.120396 0.2794)
			(stroke
				(width 0.1)
				(type default)
			)
			(layer "F.Fab")
		)
		(fp_line
			(start -0.12065 0.3048)
			(end -0.67945 0.3048)
			(stroke
				(width 0.1)
				(type default)
			)
			(layer "F.Fab")
		)
		(fp_line
			(start -0.67945 0.3048)
			(end -0.67945 -0.305054)
			(stroke
				(width 0.1)
				(type default)
			)
			(layer "F.Fab")
		)
		(pad "1" smd circle
			(at -0.40005 0 90)
			(size 0 0)
			(layers "F.Cu" "F.Mask" "F.Paste")
			(net "SMB_FAN6_R_SCL")
		)
		(pad "2" smd circle
			(at 0.40005 0 90)
			(size 0 0)
			(layers "F.Cu" "F.Mask" "F.Paste")
			(net "P3V3_AUX")
		)
	)
	(footprint ""
		(layer "F.Cu")
		(at 29.337 -289.56 -90)
		(property "Reference" "U402"
			(at -1.778 1.11633 90)
			(unlocked yes)
			(layer "F.SilkS")
			(effects
				(font
					(size 0.7874 0.5842)
					(thickness 0.1524)
				)
				(justify left)
			)
		)
		(property "Value" ""
			(at 0 0 270)
			(layer "F.Fab")
			(effects
				(font
					(size 1.27 1.27)
				)
			)
		)
		(duplicate_pad_numbers_are_jumpers no)
		(fp_line
			(start -1.33096 1.100074)
			(end -1.33096 -1.100074)
			(stroke
				(width 0.1524)
				(type default)
			)
			(layer "F.SilkS")
		)
		(fp_line
			(start 1.33096 1.100074)
			(end -1.33096 1.100074)
			(stroke
				(width 0.1524)
				(type default)
			)
			(layer "F.SilkS")
		)
		(fp_line
			(start 0 -0.649986)
			(end 0.381 -1.100074)
			(stroke
				(width 0.1524)
				(type default)
			)
			(layer "F.SilkS")
		)
		(fp_line
			(start -1.33096 -1.100074)
			(end -0.381 -1.100074)
			(stroke
				(width 0.1524)
				(type default)
			)
			(layer "F.SilkS")
		)
		(fp_line
			(start -0.381 -1.100074)
			(end 0 -0.649986)
			(stroke
				(width 0.1524)
				(type default)
			)
			(layer "F.SilkS")
		)
		(fp_line
			(start 0.381 -1.100074)
			(end 1.33096 -1.100074)
			(stroke
				(width 0.1524)
				(type default)
			)
			(layer "F.SilkS")
		)
		(fp_line
			(start 1.33096 -1.100074)
			(end 1.33096 1.100074)
			(stroke
				(width 0.1524)
				(type default)
			)
			(layer "F.SilkS")
		)
		(fp_poly
			(pts
				(xy -0.748538 -2.082292) (xy -1.256538 -2.082292) (xy -1.002538 -1.320292)
			)
			(stroke
				(width 0)
				(type default)
			)
			(fill yes)
			(layer "F.SilkS")
		)
		(fp_line
			(start -0.674878 1.100074)
			(end -0.674878 -1.100074)
			(stroke
				(width 0.1)
				(type default)
			)
			(layer "F.Fab")
		)
		(fp_line
			(start 0.674878 1.100074)
			(end -0.674878 1.100074)
			(stroke
				(width 0.1)
				(type default)
			)
			(layer "F.Fab")
		)
		(fp_line
			(start -0.674878 -1.100074)
			(end 0.674878 -1.100074)
			(stroke
				(width 0.1)
				(type default)
			)
			(layer "F.Fab")
		)
		(fp_line
			(start 0.674878 -1.100074)
			(end 0.674878 1.100074)
			(stroke
				(width 0.1)
				(type default)
			)
			(layer "F.Fab")
		)
		(fp_poly
			(pts
				(xy -2.209292 -0.902462) (xy -2.209292 -0.394462) (xy -1.447292 -0.648462)
			)
			(stroke
				(width 0)
				(type default)
			)
			(fill yes)
			(layer "F.Fab")
		)
		(pad "1" smd rect
			(at -0.94996 -0.649986)
			(size 0.4064 0.508)
			(layers "F.Cu" "F.Mask" "F.Paste")
			(net "NC_U402_P1")
		)
		(pad "2" smd rect
			(at -0.94996 0)
			(size 0.4064 0.508)
			(layers "F.Cu" "F.Mask" "F.Paste")
			(net "FAN_7_PWM")
		)
		(pad "3" smd rect
			(at -0.94996 0.649986)
			(size 0.4064 0.508)
			(layers "F.Cu" "F.Mask" "F.Paste")
			(net "GND")
		)
		(pad "4" smd rect
			(at 0.94996 0.649986)
			(size 0.4064 0.508)
			(layers "F.Cu" "F.Mask" "F.Paste")
			(net "FAN_7_PWM_BUF")
		)
		(pad "5" smd rect
			(at 0.94996 -0.649986)
			(size 0.4064 0.508)
			(layers "F.Cu" "F.Mask" "F.Paste")
			(net "P3V3_AUX")
		)
	)
	(footprint ""
		(layer "F.Cu")
		(at 26.162 -33.401 -90)
		(property "Reference" "R5657"
			(at 0 0 270)
			(layer "F.SilkS")
			(hide yes)
			(effects
				(font
					(size 1.27 1.27)
				)
			)
		)
		(property "Value" ""
			(at 0 0 270)
			(layer "F.Fab")
			(effects
				(font
					(size 1.27 1.27)
				)
			)
		)
		(duplicate_pad_numbers_are_jumpers no)
		(fp_line
			(start -0.7874 0.4064)
			(end -0.7874 -0.4064)
			(stroke
				(width 0.1524)
				(type default)
			)
			(layer "F.SilkS")
		)
		(fp_line
			(start 0.7874 0.4064)
			(end -0.7874 0.4064)
			(stroke
				(width 0.1524)
				(type default)
			)
			(layer "F.SilkS")
		)
		(fp_line
			(start -0.7874 -0.4064)
			(end 0.7874 -0.4064)
			(stroke
				(width 0.1524)
				(type default)
			)
			(layer "F.SilkS")
		)
		(fp_line
			(start 0.7874 -0.4064)
			(end 0.7874 0.4064)
			(stroke
				(width 0.1524)
				(type default)
			)
			(layer "F.SilkS")
		)
		(fp_line
			(start -0.67945 0.3048)
			(end -0.67945 -0.305054)
			(stroke
				(width 0.1)
				(type default)
			)
			(layer "F.Fab")
		)
		(fp_line
			(start -0.12065 0.3048)
			(end -0.67945 0.3048)
			(stroke
				(width 0.1)
				(type default)
			)
			(layer "F.Fab")
		)
		(fp_line
			(start 0.120396 0.3048)
			(end 0.120396 0.2794)
			(stroke
				(width 0.1)
				(type default)
			)
			(layer "F.Fab")
		)
		(fp_line
			(start 0.67945 0.3048)
			(end 0.120396 0.3048)
			(stroke
				(width 0.1)
				(type default)
			)
			(layer "F.Fab")
		)
		(fp_line
			(start -0.12065 0.2794)
			(end -0.12065 0.3048)
			(stroke
				(width 0.1)
				(type default)
			)
			(layer "F.Fab")
		)
		(fp_line
			(start 0.120396 0.2794)
			(end -0.12065 0.2794)
			(stroke
				(width 0.1)
				(type default)
			)
			(layer "F.Fab")
		)
		(fp_line
			(start -0.12065 -0.2794)
			(end 0.12065 -0.2794)
			(stroke
				(width 0.1)
				(type default)
			)
			(layer "F.Fab")
		)
		(fp_line
			(start 0.12065 -0.2794)
			(end 0.12065 -0.3048)
			(stroke
				(width 0.1)
				(type default)
			)
			(layer "F.Fab")
		)
		(fp_line
			(start 0.12065 -0.3048)
			(end 0.67945 -0.3048)
			(stroke
				(width 0.1)
				(type default)
			)
			(layer "F.Fab")
		)
		(fp_line
			(start 0.67945 -0.3048)
			(end 0.67945 0.3048)
			(stroke
				(width 0.1)
				(type default)
			)
			(layer "F.Fab")
		)
		(fp_line
			(start -0.67945 -0.305054)
			(end -0.12065 -0.305054)
			(stroke
				(width 0.1)
				(type default)
			)
			(layer "F.Fab")
		)
		(fp_line
			(start -0.12065 -0.305054)
			(end -0.12065 -0.2794)
			(stroke
				(width 0.1)
				(type default)
			)
			(layer "F.Fab")
		)
		(pad "1" smd circle
			(at -0.40005 0 270)
			(size 0 0)
			(layers "F.Cu" "F.Mask" "F.Paste")
			(net "FAN_3_PRESENT")
		)
		(pad "2" smd circle
			(at 0.40005 0 270)
			(size 0 0)
			(layers "F.Cu" "F.Mask" "F.Paste")
			(net "GND")
		)
	)
	(footprint ""
		(layer "F.Cu")
		(at 34.798 -20.574)
		(property "Reference" "R5532"
			(at 0 0 0)
			(layer "F.SilkS")
			(hide yes)
			(effects
				(font
					(size 1.27 1.27)
				)
			)
		)
		(property "Value" ""
			(at 0 0 0)
			(layer "F.Fab")
			(effects
				(font
					(size 1.27 1.27)
				)
			)
		)
		(duplicate_pad_numbers_are_jumpers no)
		(fp_line
			(start -0.7874 -0.4064)
			(end 0.7874 -0.4064)
			(stroke
				(width 0.1524)
				(type default)
			)
			(layer "F.SilkS")
		)
		(fp_line
			(start -0.7874 0.4064)
			(end -0.7874 -0.4064)
			(stroke
				(width 0.1524)
				(type default)
			)
			(layer "F.SilkS")
		)
		(fp_line
			(start 0.7874 -0.4064)
			(end 0.7874 0.4064)
			(stroke
				(width 0.1524)
				(type default)
			)
			(layer "F.SilkS")
		)
		(fp_line
			(start 0.7874 0.4064)
			(end -0.7874 0.4064)
			(stroke
				(width 0.1524)
				(type default)
			)
			(layer "F.SilkS")
		)
		(fp_line
			(start -0.67945 -0.305054)
			(end -0.12065 -0.305054)
			(stroke
				(width 0.1)
				(type default)
			)
			(layer "F.Fab")
		)
		(fp_line
			(start -0.67945 0.3048)
			(end -0.67945 -0.305054)
			(stroke
				(width 0.1)
				(type default)
			)
			(layer "F.Fab")
		)
		(fp_line
			(start -0.12065 -0.305054)
			(end -0.12065 -0.2794)
			(stroke
				(width 0.1)
				(type default)
			)
			(layer "F.Fab")
		)
		(fp_line
			(start -0.12065 -0.2794)
			(end 0.12065 -0.2794)
			(stroke
				(width 0.1)
				(type default)
			)
			(layer "F.Fab")
		)
		(fp_line
			(start -0.12065 0.2794)
			(end -0.12065 0.3048)
			(stroke
				(width 0.1)
				(type default)
			)
			(layer "F.Fab")
		)
		(fp_line
			(start -0.12065 0.3048)
			(end -0.67945 0.3048)
			(stroke
				(width 0.1)
				(type default)
			)
			(layer "F.Fab")
		)
		(fp_line
			(start 0.120396 0.2794)
			(end -0.12065 0.2794)
			(stroke
				(width 0.1)
				(type default)
			)
			(layer "F.Fab")
		)
		(fp_line
			(start 0.120396 0.3048)
			(end 0.120396 0.2794)
			(stroke
				(width 0.1)
				(type default)
			)
			(layer "F.Fab")
		)
		(fp_line
			(start 0.12065 -0.3048)
			(end 0.67945 -0.3048)
			(stroke
				(width 0.1)
				(type default)
			)
			(layer "F.Fab")
		)
		(fp_line
			(start 0.12065 -0.2794)
			(end 0.12065 -0.3048)
			(stroke
				(width 0.1)
				(type default)
			)
			(layer "F.Fab")
		)
		(fp_line
			(start 0.67945 -0.3048)
			(end 0.67945 0.3048)
			(stroke
				(width 0.1)
				(type default)
			)
			(layer "F.Fab")
		)
		(fp_line
			(start 0.67945 0.3048)
			(end 0.120396 0.3048)
			(stroke
				(width 0.1)
				(type default)
			)
			(layer "F.Fab")
		)
		(pad "1" smd rect
			(at -0.40005 0 180)
			(size 0.4572 0.508)
			(layers "F.Cu" "F.Mask" "F.Paste")
			(net "P12V_LED_FAN3")
		)
		(pad "2" smd rect
			(at 0.40005 0 180)
			(size 0.4572 0.508)
			(layers "F.Cu" "F.Mask" "F.Paste")
			(net "FAN_3_OK_LED_R_N")
		)
	)
	(footprint ""
		(layer "F.Cu")
		(at 17.907 -120.65)
		(property "Reference" "C2035"
			(at 0 0 0)
			(layer "F.SilkS")
			(hide yes)
			(effects
				(font
					(size 1.27 1.27)
				)
			)
		)
		(property "Value" ""
			(at 0 0 0)
			(layer "F.Fab")
			(effects
				(font
					(size 1.27 1.27)
				)
			)
		)
		(duplicate_pad_numbers_are_jumpers no)
		(fp_line
			(start -0.7874 -0.4064)
			(end 0.7874 -0.4064)
			(stroke
				(width 0.1524)
				(type default)
			)
			(layer "F.SilkS")
		)
		(fp_line
			(start -0.7874 0.4064)
			(end -0.7874 -0.4064)
			(stroke
				(width 0.1524)
				(type default)
			)
			(layer "F.SilkS")
		)
		(fp_line
			(start 0.7874 -0.4064)
			(end 0.7874 0.4064)
			(stroke
				(width 0.1524)
				(type default)
			)
			(layer "F.SilkS")
		)
		(fp_line
			(start 0.7874 0.4064)
			(end -0.7874 0.4064)
			(stroke
				(width 0.1524)
				(type default)
			)
			(layer "F.SilkS")
		)
		(fp_line
			(start -0.67945 -0.305054)
			(end -0.12065 -0.305054)
			(stroke
				(width 0.1)
				(type default)
			)
			(layer "F.Fab")
		)
		(fp_line
			(start -0.67945 0.3048)
			(end -0.67945 -0.305054)
			(stroke
				(width 0.1)
				(type default)
			)
			(layer "F.Fab")
		)
		(fp_line
			(start -0.12065 -0.305054)
			(end -0.12065 -0.2794)
			(stroke
				(width 0.1)
				(type default)
			)
			(layer "F.Fab")
		)
		(fp_line
			(start -0.12065 -0.2794)
			(end 0.12065 -0.2794)
			(stroke
				(width 0.1)
				(type default)
			)
			(layer "F.Fab")
		)
		(fp_line
			(start -0.12065 0.2794)
			(end -0.12065 0.3048)
			(stroke
				(width 0.1)
				(type default)
			)
			(layer "F.Fab")
		)
		(fp_line
			(start -0.12065 0.3048)
			(end -0.67945 0.3048)
			(stroke
				(width 0.1)
				(type default)
			)
			(layer "F.Fab")
		)
		(fp_line
			(start 0.120396 0.2794)
			(end -0.12065 0.2794)
			(stroke
				(width 0.1)
				(type default)
			)
			(layer "F.Fab")
		)
		(fp_line
			(start 0.120396 0.3048)
			(end 0.120396 0.2794)
			(stroke
				(width 0.1)
				(type default)
			)
			(layer "F.Fab")
		)
		(fp_line
			(start 0.12065 -0.3048)
			(end 0.67945 -0.3048)
			(stroke
				(width 0.1)
				(type default)
			)
			(layer "F.Fab")
		)
		(fp_line
			(start 0.12065 -0.2794)
			(end 0.12065 -0.3048)
			(stroke
				(width 0.1)
				(type default)
			)
			(layer "F.Fab")
		)
		(fp_line
			(start 0.67945 -0.3048)
			(end 0.67945 0.3048)
			(stroke
				(width 0.1)
				(type default)
			)
			(layer "F.Fab")
		)
		(fp_line
			(start 0.67945 0.3048)
			(end 0.120396 0.3048)
			(stroke
				(width 0.1)
				(type default)
			)
			(layer "F.Fab")
		)
		(pad "1" smd circle
			(at -0.40005 0)
			(size 0 0)
			(layers "F.Cu" "F.Mask" "F.Paste")
			(net "FAN_5_TACH_OL_R")
		)
		(pad "2" smd circle
			(at 0.40005 0)
			(size 0 0)
			(layers "F.Cu" "F.Mask" "F.Paste")
			(net "GND")
		)
	)
	(footprint ""
		(layer "F.Cu")
		(at 27.432 -189.23 180)
		(property "Reference" "R5491"
			(at 0 0 180)
			(layer "F.SilkS")
			(hide yes)
			(effects
				(font
					(size 1.27 1.27)
				)
			)
		)
		(property "Value" ""
			(at 0 0 180)
			(layer "F.Fab")
			(effects
				(font
					(size 1.27 1.27)
				)
			)
		)
		(duplicate_pad_numbers_are_jumpers no)
		(fp_line
			(start 0.7874 0.4064)
			(end -0.7874 0.4064)
			(stroke
				(width 0.1524)
				(type default)
			)
			(layer "F.SilkS")
		)
		(fp_line
			(start 0.7874 -0.4064)
			(end 0.7874 0.4064)
			(stroke
				(width 0.1524)
				(type default)
			)
			(layer "F.SilkS")
		)
		(fp_line
			(start -0.7874 0.4064)
			(end -0.7874 -0.4064)
			(stroke
				(width 0.1524)
				(type default)
			)
			(layer "F.SilkS")
		)
		(fp_line
			(start -0.7874 -0.4064)
			(end 0.7874 -0.4064)
			(stroke
				(width 0.1524)
				(type default)
			)
			(layer "F.SilkS")
		)
		(fp_line
			(start 0.67945 0.3048)
			(end 0.120396 0.3048)
			(stroke
				(width 0.1)
				(type default)
			)
			(layer "F.Fab")
		)
		(fp_line
			(start 0.67945 -0.3048)
			(end 0.67945 0.3048)
			(stroke
				(width 0.1)
				(type default)
			)
			(layer "F.Fab")
		)
		(fp_line
			(start 0.12065 -0.2794)
			(end 0.12065 -0.3048)
			(stroke
				(width 0.1)
				(type default)
			)
			(layer "F.Fab")
		)
		(fp_line
			(start 0.12065 -0.3048)
			(end 0.67945 -0.3048)
			(stroke
				(width 0.1)
				(type default)
			)
			(layer "F.Fab")
		)
		(fp_line
			(start 0.120396 0.3048)
			(end 0.120396 0.2794)
			(stroke
				(width 0.1)
				(type default)
			)
			(layer "F.Fab")
		)
		(fp_line
			(start 0.120396 0.2794)
			(end -0.12065 0.2794)
			(stroke
				(width 0.1)
				(type default)
			)
			(layer "F.Fab")
		)
		(fp_line
			(start -0.12065 0.3048)
			(end -0.67945 0.3048)
			(stroke
				(width 0.1)
				(type default)
			)
			(layer "F.Fab")
		)
		(fp_line
			(start -0.12065 0.2794)
			(end -0.12065 0.3048)
			(stroke
				(width 0.1)
				(type default)
			)
			(layer "F.Fab")
		)
		(fp_line
			(start -0.12065 -0.2794)
			(end 0.12065 -0.2794)
			(stroke
				(width 0.1)
				(type default)
			)
			(layer "F.Fab")
		)
		(fp_line
			(start -0.12065 -0.305054)
			(end -0.12065 -0.2794)
			(stroke
				(width 0.1)
				(type default)
			)
			(layer "F.Fab")
		)
		(fp_line
			(start -0.67945 0.3048)
			(end -0.67945 -0.305054)
			(stroke
				(width 0.1)
				(type default)
			)
			(layer "F.Fab")
		)
		(fp_line
			(start -0.67945 -0.305054)
			(end -0.12065 -0.305054)
			(stroke
				(width 0.1)
				(type default)
			)
			(layer "F.Fab")
		)
		(pad "1" smd circle
			(at -0.40005 0 180)
			(size 0 0)
			(layers "F.Cu" "F.Mask" "F.Paste")
			(net "P52V_FAN_4_BUFF_EN")
		)
		(pad "2" smd circle
			(at 0.40005 0 180)
			(size 0 0)
			(layers "F.Cu" "F.Mask" "F.Paste")
			(net "P52V_FAN_4_BUFF_EN_R")
		)
	)
	(footprint ""
		(layer "F.Cu")
		(at 17.272 -143.891 -90)
		(property "Reference" "R5524"
			(at 0 0 270)
			(layer "F.SilkS")
			(hide yes)
			(effects
				(font
					(size 1.27 1.27)
				)
			)
		)
		(property "Value" ""
			(at 0 0 270)
			(layer "F.Fab")
			(effects
				(font
					(size 1.27 1.27)
				)
			)
		)
		(duplicate_pad_numbers_are_jumpers no)
		(fp_line
			(start -0.7874 0.4064)
			(end -0.7874 -0.4064)
			(stroke
				(width 0.1524)
				(type default)
			)
			(layer "F.SilkS")
		)
		(fp_line
			(start 0.7874 0.4064)
			(end -0.7874 0.4064)
			(stroke
				(width 0.1524)
				(type default)
			)
			(layer "F.SilkS")
		)
		(fp_line
			(start -0.7874 -0.4064)
			(end 0.7874 -0.4064)
			(stroke
				(width 0.1524)
				(type default)
			)
			(layer "F.SilkS")
		)
		(fp_line
			(start 0.7874 -0.4064)
			(end 0.7874 0.4064)
			(stroke
				(width 0.1524)
				(type default)
			)
			(layer "F.SilkS")
		)
		(fp_line
			(start -0.67945 0.3048)
			(end -0.67945 -0.305054)
			(stroke
				(width 0.1)
				(type default)
			)
			(layer "F.Fab")
		)
		(fp_line
			(start -0.12065 0.3048)
			(end -0.67945 0.3048)
			(stroke
				(width 0.1)
				(type default)
			)
			(layer "F.Fab")
		)
		(fp_line
			(start 0.120396 0.3048)
			(end 0.120396 0.2794)
			(stroke
				(width 0.1)
				(type default)
			)
			(layer "F.Fab")
		)
		(fp_line
			(start 0.67945 0.3048)
			(end 0.120396 0.3048)
			(stroke
				(width 0.1)
				(type default)
			)
			(layer "F.Fab")
		)
		(fp_line
			(start -0.12065 0.2794)
			(end -0.12065 0.3048)
			(stroke
				(width 0.1)
				(type default)
			)
			(layer "F.Fab")
		)
		(fp_line
			(start 0.120396 0.2794)
			(end -0.12065 0.2794)
			(stroke
				(width 0.1)
				(type default)
			)
			(layer "F.Fab")
		)
		(fp_line
			(start -0.12065 -0.2794)
			(end 0.12065 -0.2794)
			(stroke
				(width 0.1)
				(type default)
			)
			(layer "F.Fab")
		)
		(fp_line
			(start 0.12065 -0.2794)
			(end 0.12065 -0.3048)
			(stroke
				(width 0.1)
				(type default)
			)
			(layer "F.Fab")
		)
		(fp_line
			(start 0.12065 -0.3048)
			(end 0.67945 -0.3048)
			(stroke
				(width 0.1)
				(type default)
			)
			(layer "F.Fab")
		)
		(fp_line
			(start 0.67945 -0.3048)
			(end 0.67945 0.3048)
			(stroke
				(width 0.1)
				(type default)
			)
			(layer "F.Fab")
		)
		(fp_line
			(start -0.67945 -0.305054)
			(end -0.12065 -0.305054)
			(stroke
				(width 0.1)
				(type default)
			)
			(layer "F.Fab")
		)
		(fp_line
			(start -0.12065 -0.305054)
			(end -0.12065 -0.2794)
			(stroke
				(width 0.1)
				(type default)
			)
			(layer "F.Fab")
		)
		(pad "1" smd circle
			(at -0.40005 0 270)
			(size 0 0)
			(layers "F.Cu" "F.Mask" "F.Paste")
			(net "PD_TCA9548_SML1_U321_A0")
		)
		(pad "2" smd circle
			(at 0.40005 0 270)
			(size 0 0)
			(layers "F.Cu" "F.Mask" "F.Paste")
			(net "GND")
		)
	)
	(footprint ""
		(layer "F.Cu")
		(at 47.752 -315.087 180)
		(property "Reference" "R5647"
			(at 0 0 180)
			(layer "F.SilkS")
			(hide yes)
			(effects
				(font
					(size 1.27 1.27)
				)
			)
		)
		(property "Value" ""
			(at 0 0 180)
			(layer "F.Fab")
			(effects
				(font
					(size 1.27 1.27)
				)
			)
		)
		(duplicate_pad_numbers_are_jumpers no)
		(fp_line
			(start 0.7874 0.4064)
			(end -0.7874 0.4064)
			(stroke
				(width 0.1524)
				(type default)
			)
			(layer "F.SilkS")
		)
		(fp_line
			(start 0.7874 -0.4064)
			(end 0.7874 0.4064)
			(stroke
				(width 0.1524)
				(type default)
			)
			(layer "F.SilkS")
		)
		(fp_line
			(start -0.7874 0.4064)
			(end -0.7874 -0.4064)
			(stroke
				(width 0.1524)
				(type default)
			)
			(layer "F.SilkS")
		)
		(fp_line
			(start -0.7874 -0.4064)
			(end 0.7874 -0.4064)
			(stroke
				(width 0.1524)
				(type default)
			)
			(layer "F.SilkS")
		)
		(fp_line
			(start 0.67945 0.3048)
			(end 0.120396 0.3048)
			(stroke
				(width 0.1)
				(type default)
			)
			(layer "F.Fab")
		)
		(fp_line
			(start 0.67945 -0.3048)
			(end 0.67945 0.3048)
			(stroke
				(width 0.1)
				(type default)
			)
			(layer "F.Fab")
		)
		(fp_line
			(start 0.12065 -0.2794)
			(end 0.12065 -0.3048)
			(stroke
				(width 0.1)
				(type default)
			)
			(layer "F.Fab")
		)
		(fp_line
			(start 0.12065 -0.3048)
			(end 0.67945 -0.3048)
			(stroke
				(width 0.1)
				(type default)
			)
			(layer "F.Fab")
		)
		(fp_line
			(start 0.120396 0.3048)
			(end 0.120396 0.2794)
			(stroke
				(width 0.1)
				(type default)
			)
			(layer "F.Fab")
		)
		(fp_line
			(start 0.120396 0.2794)
			(end -0.12065 0.2794)
			(stroke
				(width 0.1)
				(type default)
			)
			(layer "F.Fab")
		)
		(fp_line
			(start -0.12065 0.3048)
			(end -0.67945 0.3048)
			(stroke
				(width 0.1)
				(type default)
			)
			(layer "F.Fab")
		)
		(fp_line
			(start -0.12065 0.2794)
			(end -0.12065 0.3048)
			(stroke
				(width 0.1)
				(type default)
			)
			(layer "F.Fab")
		)
		(fp_line
			(start -0.12065 -0.2794)
			(end 0.12065 -0.2794)
			(stroke
				(width 0.1)
				(type default)
			)
			(layer "F.Fab")
		)
		(fp_line
			(start -0.12065 -0.305054)
			(end -0.12065 -0.2794)
			(stroke
				(width 0.1)
				(type default)
			)
			(layer "F.Fab")
		)
		(fp_line
			(start -0.67945 0.3048)
			(end -0.67945 -0.305054)
			(stroke
				(width 0.1)
				(type default)
			)
			(layer "F.Fab")
		)
		(fp_line
			(start -0.67945 -0.305054)
			(end -0.12065 -0.305054)
			(stroke
				(width 0.1)
				(type default)
			)
			(layer "F.Fab")
		)
		(pad "1" smd circle
			(at -0.40005 0 180)
			(size 0 0)
			(layers "F.Cu" "F.Mask" "F.Paste")
			(net "FAN_0_PRESENT")
		)
		(pad "2" smd circle
			(at 0.40005 0 180)
			(size 0 0)
			(layers "F.Cu" "F.Mask" "F.Paste")
			(net "GND")
		)
	)
	(footprint ""
		(layer "F.Cu")
		(at 25.850088 -241.909854)
		(property "Reference" "H2"
			(at -3.9878 -4.435348 0)
			(unlocked yes)
			(layer "F.SilkS")
			(effects
				(font
					(size 0.7874 0.5842)
					(thickness 0.1524)
				)
				(justify left)
			)
		)
		(property "Value" ""
			(at 0 0 0)
			(layer "F.Fab")
			(effects
				(font
					(size 1.27 1.27)
				)
			)
		)
		(duplicate_pad_numbers_are_jumpers no)
		(pad "1" thru_hole oval
			(at 0 0)
			(size 9.017 21.0058)
			(drill 3.0226
				(offset 0 5.999988)
			)
			(layers "*.Cu" "*.Mask")
			(remove_unused_layers no)
			(net "GND")
			(clearance -1.500378)
			(padstack
				(mode front_inner_back)
				(layer "Inner"
					(shape circle)
					(size 0 0)
					(clearance 0)
				)
				(layer "B.Cu"
					(shape oval)
					(size 9.017 21.0058)
					(offset 0 5.999988)
					(clearance -1.500378)
				)
			)
		)
	)
	(footprint ""
		(layer "F.Cu")
		(at 43.688 -258.826 90)
		(property "Reference" "PR3"
			(at 0 0 90)
			(layer "F.SilkS")
			(hide yes)
			(effects
				(font
					(size 1.27 1.27)
				)
			)
		)
		(property "Value" ""
			(at 0 0 90)
			(layer "F.Fab")
			(effects
				(font
					(size 1.27 1.27)
				)
			)
		)
		(duplicate_pad_numbers_are_jumpers no)
		(fp_line
			(start 0.7874 -0.4064)
			(end 0.7874 0.4064)
			(stroke
				(width 0.1524)
				(type default)
			)
			(layer "F.SilkS")
		)
		(fp_line
			(start -0.7874 -0.4064)
			(end 0.7874 -0.4064)
			(stroke
				(width 0.1524)
				(type default)
			)
			(layer "F.SilkS")
		)
		(fp_line
			(start 0.7874 0.4064)
			(end -0.7874 0.4064)
			(stroke
				(width 0.1524)
				(type default)
			)
			(layer "F.SilkS")
		)
		(fp_line
			(start -0.7874 0.4064)
			(end -0.7874 -0.4064)
			(stroke
				(width 0.1524)
				(type default)
			)
			(layer "F.SilkS")
		)
		(fp_line
			(start -0.12065 -0.305054)
			(end -0.12065 -0.2794)
			(stroke
				(width 0.1)
				(type default)
			)
			(layer "F.Fab")
		)
		(fp_line
			(start -0.67945 -0.305054)
			(end -0.12065 -0.305054)
			(stroke
				(width 0.1)
				(type default)
			)
			(layer "F.Fab")
		)
		(fp_line
			(start 0.67945 -0.3048)
			(end 0.67945 0.3048)
			(stroke
				(width 0.1)
				(type default)
			)
			(layer "F.Fab")
		)
		(fp_line
			(start 0.12065 -0.3048)
			(end 0.67945 -0.3048)
			(stroke
				(width 0.1)
				(type default)
			)
			(layer "F.Fab")
		)
		(fp_line
			(start 0.12065 -0.2794)
			(end 0.12065 -0.3048)
			(stroke
				(width 0.1)
				(type default)
			)
			(layer "F.Fab")
		)
		(fp_line
			(start -0.12065 -0.2794)
			(end 0.12065 -0.2794)
			(stroke
				(width 0.1)
				(type default)
			)
			(layer "F.Fab")
		)
		(fp_line
			(start 0.120396 0.2794)
			(end -0.12065 0.2794)
			(stroke
				(width 0.1)
				(type default)
			)
			(layer "F.Fab")
		)
		(fp_line
			(start -0.12065 0.2794)
			(end -0.12065 0.3048)
			(stroke
				(width 0.1)
				(type default)
			)
			(layer "F.Fab")
		)
		(fp_line
			(start 0.67945 0.3048)
			(end 0.120396 0.3048)
			(stroke
				(width 0.1)
				(type default)
			)
			(layer "F.Fab")
		)
		(fp_line
			(start 0.120396 0.3048)
			(end 0.120396 0.2794)
			(stroke
				(width 0.1)
				(type default)
			)
			(layer "F.Fab")
		)
		(fp_line
			(start -0.12065 0.3048)
			(end -0.67945 0.3048)
			(stroke
				(width 0.1)
				(type default)
			)
			(layer "F.Fab")
		)
		(fp_line
			(start -0.67945 0.3048)
			(end -0.67945 -0.305054)
			(stroke
				(width 0.1)
				(type default)
			)
			(layer "F.Fab")
		)
		(pad "1" smd rect
			(at -0.40005 0 270)
			(size 0.4572 0.508)
			(layers "F.Cu" "F.Mask" "F.Paste")
			(net "FAN_0_FAULT_R")
		)
		(pad "2" smd rect
			(at 0.40005 0 270)
			(size 0.4572 0.508)
			(layers "F.Cu" "F.Mask" "F.Paste")
			(net "FAN_0_FAULT")
		)
	)
	(footprint ""
		(layer "F.Cu")
		(at 37.465 -211.864956)
		(property "Reference" "R5196"
			(at 0 0 0)
			(layer "F.SilkS")
			(hide yes)
			(effects
				(font
					(size 1.27 1.27)
				)
			)
		)
		(property "Value" ""
			(at 0 0 0)
			(layer "F.Fab")
			(effects
				(font
					(size 1.27 1.27)
				)
			)
		)
		(duplicate_pad_numbers_are_jumpers no)
		(fp_line
			(start -0.7874 -0.4064)
			(end 0.7874 -0.4064)
			(stroke
				(width 0.1524)
				(type default)
			)
			(layer "F.SilkS")
		)
		(fp_line
			(start -0.7874 0.4064)
			(end -0.7874 -0.4064)
			(stroke
				(width 0.1524)
				(type default)
			)
			(layer "F.SilkS")
		)
		(fp_line
			(start 0.7874 -0.4064)
			(end 0.7874 0.4064)
			(stroke
				(width 0.1524)
				(type default)
			)
			(layer "F.SilkS")
		)
		(fp_line
			(start 0.7874 0.4064)
			(end -0.7874 0.4064)
			(stroke
				(width 0.1524)
				(type default)
			)
			(layer "F.SilkS")
		)
		(fp_line
			(start -0.67945 -0.305054)
			(end -0.12065 -0.305054)
			(stroke
				(width 0.1)
				(type default)
			)
			(layer "F.Fab")
		)
		(fp_line
			(start -0.67945 0.3048)
			(end -0.67945 -0.305054)
			(stroke
				(width 0.1)
				(type default)
			)
			(layer "F.Fab")
		)
		(fp_line
			(start -0.12065 -0.305054)
			(end -0.12065 -0.2794)
			(stroke
				(width 0.1)
				(type default)
			)
			(layer "F.Fab")
		)
		(fp_line
			(start -0.12065 -0.2794)
			(end 0.12065 -0.2794)
			(stroke
				(width 0.1)
				(type default)
			)
			(layer "F.Fab")
		)
		(fp_line
			(start -0.12065 0.2794)
			(end -0.12065 0.3048)
			(stroke
				(width 0.1)
				(type default)
			)
			(layer "F.Fab")
		)
		(fp_line
			(start -0.12065 0.3048)
			(end -0.67945 0.3048)
			(stroke
				(width 0.1)
				(type default)
			)
			(layer "F.Fab")
		)
		(fp_line
			(start 0.120396 0.2794)
			(end -0.12065 0.2794)
			(stroke
				(width 0.1)
				(type default)
			)
			(layer "F.Fab")
		)
		(fp_line
			(start 0.120396 0.3048)
			(end 0.120396 0.2794)
			(stroke
				(width 0.1)
				(type default)
			)
			(layer "F.Fab")
		)
		(fp_line
			(start 0.12065 -0.3048)
			(end 0.67945 -0.3048)
			(stroke
				(width 0.1)
				(type default)
			)
			(layer "F.Fab")
		)
		(fp_line
			(start 0.12065 -0.2794)
			(end 0.12065 -0.3048)
			(stroke
				(width 0.1)
				(type default)
			)
			(layer "F.Fab")
		)
		(fp_line
			(start 0.67945 -0.3048)
			(end 0.67945 0.3048)
			(stroke
				(width 0.1)
				(type default)
			)
			(layer "F.Fab")
		)
		(fp_line
			(start 0.67945 0.3048)
			(end 0.120396 0.3048)
			(stroke
				(width 0.1)
				(type default)
			)
			(layer "F.Fab")
		)
		(pad "1" smd circle
			(at -0.40005 0)
			(size 0 0)
			(layers "F.Cu" "F.Mask" "F.Paste")
			(net "FAN_1_PWM_OL")
		)
		(pad "2" smd circle
			(at 0.40005 0)
			(size 0 0)
			(layers "F.Cu" "F.Mask" "F.Paste")
			(net "FAN_1_PWM_OL_R")
		)
	)
	(footprint ""
		(layer "F.Cu")
		(at 4.191 -163.957 180)
		(property "Reference" "R103"
			(at 0 0 180)
			(layer "F.SilkS")
			(hide yes)
			(effects
				(font
					(size 1.27 1.27)
				)
			)
		)
		(property "Value" ""
			(at 0 0 180)
			(layer "F.Fab")
			(effects
				(font
					(size 1.27 1.27)
				)
			)
		)
		(duplicate_pad_numbers_are_jumpers no)
		(fp_line
			(start 0.7874 0.4064)
			(end -0.7874 0.4064)
			(stroke
				(width 0.1524)
				(type default)
			)
			(layer "F.SilkS")
		)
		(fp_line
			(start 0.7874 -0.4064)
			(end 0.7874 0.4064)
			(stroke
				(width 0.1524)
				(type default)
			)
			(layer "F.SilkS")
		)
		(fp_line
			(start -0.7874 0.4064)
			(end -0.7874 -0.4064)
			(stroke
				(width 0.1524)
				(type default)
			)
			(layer "F.SilkS")
		)
		(fp_line
			(start -0.7874 -0.4064)
			(end 0.7874 -0.4064)
			(stroke
				(width 0.1524)
				(type default)
			)
			(layer "F.SilkS")
		)
		(fp_line
			(start 0.67945 0.3048)
			(end 0.120396 0.3048)
			(stroke
				(width 0.1)
				(type default)
			)
			(layer "F.Fab")
		)
		(fp_line
			(start 0.67945 -0.3048)
			(end 0.67945 0.3048)
			(stroke
				(width 0.1)
				(type default)
			)
			(layer "F.Fab")
		)
		(fp_line
			(start 0.12065 -0.2794)
			(end 0.12065 -0.3048)
			(stroke
				(width 0.1)
				(type default)
			)
			(layer "F.Fab")
		)
		(fp_line
			(start 0.12065 -0.3048)
			(end 0.67945 -0.3048)
			(stroke
				(width 0.1)
				(type default)
			)
			(layer "F.Fab")
		)
		(fp_line
			(start 0.120396 0.3048)
			(end 0.120396 0.2794)
			(stroke
				(width 0.1)
				(type default)
			)
			(layer "F.Fab")
		)
		(fp_line
			(start 0.120396 0.2794)
			(end -0.12065 0.2794)
			(stroke
				(width 0.1)
				(type default)
			)
			(layer "F.Fab")
		)
		(fp_line
			(start -0.12065 0.3048)
			(end -0.67945 0.3048)
			(stroke
				(width 0.1)
				(type default)
			)
			(layer "F.Fab")
		)
		(fp_line
			(start -0.12065 0.2794)
			(end -0.12065 0.3048)
			(stroke
				(width 0.1)
				(type default)
			)
			(layer "F.Fab")
		)
		(fp_line
			(start -0.12065 -0.2794)
			(end 0.12065 -0.2794)
			(stroke
				(width 0.1)
				(type default)
			)
			(layer "F.Fab")
		)
		(fp_line
			(start -0.12065 -0.305054)
			(end -0.12065 -0.2794)
			(stroke
				(width 0.1)
				(type default)
			)
			(layer "F.Fab")
		)
		(fp_line
			(start -0.67945 0.3048)
			(end -0.67945 -0.305054)
			(stroke
				(width 0.1)
				(type default)
			)
			(layer "F.Fab")
		)
		(fp_line
			(start -0.67945 -0.305054)
			(end -0.12065 -0.305054)
			(stroke
				(width 0.1)
				(type default)
			)
			(layer "F.Fab")
		)
		(pad "1" smd circle
			(at -0.40005 0 180)
			(size 0 0)
			(layers "F.Cu" "F.Mask" "F.Paste")
			(net "FAN_1_PRSNT_BUF_R_N")
		)
		(pad "2" smd circle
			(at 0.40005 0 180)
			(size 0 0)
			(layers "F.Cu" "F.Mask" "F.Paste")
			(net "FAN_1_PRSNT_BUF_N")
		)
	)
	(footprint ""
		(layer "F.Cu")
		(at 28.956 -169.545 180)
		(property "Reference" "R5093"
			(at 0 0 180)
			(layer "F.SilkS")
			(hide yes)
			(effects
				(font
					(size 1.27 1.27)
				)
			)
		)
		(property "Value" ""
			(at 0 0 180)
			(layer "F.Fab")
			(effects
				(font
					(size 1.27 1.27)
				)
			)
		)
		(duplicate_pad_numbers_are_jumpers no)
		(fp_line
			(start 0.7874 0.4064)
			(end -0.7874 0.4064)
			(stroke
				(width 0.1524)
				(type default)
			)
			(layer "F.SilkS")
		)
		(fp_line
			(start 0.7874 -0.4064)
			(end 0.7874 0.4064)
			(stroke
				(width 0.1524)
				(type default)
			)
			(layer "F.SilkS")
		)
		(fp_line
			(start -0.7874 0.4064)
			(end -0.7874 -0.4064)
			(stroke
				(width 0.1524)
				(type default)
			)
			(layer "F.SilkS")
		)
		(fp_line
			(start -0.7874 -0.4064)
			(end 0.7874 -0.4064)
			(stroke
				(width 0.1524)
				(type default)
			)
			(layer "F.SilkS")
		)
		(fp_line
			(start 0.67945 0.3048)
			(end 0.120396 0.3048)
			(stroke
				(width 0.1)
				(type default)
			)
			(layer "F.Fab")
		)
		(fp_line
			(start 0.67945 -0.3048)
			(end 0.67945 0.3048)
			(stroke
				(width 0.1)
				(type default)
			)
			(layer "F.Fab")
		)
		(fp_line
			(start 0.12065 -0.2794)
			(end 0.12065 -0.3048)
			(stroke
				(width 0.1)
				(type default)
			)
			(layer "F.Fab")
		)
		(fp_line
			(start 0.12065 -0.3048)
			(end 0.67945 -0.3048)
			(stroke
				(width 0.1)
				(type default)
			)
			(layer "F.Fab")
		)
		(fp_line
			(start 0.120396 0.3048)
			(end 0.120396 0.2794)
			(stroke
				(width 0.1)
				(type default)
			)
			(layer "F.Fab")
		)
		(fp_line
			(start 0.120396 0.2794)
			(end -0.12065 0.2794)
			(stroke
				(width 0.1)
				(type default)
			)
			(layer "F.Fab")
		)
		(fp_line
			(start -0.12065 0.3048)
			(end -0.67945 0.3048)
			(stroke
				(width 0.1)
				(type default)
			)
			(layer "F.Fab")
		)
		(fp_line
			(start -0.12065 0.2794)
			(end -0.12065 0.3048)
			(stroke
				(width 0.1)
				(type default)
			)
			(layer "F.Fab")
		)
		(fp_line
			(start -0.12065 -0.2794)
			(end 0.12065 -0.2794)
			(stroke
				(width 0.1)
				(type default)
			)
			(layer "F.Fab")
		)
		(fp_line
			(start -0.12065 -0.305054)
			(end -0.12065 -0.2794)
			(stroke
				(width 0.1)
				(type default)
			)
			(layer "F.Fab")
		)
		(fp_line
			(start -0.67945 0.3048)
			(end -0.67945 -0.305054)
			(stroke
				(width 0.1)
				(type default)
			)
			(layer "F.Fab")
		)
		(fp_line
			(start -0.67945 -0.305054)
			(end -0.12065 -0.305054)
			(stroke
				(width 0.1)
				(type default)
			)
			(layer "F.Fab")
		)
		(pad "1" smd circle
			(at -0.40005 0 180)
			(size 0 0)
			(layers "F.Cu" "F.Mask" "F.Paste")
			(net "PU_U8_PIN2")
		)
		(pad "2" smd circle
			(at 0.40005 0 180)
			(size 0 0)
			(layers "F.Cu" "F.Mask" "F.Paste")
			(net "P3V3_AUX")
		)
	)
	(footprint ""
		(layer "F.Cu")
		(at 34.29 -160.02 90)
		(property "Reference" "R4876"
			(at 0 0 90)
			(layer "F.SilkS")
			(hide yes)
			(effects
				(font
					(size 1.27 1.27)
				)
			)
		)
		(property "Value" ""
			(at 0 0 90)
			(layer "F.Fab")
			(effects
				(font
					(size 1.27 1.27)
				)
			)
		)
		(duplicate_pad_numbers_are_jumpers no)
		(fp_line
			(start 0.7874 -0.4064)
			(end 0.7874 0.4064)
			(stroke
				(width 0.1524)
				(type default)
			)
			(layer "F.SilkS")
		)
		(fp_line
			(start -0.7874 -0.4064)
			(end 0.7874 -0.4064)
			(stroke
				(width 0.1524)
				(type default)
			)
			(layer "F.SilkS")
		)
		(fp_line
			(start 0.7874 0.4064)
			(end -0.7874 0.4064)
			(stroke
				(width 0.1524)
				(type default)
			)
			(layer "F.SilkS")
		)
		(fp_line
			(start -0.7874 0.4064)
			(end -0.7874 -0.4064)
			(stroke
				(width 0.1524)
				(type default)
			)
			(layer "F.SilkS")
		)
		(fp_line
			(start -0.12065 -0.305054)
			(end -0.12065 -0.2794)
			(stroke
				(width 0.1)
				(type default)
			)
			(layer "F.Fab")
		)
		(fp_line
			(start -0.67945 -0.305054)
			(end -0.12065 -0.305054)
			(stroke
				(width 0.1)
				(type default)
			)
			(layer "F.Fab")
		)
		(fp_line
			(start 0.67945 -0.3048)
			(end 0.67945 0.3048)
			(stroke
				(width 0.1)
				(type default)
			)
			(layer "F.Fab")
		)
		(fp_line
			(start 0.12065 -0.3048)
			(end 0.67945 -0.3048)
			(stroke
				(width 0.1)
				(type default)
			)
			(layer "F.Fab")
		)
		(fp_line
			(start 0.12065 -0.2794)
			(end 0.12065 -0.3048)
			(stroke
				(width 0.1)
				(type default)
			)
			(layer "F.Fab")
		)
		(fp_line
			(start -0.12065 -0.2794)
			(end 0.12065 -0.2794)
			(stroke
				(width 0.1)
				(type default)
			)
			(layer "F.Fab")
		)
		(fp_line
			(start 0.120396 0.2794)
			(end -0.12065 0.2794)
			(stroke
				(width 0.1)
				(type default)
			)
			(layer "F.Fab")
		)
		(fp_line
			(start -0.12065 0.2794)
			(end -0.12065 0.3048)
			(stroke
				(width 0.1)
				(type default)
			)
			(layer "F.Fab")
		)
		(fp_line
			(start 0.67945 0.3048)
			(end 0.120396 0.3048)
			(stroke
				(width 0.1)
				(type default)
			)
			(layer "F.Fab")
		)
		(fp_line
			(start 0.120396 0.3048)
			(end 0.120396 0.2794)
			(stroke
				(width 0.1)
				(type default)
			)
			(layer "F.Fab")
		)
		(fp_line
			(start -0.12065 0.3048)
			(end -0.67945 0.3048)
			(stroke
				(width 0.1)
				(type default)
			)
			(layer "F.Fab")
		)
		(fp_line
			(start -0.67945 0.3048)
			(end -0.67945 -0.305054)
			(stroke
				(width 0.1)
				(type default)
			)
			(layer "F.Fab")
		)
		(pad "1" smd circle
			(at -0.40005 0 90)
			(size 0 0)
			(layers "F.Cu" "F.Mask" "F.Paste")
			(net "SMB_FAN4_R_SDA")
		)
		(pad "2" smd circle
			(at 0.40005 0 90)
			(size 0 0)
			(layers "F.Cu" "F.Mask" "F.Paste")
			(net "SMB_FAN4_SDA")
		)
	)
	(footprint ""
		(layer "F.Cu")
		(at 14.0589 -129.794 180)
		(property "Reference" "R5591"
			(at 0 0 180)
			(layer "F.SilkS")
			(hide yes)
			(effects
				(font
					(size 1.27 1.27)
				)
			)
		)
		(property "Value" ""
			(at 0 0 180)
			(layer "F.Fab")
			(effects
				(font
					(size 1.27 1.27)
				)
			)
		)
		(duplicate_pad_numbers_are_jumpers no)
		(fp_line
			(start 0.7874 0.4064)
			(end -0.7874 0.4064)
			(stroke
				(width 0.1524)
				(type default)
			)
			(layer "F.SilkS")
		)
		(fp_line
			(start 0.7874 -0.4064)
			(end 0.7874 0.4064)
			(stroke
				(width 0.1524)
				(type default)
			)
			(layer "F.SilkS")
		)
		(fp_line
			(start -0.7874 0.4064)
			(end -0.7874 -0.4064)
			(stroke
				(width 0.1524)
				(type default)
			)
			(layer "F.SilkS")
		)
		(fp_line
			(start -0.7874 -0.4064)
			(end 0.7874 -0.4064)
			(stroke
				(width 0.1524)
				(type default)
			)
			(layer "F.SilkS")
		)
		(fp_line
			(start 0.67945 0.3048)
			(end 0.120396 0.3048)
			(stroke
				(width 0.1)
				(type default)
			)
			(layer "F.Fab")
		)
		(fp_line
			(start 0.67945 -0.3048)
			(end 0.67945 0.3048)
			(stroke
				(width 0.1)
				(type default)
			)
			(layer "F.Fab")
		)
		(fp_line
			(start 0.12065 -0.2794)
			(end 0.12065 -0.3048)
			(stroke
				(width 0.1)
				(type default)
			)
			(layer "F.Fab")
		)
		(fp_line
			(start 0.12065 -0.3048)
			(end 0.67945 -0.3048)
			(stroke
				(width 0.1)
				(type default)
			)
			(layer "F.Fab")
		)
		(fp_line
			(start 0.120396 0.3048)
			(end 0.120396 0.2794)
			(stroke
				(width 0.1)
				(type default)
			)
			(layer "F.Fab")
		)
		(fp_line
			(start 0.120396 0.2794)
			(end -0.12065 0.2794)
			(stroke
				(width 0.1)
				(type default)
			)
			(layer "F.Fab")
		)
		(fp_line
			(start -0.12065 0.3048)
			(end -0.67945 0.3048)
			(stroke
				(width 0.1)
				(type default)
			)
			(layer "F.Fab")
		)
		(fp_line
			(start -0.12065 0.2794)
			(end -0.12065 0.3048)
			(stroke
				(width 0.1)
				(type default)
			)
			(layer "F.Fab")
		)
		(fp_line
			(start -0.12065 -0.2794)
			(end 0.12065 -0.2794)
			(stroke
				(width 0.1)
				(type default)
			)
			(layer "F.Fab")
		)
		(fp_line
			(start -0.12065 -0.305054)
			(end -0.12065 -0.2794)
			(stroke
				(width 0.1)
				(type default)
			)
			(layer "F.Fab")
		)
		(fp_line
			(start -0.67945 0.3048)
			(end -0.67945 -0.305054)
			(stroke
				(width 0.1)
				(type default)
			)
			(layer "F.Fab")
		)
		(fp_line
			(start -0.67945 -0.305054)
			(end -0.12065 -0.305054)
			(stroke
				(width 0.1)
				(type default)
			)
			(layer "F.Fab")
		)
		(pad "1" smd rect
			(at -0.40005 0)
			(size 0.4572 0.508)
			(layers "F.Cu" "F.Mask" "F.Paste")
			(net "FAN_6_PWM")
		)
		(pad "2" smd rect
			(at 0.40005 0)
			(size 0.4572 0.508)
			(layers "F.Cu" "F.Mask" "F.Paste")
			(net "FAN_6_PWM_R2")
		)
	)
	(footprint ""
		(layer "F.Cu")
		(at 22.479 -208.788 90)
		(property "Reference" "U62"
			(at 0.635 -1.87833 90)
			(unlocked yes)
			(layer "F.SilkS")
			(effects
				(font
					(size 0.7874 0.5842)
					(thickness 0.1524)
				)
				(justify left)
			)
		)
		(property "Value" ""
			(at 0 0 90)
			(layer "F.Fab")
			(effects
				(font
					(size 1.27 1.27)
				)
			)
		)
		(duplicate_pad_numbers_are_jumpers no)
		(fp_line
			(start 1.33096 -1.100074)
			(end 1.33096 1.100074)
			(stroke
				(width 0.1524)
				(type default)
			)
			(layer "F.SilkS")
		)
		(fp_line
			(start 0.381 -1.100074)
			(end 1.33096 -1.100074)
			(stroke
				(width 0.1524)
				(type default)
			)
			(layer "F.SilkS")
		)
		(fp_line
			(start -0.381 -1.100074)
			(end 0 -0.649986)
			(stroke
				(width 0.1524)
				(type default)
			)
			(layer "F.SilkS")
		)
		(fp_line
			(start -1.33096 -1.100074)
			(end -0.381 -1.100074)
			(stroke
				(width 0.1524)
				(type default)
			)
			(layer "F.SilkS")
		)
		(fp_line
			(start 0 -0.649986)
			(end 0.381 -1.100074)
			(stroke
				(width 0.1524)
				(type default)
			)
			(layer "F.SilkS")
		)
		(fp_line
			(start 1.33096 1.100074)
			(end -1.33096 1.100074)
			(stroke
				(width 0.1524)
				(type default)
			)
			(layer "F.SilkS")
		)
		(fp_line
			(start -1.33096 1.100074)
			(end -1.33096 -1.100074)
			(stroke
				(width 0.1524)
				(type default)
			)
			(layer "F.SilkS")
		)
		(fp_poly
			(pts
				(xy -0.748538 -2.082292) (xy -1.256538 -2.082292) (xy -1.002538 -1.320292)
			)
			(stroke
				(width 0)
				(type default)
			)
			(fill yes)
			(layer "F.SilkS")
		)
		(fp_line
			(start 0.674878 -1.100074)
			(end 0.674878 1.100074)
			(stroke
				(width 0.1)
				(type default)
			)
			(layer "F.Fab")
		)
		(fp_line
			(start -0.674878 -1.100074)
			(end 0.674878 -1.100074)
			(stroke
				(width 0.1)
				(type default)
			)
			(layer "F.Fab")
		)
		(fp_line
			(start 0.674878 1.100074)
			(end -0.674878 1.100074)
			(stroke
				(width 0.1)
				(type default)
			)
			(layer "F.Fab")
		)
		(fp_line
			(start -0.674878 1.100074)
			(end -0.674878 -1.100074)
			(stroke
				(width 0.1)
				(type default)
			)
			(layer "F.Fab")
		)
		(fp_poly
			(pts
				(xy -2.209292 -0.902462) (xy -2.209292 -0.394462) (xy -1.447292 -0.648462)
			)
			(stroke
				(width 0)
				(type default)
			)
			(fill yes)
			(layer "F.Fab")
		)
		(pad "1" smd rect
			(at -0.94996 -0.649986 180)
			(size 0.4064 0.508)
			(layers "F.Cu" "F.Mask" "F.Paste")
			(net "NC_U62_P1")
		)
		(pad "2" smd rect
			(at -0.94996 0 180)
			(size 0.4064 0.508)
			(layers "F.Cu" "F.Mask" "F.Paste")
			(net "FAN_1_PWM")
		)
		(pad "3" smd rect
			(at -0.94996 0.649986 180)
			(size 0.4064 0.508)
			(layers "F.Cu" "F.Mask" "F.Paste")
			(net "GND")
		)
		(pad "4" smd rect
			(at 0.94996 0.649986 180)
			(size 0.4064 0.508)
			(layers "F.Cu" "F.Mask" "F.Paste")
			(net "FAN_1_PWM_BUF")
		)
		(pad "5" smd rect
			(at 0.94996 -0.649986 180)
			(size 0.4064 0.508)
			(layers "F.Cu" "F.Mask" "F.Paste")
			(net "P3V3_AUX")
		)
	)
	(footprint ""
		(layer "F.Cu")
		(at 17.018 -20.574 180)
		(property "Reference" "R5539"
			(at 0 0 180)
			(layer "F.SilkS")
			(hide yes)
			(effects
				(font
					(size 1.27 1.27)
				)
			)
		)
		(property "Value" ""
			(at 0 0 180)
			(layer "F.Fab")
			(effects
				(font
					(size 1.27 1.27)
				)
			)
		)
		(duplicate_pad_numbers_are_jumpers no)
		(fp_line
			(start 0.7874 0.4064)
			(end -0.7874 0.4064)
			(stroke
				(width 0.1524)
				(type default)
			)
			(layer "F.SilkS")
		)
		(fp_line
			(start 0.7874 -0.4064)
			(end 0.7874 0.4064)
			(stroke
				(width 0.1524)
				(type default)
			)
			(layer "F.SilkS")
		)
		(fp_line
			(start -0.7874 0.4064)
			(end -0.7874 -0.4064)
			(stroke
				(width 0.1524)
				(type default)
			)
			(layer "F.SilkS")
		)
		(fp_line
			(start -0.7874 -0.4064)
			(end 0.7874 -0.4064)
			(stroke
				(width 0.1524)
				(type default)
			)
			(layer "F.SilkS")
		)
		(fp_line
			(start 0.67945 0.3048)
			(end 0.120396 0.3048)
			(stroke
				(width 0.1)
				(type default)
			)
			(layer "F.Fab")
		)
		(fp_line
			(start 0.67945 -0.3048)
			(end 0.67945 0.3048)
			(stroke
				(width 0.1)
				(type default)
			)
			(layer "F.Fab")
		)
		(fp_line
			(start 0.12065 -0.2794)
			(end 0.12065 -0.3048)
			(stroke
				(width 0.1)
				(type default)
			)
			(layer "F.Fab")
		)
		(fp_line
			(start 0.12065 -0.3048)
			(end 0.67945 -0.3048)
			(stroke
				(width 0.1)
				(type default)
			)
			(layer "F.Fab")
		)
		(fp_line
			(start 0.120396 0.3048)
			(end 0.120396 0.2794)
			(stroke
				(width 0.1)
				(type default)
			)
			(layer "F.Fab")
		)
		(fp_line
			(start 0.120396 0.2794)
			(end -0.12065 0.2794)
			(stroke
				(width 0.1)
				(type default)
			)
			(layer "F.Fab")
		)
		(fp_line
			(start -0.12065 0.3048)
			(end -0.67945 0.3048)
			(stroke
				(width 0.1)
				(type default)
			)
			(layer "F.Fab")
		)
		(fp_line
			(start -0.12065 0.2794)
			(end -0.12065 0.3048)
			(stroke
				(width 0.1)
				(type default)
			)
			(layer "F.Fab")
		)
		(fp_line
			(start -0.12065 -0.2794)
			(end 0.12065 -0.2794)
			(stroke
				(width 0.1)
				(type default)
			)
			(layer "F.Fab")
		)
		(fp_line
			(start -0.12065 -0.305054)
			(end -0.12065 -0.2794)
			(stroke
				(width 0.1)
				(type default)
			)
			(layer "F.Fab")
		)
		(fp_line
			(start -0.67945 0.3048)
			(end -0.67945 -0.305054)
			(stroke
				(width 0.1)
				(type default)
			)
			(layer "F.Fab")
		)
		(fp_line
			(start -0.67945 -0.305054)
			(end -0.12065 -0.305054)
			(stroke
				(width 0.1)
				(type default)
			)
			(layer "F.Fab")
		)
		(pad "1" smd rect
			(at -0.40005 0)
			(size 0.4572 0.508)
			(layers "F.Cu" "F.Mask" "F.Paste")
			(net "P12V_LED_FAN4")
		)
		(pad "2" smd rect
			(at 0.40005 0)
			(size 0.4572 0.508)
			(layers "F.Cu" "F.Mask" "F.Paste")
			(net "FAN_4_FAIL_LED_R_N")
		)
	)
	(footprint ""
		(layer "F.Cu")
		(at 17.399 -203.073 180)
		(property "Reference" "U365"
			(at 1.397 -1.80467 0)
			(unlocked yes)
			(layer "F.SilkS")
			(effects
				(font
					(size 0.7874 0.5842)
					(thickness 0.1524)
				)
				(justify left)
			)
		)
		(property "Value" ""
			(at 0 0 180)
			(layer "F.Fab")
			(effects
				(font
					(size 1.27 1.27)
				)
			)
		)
		(duplicate_pad_numbers_are_jumpers no)
		(fp_line
			(start 1.335278 1.100074)
			(end 1.335278 -1.100074)
			(stroke
				(width 0.1524)
				(type default)
			)
			(layer "F.SilkS")
		)
		(fp_line
			(start 1.335278 -1.100074)
			(end -1.335278 -1.100074)
			(stroke
				(width 0.1524)
				(type default)
			)
			(layer "F.SilkS")
		)
		(fp_line
			(start -1.335278 1.100074)
			(end 1.335278 1.100074)
			(stroke
				(width 0.1524)
				(type default)
			)
			(layer "F.SilkS")
		)
		(fp_line
			(start -1.335278 -1.100074)
			(end -1.335278 1.100074)
			(stroke
				(width 0.1524)
				(type default)
			)
			(layer "F.SilkS")
		)
		(fp_line
			(start 0.674878 1.100074)
			(end 0.674878 -1.100074)
			(stroke
				(width 0.1)
				(type default)
			)
			(layer "F.Fab")
		)
		(fp_line
			(start 0.674878 -1.100074)
			(end -0.674878 -1.100074)
			(stroke
				(width 0.1)
				(type default)
			)
			(layer "F.Fab")
		)
		(fp_line
			(start -0.674878 1.100074)
			(end 0.674878 1.100074)
			(stroke
				(width 0.1)
				(type default)
			)
			(layer "F.Fab")
		)
		(fp_line
			(start -0.674878 -1.100074)
			(end -0.674878 1.100074)
			(stroke
				(width 0.1)
				(type default)
			)
			(layer "F.Fab")
		)
		(pad "D" smd rect
			(at 0.8001 0 90)
			(size 0.6096 0.8128)
			(layers "F.Cu" "F.Mask" "F.Paste")
			(net "FAN_6_FAIL_LED_R_N")
		)
		(pad "G" smd rect
			(at -0.8001 -0.649986 90)
			(size 0.6096 0.8128)
			(layers "F.Cu" "F.Mask" "F.Paste")
			(net "FAN_6_FAIL_R_LED")
		)
		(pad "S" smd rect
			(at -0.8001 0.649986 90)
			(size 0.6096 0.8128)
			(layers "F.Cu" "F.Mask" "F.Paste")
			(net "GND")
		)
	)
	(footprint ""
		(layer "F.Cu")
		(at 3.429 -126.111)
		(property "Reference" "C2026"
			(at 0 0 0)
			(layer "F.SilkS")
			(hide yes)
			(effects
				(font
					(size 1.27 1.27)
				)
			)
		)
		(property "Value" ""
			(at 0 0 0)
			(layer "F.Fab")
			(effects
				(font
					(size 1.27 1.27)
				)
			)
		)
		(duplicate_pad_numbers_are_jumpers no)
		(fp_line
			(start -1.524 -0.762)
			(end 1.524 -0.762)
			(stroke
				(width 0.1524)
				(type default)
			)
			(layer "F.SilkS")
		)
		(fp_line
			(start -1.524 0.762)
			(end -1.524 -0.762)
			(stroke
				(width 0.1524)
				(type default)
			)
			(layer "F.SilkS")
		)
		(fp_line
			(start 1.524 -0.762)
			(end 1.524 0.762)
			(stroke
				(width 0.1524)
				(type default)
			)
			(layer "F.SilkS")
		)
		(fp_line
			(start 1.524 0.762)
			(end -1.524 0.762)
			(stroke
				(width 0.1524)
				(type default)
			)
			(layer "F.SilkS")
		)
		(fp_line
			(start -1.1049 -0.724916)
			(end -1.1049 0.724916)
			(stroke
				(width 0.1)
				(type default)
			)
			(layer "F.Fab")
		)
		(fp_line
			(start -1.1049 0.724916)
			(end 1.1049 0.724916)
			(stroke
				(width 0.1)
				(type default)
			)
			(layer "F.Fab")
		)
		(fp_line
			(start 1.1049 -0.724916)
			(end -1.1049 -0.724916)
			(stroke
				(width 0.1)
				(type default)
			)
			(layer "F.Fab")
		)
		(fp_line
			(start 1.1049 0.724916)
			(end 1.1049 -0.724916)
			(stroke
				(width 0.1)
				(type default)
			)
			(layer "F.Fab")
		)
		(pad "1" smd rect
			(at -0.889 0 180)
			(size 1.016 1.27)
			(layers "F.Cu" "F.Mask" "F.Paste")
			(net "P12V_LED_FAN5")
		)
		(pad "2" smd rect
			(at 0.889 0 180)
			(size 1.016 1.27)
			(layers "F.Cu" "F.Mask" "F.Paste")
			(net "GND")
		)
	)
	(footprint ""
		(layer "F.Cu")
		(at 18.669 -288.036 180)
		(property "Reference" "R5320"
			(at 0 0 180)
			(layer "F.SilkS")
			(hide yes)
			(effects
				(font
					(size 1.27 1.27)
				)
			)
		)
		(property "Value" ""
			(at 0 0 180)
			(layer "F.Fab")
			(effects
				(font
					(size 1.27 1.27)
				)
			)
		)
		(duplicate_pad_numbers_are_jumpers no)
		(fp_line
			(start 1.2954 0.5842)
			(end -1.2954 0.5842)
			(stroke
				(width 0.1524)
				(type default)
			)
			(layer "F.SilkS")
		)
		(fp_line
			(start 1.2954 -0.5842)
			(end 1.2954 0.5842)
			(stroke
				(width 0.1524)
				(type default)
			)
			(layer "F.SilkS")
		)
		(fp_line
			(start -1.2954 0.5842)
			(end -1.2954 -0.5842)
			(stroke
				(width 0.1524)
				(type default)
			)
			(layer "F.SilkS")
		)
		(fp_line
			(start -1.2954 -0.5842)
			(end 1.2954 -0.5842)
			(stroke
				(width 0.1524)
				(type default)
			)
			(layer "F.SilkS")
		)
		(fp_line
			(start 1.1938 0.4064)
			(end 0.8636 0.4064)
			(stroke
				(width 0.1)
				(type default)
			)
			(layer "F.Fab")
		)
		(fp_line
			(start 1.1938 -0.406654)
			(end 1.1938 0.4064)
			(stroke
				(width 0.1)
				(type default)
			)
			(layer "F.Fab")
		)
		(fp_line
			(start 0.8636 0.4572)
			(end -0.8636 0.4572)
			(stroke
				(width 0.1)
				(type default)
			)
			(layer "F.Fab")
		)
		(fp_line
			(start 0.8636 0.4064)
			(end 0.8636 0.4572)
			(stroke
				(width 0.1)
				(type default)
			)
			(layer "F.Fab")
		)
		(fp_line
			(start 0.8636 -0.406654)
			(end 1.1938 -0.406654)
			(stroke
				(width 0.1)
				(type default)
			)
			(layer "F.Fab")
		)
		(fp_line
			(start 0.8636 -0.4572)
			(end 0.8636 -0.406654)
			(stroke
				(width 0.1)
				(type default)
			)
			(layer "F.Fab")
		)
		(fp_line
			(start -0.8636 0.4572)
			(end -0.8636 0.4318)
			(stroke
				(width 0.1)
				(type default)
			)
			(layer "F.Fab")
		)
		(fp_line
			(start -0.8636 0.4318)
			(end -0.8636 0.4064)
			(stroke
				(width 0.1)
				(type default)
			)
			(layer "F.Fab")
		)
		(fp_line
			(start -0.8636 0.4064)
			(end -1.1938 0.4064)
			(stroke
				(width 0.1)
				(type default)
			)
			(layer "F.Fab")
		)
		(fp_line
			(start -0.8636 -0.406654)
			(end -0.8636 -0.4572)
			(stroke
				(width 0.1)
				(type default)
			)
			(layer "F.Fab")
		)
		(fp_line
			(start -0.8636 -0.4572)
			(end 0.8636 -0.4572)
			(stroke
				(width 0.1)
				(type default)
			)
			(layer "F.Fab")
		)
		(fp_line
			(start -1.1938 0.4064)
			(end -1.1938 -0.406654)
			(stroke
				(width 0.1)
				(type default)
			)
			(layer "F.Fab")
		)
		(fp_line
			(start -1.1938 -0.406654)
			(end -0.8636 -0.406654)
			(stroke
				(width 0.1)
				(type default)
			)
			(layer "F.Fab")
		)
		(pad "1" smd rect
			(at -0.7366 0 90)
			(size 0.7112 0.8128)
			(layers "F.Cu" "F.Mask" "F.Paste")
			(net "P52V_FAN_7")
		)
		(pad "2" smd rect
			(at 0.7366 0 90)
			(size 0.7112 0.8128)
			(layers "F.Cu" "F.Mask" "F.Paste")
			(net "FAN_7_TACH_IL_R")
		)
	)
	(footprint ""
		(layer "F.Cu")
		(at 14.361922 -291.5031)
		(property "Reference" "R5241"
			(at 0 0 0)
			(layer "F.SilkS")
			(hide yes)
			(effects
				(font
					(size 1.27 1.27)
				)
			)
		)
		(property "Value" ""
			(at 0 0 0)
			(layer "F.Fab")
			(effects
				(font
					(size 1.27 1.27)
				)
			)
		)
		(duplicate_pad_numbers_are_jumpers no)
		(fp_line
			(start -0.7874 -0.4064)
			(end 0.7874 -0.4064)
			(stroke
				(width 0.1524)
				(type default)
			)
			(layer "F.SilkS")
		)
		(fp_line
			(start -0.7874 0.4064)
			(end -0.7874 -0.4064)
			(stroke
				(width 0.1524)
				(type default)
			)
			(layer "F.SilkS")
		)
		(fp_line
			(start 0.7874 -0.4064)
			(end 0.7874 0.4064)
			(stroke
				(width 0.1524)
				(type default)
			)
			(layer "F.SilkS")
		)
		(fp_line
			(start 0.7874 0.4064)
			(end -0.7874 0.4064)
			(stroke
				(width 0.1524)
				(type default)
			)
			(layer "F.SilkS")
		)
		(fp_line
			(start -0.67945 -0.305054)
			(end -0.12065 -0.305054)
			(stroke
				(width 0.1)
				(type default)
			)
			(layer "F.Fab")
		)
		(fp_line
			(start -0.67945 0.3048)
			(end -0.67945 -0.305054)
			(stroke
				(width 0.1)
				(type default)
			)
			(layer "F.Fab")
		)
		(fp_line
			(start -0.12065 -0.305054)
			(end -0.12065 -0.2794)
			(stroke
				(width 0.1)
				(type default)
			)
			(layer "F.Fab")
		)
		(fp_line
			(start -0.12065 -0.2794)
			(end 0.12065 -0.2794)
			(stroke
				(width 0.1)
				(type default)
			)
			(layer "F.Fab")
		)
		(fp_line
			(start -0.12065 0.2794)
			(end -0.12065 0.3048)
			(stroke
				(width 0.1)
				(type default)
			)
			(layer "F.Fab")
		)
		(fp_line
			(start -0.12065 0.3048)
			(end -0.67945 0.3048)
			(stroke
				(width 0.1)
				(type default)
			)
			(layer "F.Fab")
		)
		(fp_line
			(start 0.120396 0.2794)
			(end -0.12065 0.2794)
			(stroke
				(width 0.1)
				(type default)
			)
			(layer "F.Fab")
		)
		(fp_line
			(start 0.120396 0.3048)
			(end 0.120396 0.2794)
			(stroke
				(width 0.1)
				(type default)
			)
			(layer "F.Fab")
		)
		(fp_line
			(start 0.12065 -0.3048)
			(end 0.67945 -0.3048)
			(stroke
				(width 0.1)
				(type default)
			)
			(layer "F.Fab")
		)
		(fp_line
			(start 0.12065 -0.2794)
			(end 0.12065 -0.3048)
			(stroke
				(width 0.1)
				(type default)
			)
			(layer "F.Fab")
		)
		(fp_line
			(start 0.67945 -0.3048)
			(end 0.67945 0.3048)
			(stroke
				(width 0.1)
				(type default)
			)
			(layer "F.Fab")
		)
		(fp_line
			(start 0.67945 0.3048)
			(end 0.120396 0.3048)
			(stroke
				(width 0.1)
				(type default)
			)
			(layer "F.Fab")
		)
		(pad "1" smd circle
			(at -0.40005 0)
			(size 0 0)
			(layers "F.Cu" "F.Mask" "F.Paste")
			(net "FAN_7_PWM_IL_R")
		)
		(pad "2" smd circle
			(at 0.40005 0)
			(size 0 0)
			(layers "F.Cu" "F.Mask" "F.Paste")
			(net "FAN_7_PWM_IL")
		)
	)
	(footprint ""
		(layer "F.Cu")
		(at 43.561 -174.879)
		(property "Reference" "R5099"
			(at 0 0 0)
			(layer "F.SilkS")
			(hide yes)
			(effects
				(font
					(size 1.27 1.27)
				)
			)
		)
		(property "Value" ""
			(at 0 0 0)
			(layer "F.Fab")
			(effects
				(font
					(size 1.27 1.27)
				)
			)
		)
		(duplicate_pad_numbers_are_jumpers no)
		(fp_line
			(start -0.7874 -0.4064)
			(end 0.7874 -0.4064)
			(stroke
				(width 0.1524)
				(type default)
			)
			(layer "F.SilkS")
		)
		(fp_line
			(start -0.7874 0.4064)
			(end -0.7874 -0.4064)
			(stroke
				(width 0.1524)
				(type default)
			)
			(layer "F.SilkS")
		)
		(fp_line
			(start 0.7874 -0.4064)
			(end 0.7874 0.4064)
			(stroke
				(width 0.1524)
				(type default)
			)
			(layer "F.SilkS")
		)
		(fp_line
			(start 0.7874 0.4064)
			(end -0.7874 0.4064)
			(stroke
				(width 0.1524)
				(type default)
			)
			(layer "F.SilkS")
		)
		(fp_line
			(start -0.67945 -0.305054)
			(end -0.12065 -0.305054)
			(stroke
				(width 0.1)
				(type default)
			)
			(layer "F.Fab")
		)
		(fp_line
			(start -0.67945 0.3048)
			(end -0.67945 -0.305054)
			(stroke
				(width 0.1)
				(type default)
			)
			(layer "F.Fab")
		)
		(fp_line
			(start -0.12065 -0.305054)
			(end -0.12065 -0.2794)
			(stroke
				(width 0.1)
				(type default)
			)
			(layer "F.Fab")
		)
		(fp_line
			(start -0.12065 -0.2794)
			(end 0.12065 -0.2794)
			(stroke
				(width 0.1)
				(type default)
			)
			(layer "F.Fab")
		)
		(fp_line
			(start -0.12065 0.2794)
			(end -0.12065 0.3048)
			(stroke
				(width 0.1)
				(type default)
			)
			(layer "F.Fab")
		)
		(fp_line
			(start -0.12065 0.3048)
			(end -0.67945 0.3048)
			(stroke
				(width 0.1)
				(type default)
			)
			(layer "F.Fab")
		)
		(fp_line
			(start 0.120396 0.2794)
			(end -0.12065 0.2794)
			(stroke
				(width 0.1)
				(type default)
			)
			(layer "F.Fab")
		)
		(fp_line
			(start 0.120396 0.3048)
			(end 0.120396 0.2794)
			(stroke
				(width 0.1)
				(type default)
			)
			(layer "F.Fab")
		)
		(fp_line
			(start 0.12065 -0.3048)
			(end 0.67945 -0.3048)
			(stroke
				(width 0.1)
				(type default)
			)
			(layer "F.Fab")
		)
		(fp_line
			(start 0.12065 -0.2794)
			(end 0.12065 -0.3048)
			(stroke
				(width 0.1)
				(type default)
			)
			(layer "F.Fab")
		)
		(fp_line
			(start 0.67945 -0.3048)
			(end 0.67945 0.3048)
			(stroke
				(width 0.1)
				(type default)
			)
			(layer "F.Fab")
		)
		(fp_line
			(start 0.67945 0.3048)
			(end 0.120396 0.3048)
			(stroke
				(width 0.1)
				(type default)
			)
			(layer "F.Fab")
		)
		(pad "1" smd circle
			(at -0.40005 0)
			(size 0 0)
			(layers "F.Cu" "F.Mask" "F.Paste")
			(net "FAN_2_FAIL_LED")
		)
		(pad "2" smd circle
			(at 0.40005 0)
			(size 0 0)
			(layers "F.Cu" "F.Mask" "F.Paste")
			(net "FAN_2_FAIL_R_LED")
		)
	)
	(footprint ""
		(layer "F.Cu")
		(at 4.191 -170.815 180)
		(property "Reference" "R4859"
			(at 0 0 180)
			(layer "F.SilkS")
			(hide yes)
			(effects
				(font
					(size 1.27 1.27)
				)
			)
		)
		(property "Value" ""
			(at 0 0 180)
			(layer "F.Fab")
			(effects
				(font
					(size 1.27 1.27)
				)
			)
		)
		(duplicate_pad_numbers_are_jumpers no)
		(fp_line
			(start 0.7874 0.4064)
			(end -0.7874 0.4064)
			(stroke
				(width 0.1524)
				(type default)
			)
			(layer "F.SilkS")
		)
		(fp_line
			(start 0.7874 -0.4064)
			(end 0.7874 0.4064)
			(stroke
				(width 0.1524)
				(type default)
			)
			(layer "F.SilkS")
		)
		(fp_line
			(start -0.7874 0.4064)
			(end -0.7874 -0.4064)
			(stroke
				(width 0.1524)
				(type default)
			)
			(layer "F.SilkS")
		)
		(fp_line
			(start -0.7874 -0.4064)
			(end 0.7874 -0.4064)
			(stroke
				(width 0.1524)
				(type default)
			)
			(layer "F.SilkS")
		)
		(fp_line
			(start 0.67945 0.3048)
			(end 0.120396 0.3048)
			(stroke
				(width 0.1)
				(type default)
			)
			(layer "F.Fab")
		)
		(fp_line
			(start 0.67945 -0.3048)
			(end 0.67945 0.3048)
			(stroke
				(width 0.1)
				(type default)
			)
			(layer "F.Fab")
		)
		(fp_line
			(start 0.12065 -0.2794)
			(end 0.12065 -0.3048)
			(stroke
				(width 0.1)
				(type default)
			)
			(layer "F.Fab")
		)
		(fp_line
			(start 0.12065 -0.3048)
			(end 0.67945 -0.3048)
			(stroke
				(width 0.1)
				(type default)
			)
			(layer "F.Fab")
		)
		(fp_line
			(start 0.120396 0.3048)
			(end 0.120396 0.2794)
			(stroke
				(width 0.1)
				(type default)
			)
			(layer "F.Fab")
		)
		(fp_line
			(start 0.120396 0.2794)
			(end -0.12065 0.2794)
			(stroke
				(width 0.1)
				(type default)
			)
			(layer "F.Fab")
		)
		(fp_line
			(start -0.12065 0.3048)
			(end -0.67945 0.3048)
			(stroke
				(width 0.1)
				(type default)
			)
			(layer "F.Fab")
		)
		(fp_line
			(start -0.12065 0.2794)
			(end -0.12065 0.3048)
			(stroke
				(width 0.1)
				(type default)
			)
			(layer "F.Fab")
		)
		(fp_line
			(start -0.12065 -0.2794)
			(end 0.12065 -0.2794)
			(stroke
				(width 0.1)
				(type default)
			)
			(layer "F.Fab")
		)
		(fp_line
			(start -0.12065 -0.305054)
			(end -0.12065 -0.2794)
			(stroke
				(width 0.1)
				(type default)
			)
			(layer "F.Fab")
		)
		(fp_line
			(start -0.67945 0.3048)
			(end -0.67945 -0.305054)
			(stroke
				(width 0.1)
				(type default)
			)
			(layer "F.Fab")
		)
		(fp_line
			(start -0.67945 -0.305054)
			(end -0.12065 -0.305054)
			(stroke
				(width 0.1)
				(type default)
			)
			(layer "F.Fab")
		)
		(pad "1" smd circle
			(at -0.40005 0 180)
			(size 0 0)
			(layers "F.Cu" "F.Mask" "F.Paste")
			(net "FAN_5_PRSNT_BUF_R_N")
		)
		(pad "2" smd circle
			(at 0.40005 0 180)
			(size 0 0)
			(layers "F.Cu" "F.Mask" "F.Paste")
			(net "FAN_5_PRSNT_BUF_N")
		)
	)
	(footprint ""
		(layer "F.Cu")
		(at 13.335 -173.99 180)
		(property "Reference" "R5506"
			(at 0 0 180)
			(layer "F.SilkS")
			(hide yes)
			(effects
				(font
					(size 1.27 1.27)
				)
			)
		)
		(property "Value" ""
			(at 0 0 180)
			(layer "F.Fab")
			(effects
				(font
					(size 1.27 1.27)
				)
			)
		)
		(duplicate_pad_numbers_are_jumpers no)
		(fp_line
			(start 0.7874 0.4064)
			(end -0.7874 0.4064)
			(stroke
				(width 0.1524)
				(type default)
			)
			(layer "F.SilkS")
		)
		(fp_line
			(start 0.7874 -0.4064)
			(end 0.7874 0.4064)
			(stroke
				(width 0.1524)
				(type default)
			)
			(layer "F.SilkS")
		)
		(fp_line
			(start -0.7874 0.4064)
			(end -0.7874 -0.4064)
			(stroke
				(width 0.1524)
				(type default)
			)
			(layer "F.SilkS")
		)
		(fp_line
			(start -0.7874 -0.4064)
			(end 0.7874 -0.4064)
			(stroke
				(width 0.1524)
				(type default)
			)
			(layer "F.SilkS")
		)
		(fp_line
			(start 0.67945 0.3048)
			(end 0.120396 0.3048)
			(stroke
				(width 0.1)
				(type default)
			)
			(layer "F.Fab")
		)
		(fp_line
			(start 0.67945 -0.3048)
			(end 0.67945 0.3048)
			(stroke
				(width 0.1)
				(type default)
			)
			(layer "F.Fab")
		)
		(fp_line
			(start 0.12065 -0.2794)
			(end 0.12065 -0.3048)
			(stroke
				(width 0.1)
				(type default)
			)
			(layer "F.Fab")
		)
		(fp_line
			(start 0.12065 -0.3048)
			(end 0.67945 -0.3048)
			(stroke
				(width 0.1)
				(type default)
			)
			(layer "F.Fab")
		)
		(fp_line
			(start 0.120396 0.3048)
			(end 0.120396 0.2794)
			(stroke
				(width 0.1)
				(type default)
			)
			(layer "F.Fab")
		)
		(fp_line
			(start 0.120396 0.2794)
			(end -0.12065 0.2794)
			(stroke
				(width 0.1)
				(type default)
			)
			(layer "F.Fab")
		)
		(fp_line
			(start -0.12065 0.3048)
			(end -0.67945 0.3048)
			(stroke
				(width 0.1)
				(type default)
			)
			(layer "F.Fab")
		)
		(fp_line
			(start -0.12065 0.2794)
			(end -0.12065 0.3048)
			(stroke
				(width 0.1)
				(type default)
			)
			(layer "F.Fab")
		)
		(fp_line
			(start -0.12065 -0.2794)
			(end 0.12065 -0.2794)
			(stroke
				(width 0.1)
				(type default)
			)
			(layer "F.Fab")
		)
		(fp_line
			(start -0.12065 -0.305054)
			(end -0.12065 -0.2794)
			(stroke
				(width 0.1)
				(type default)
			)
			(layer "F.Fab")
		)
		(fp_line
			(start -0.67945 0.3048)
			(end -0.67945 -0.305054)
			(stroke
				(width 0.1)
				(type default)
			)
			(layer "F.Fab")
		)
		(fp_line
			(start -0.67945 -0.305054)
			(end -0.12065 -0.305054)
			(stroke
				(width 0.1)
				(type default)
			)
			(layer "F.Fab")
		)
		(pad "1" smd circle
			(at -0.40005 0 180)
			(size 0 0)
			(layers "F.Cu" "F.Mask" "F.Paste")
			(net "P3V3_AUX")
		)
		(pad "2" smd circle
			(at 0.40005 0 180)
			(size 0 0)
			(layers "F.Cu" "F.Mask" "F.Paste")
			(net "FAN_7_PRESENT_N")
		)
	)
	(footprint ""
		(layer "F.Cu")
		(at 45.085 -181.102 180)
		(property "Reference" "R519"
			(at 0 0 180)
			(layer "F.SilkS")
			(hide yes)
			(effects
				(font
					(size 1.27 1.27)
				)
			)
		)
		(property "Value" ""
			(at 0 0 180)
			(layer "F.Fab")
			(effects
				(font
					(size 1.27 1.27)
				)
			)
		)
		(duplicate_pad_numbers_are_jumpers no)
		(fp_line
			(start 0.7874 0.4064)
			(end -0.7874 0.4064)
			(stroke
				(width 0.1524)
				(type default)
			)
			(layer "F.SilkS")
		)
		(fp_line
			(start 0.7874 -0.4064)
			(end 0.7874 0.4064)
			(stroke
				(width 0.1524)
				(type default)
			)
			(layer "F.SilkS")
		)
		(fp_line
			(start -0.7874 0.4064)
			(end -0.7874 -0.4064)
			(stroke
				(width 0.1524)
				(type default)
			)
			(layer "F.SilkS")
		)
		(fp_line
			(start -0.7874 -0.4064)
			(end 0.7874 -0.4064)
			(stroke
				(width 0.1524)
				(type default)
			)
			(layer "F.SilkS")
		)
		(fp_line
			(start 0.67945 0.3048)
			(end 0.120396 0.3048)
			(stroke
				(width 0.1)
				(type default)
			)
			(layer "F.Fab")
		)
		(fp_line
			(start 0.67945 -0.3048)
			(end 0.67945 0.3048)
			(stroke
				(width 0.1)
				(type default)
			)
			(layer "F.Fab")
		)
		(fp_line
			(start 0.12065 -0.2794)
			(end 0.12065 -0.3048)
			(stroke
				(width 0.1)
				(type default)
			)
			(layer "F.Fab")
		)
		(fp_line
			(start 0.12065 -0.3048)
			(end 0.67945 -0.3048)
			(stroke
				(width 0.1)
				(type default)
			)
			(layer "F.Fab")
		)
		(fp_line
			(start 0.120396 0.3048)
			(end 0.120396 0.2794)
			(stroke
				(width 0.1)
				(type default)
			)
			(layer "F.Fab")
		)
		(fp_line
			(start 0.120396 0.2794)
			(end -0.12065 0.2794)
			(stroke
				(width 0.1)
				(type default)
			)
			(layer "F.Fab")
		)
		(fp_line
			(start -0.12065 0.3048)
			(end -0.67945 0.3048)
			(stroke
				(width 0.1)
				(type default)
			)
			(layer "F.Fab")
		)
		(fp_line
			(start -0.12065 0.2794)
			(end -0.12065 0.3048)
			(stroke
				(width 0.1)
				(type default)
			)
			(layer "F.Fab")
		)
		(fp_line
			(start -0.12065 -0.2794)
			(end 0.12065 -0.2794)
			(stroke
				(width 0.1)
				(type default)
			)
			(layer "F.Fab")
		)
		(fp_line
			(start -0.12065 -0.305054)
			(end -0.12065 -0.2794)
			(stroke
				(width 0.1)
				(type default)
			)
			(layer "F.Fab")
		)
		(fp_line
			(start -0.67945 0.3048)
			(end -0.67945 -0.305054)
			(stroke
				(width 0.1)
				(type default)
			)
			(layer "F.Fab")
		)
		(fp_line
			(start -0.67945 -0.305054)
			(end -0.12065 -0.305054)
			(stroke
				(width 0.1)
				(type default)
			)
			(layer "F.Fab")
		)
		(pad "1" smd circle
			(at -0.40005 0 180)
			(size 0 0)
			(layers "F.Cu" "F.Mask" "F.Paste")
			(net "GND")
		)
		(pad "2" smd circle
			(at 0.40005 0 180)
			(size 0 0)
			(layers "F.Cu" "F.Mask" "F.Paste")
			(net "PD_FAN_BUFF_INPUT_U336E")
		)
	)
	(footprint ""
		(layer "F.Cu")
		(at 18.415 -181.61 180)
		(property "Reference" "R2360"
			(at 0 0 180)
			(layer "F.SilkS")
			(hide yes)
			(effects
				(font
					(size 1.27 1.27)
				)
			)
		)
		(property "Value" ""
			(at 0 0 180)
			(layer "F.Fab")
			(effects
				(font
					(size 1.27 1.27)
				)
			)
		)
		(duplicate_pad_numbers_are_jumpers no)
		(fp_line
			(start 0.7874 0.4064)
			(end -0.7874 0.4064)
			(stroke
				(width 0.1524)
				(type default)
			)
			(layer "F.SilkS")
		)
		(fp_line
			(start 0.7874 -0.4064)
			(end 0.7874 0.4064)
			(stroke
				(width 0.1524)
				(type default)
			)
			(layer "F.SilkS")
		)
		(fp_line
			(start -0.7874 0.4064)
			(end -0.7874 -0.4064)
			(stroke
				(width 0.1524)
				(type default)
			)
			(layer "F.SilkS")
		)
		(fp_line
			(start -0.7874 -0.4064)
			(end 0.7874 -0.4064)
			(stroke
				(width 0.1524)
				(type default)
			)
			(layer "F.SilkS")
		)
		(fp_line
			(start 0.67945 0.3048)
			(end 0.120396 0.3048)
			(stroke
				(width 0.1)
				(type default)
			)
			(layer "F.Fab")
		)
		(fp_line
			(start 0.67945 -0.3048)
			(end 0.67945 0.3048)
			(stroke
				(width 0.1)
				(type default)
			)
			(layer "F.Fab")
		)
		(fp_line
			(start 0.12065 -0.2794)
			(end 0.12065 -0.3048)
			(stroke
				(width 0.1)
				(type default)
			)
			(layer "F.Fab")
		)
		(fp_line
			(start 0.12065 -0.3048)
			(end 0.67945 -0.3048)
			(stroke
				(width 0.1)
				(type default)
			)
			(layer "F.Fab")
		)
		(fp_line
			(start 0.120396 0.3048)
			(end 0.120396 0.2794)
			(stroke
				(width 0.1)
				(type default)
			)
			(layer "F.Fab")
		)
		(fp_line
			(start 0.120396 0.2794)
			(end -0.12065 0.2794)
			(stroke
				(width 0.1)
				(type default)
			)
			(layer "F.Fab")
		)
		(fp_line
			(start -0.12065 0.3048)
			(end -0.67945 0.3048)
			(stroke
				(width 0.1)
				(type default)
			)
			(layer "F.Fab")
		)
		(fp_line
			(start -0.12065 0.2794)
			(end -0.12065 0.3048)
			(stroke
				(width 0.1)
				(type default)
			)
			(layer "F.Fab")
		)
		(fp_line
			(start -0.12065 -0.2794)
			(end 0.12065 -0.2794)
			(stroke
				(width 0.1)
				(type default)
			)
			(layer "F.Fab")
		)
		(fp_line
			(start -0.12065 -0.305054)
			(end -0.12065 -0.2794)
			(stroke
				(width 0.1)
				(type default)
			)
			(layer "F.Fab")
		)
		(fp_line
			(start -0.67945 0.3048)
			(end -0.67945 -0.305054)
			(stroke
				(width 0.1)
				(type default)
			)
			(layer "F.Fab")
		)
		(fp_line
			(start -0.67945 -0.305054)
			(end -0.12065 -0.305054)
			(stroke
				(width 0.1)
				(type default)
			)
			(layer "F.Fab")
		)
		(pad "1" smd circle
			(at -0.40005 0 180)
			(size 0 0)
			(layers "F.Cu" "F.Mask" "F.Paste")
			(net "P3V3_AUX")
		)
		(pad "2" smd circle
			(at 0.40005 0 180)
			(size 0 0)
			(layers "F.Cu" "F.Mask" "F.Paste")
			(net "PCA9555_MB0_A0")
		)
	)
	(footprint ""
		(layer "F.Cu")
		(at 25.527 -132.461)
		(property "Reference" "R4942"
			(at 0 0 0)
			(layer "F.SilkS")
			(hide yes)
			(effects
				(font
					(size 1.27 1.27)
				)
			)
		)
		(property "Value" ""
			(at 0 0 0)
			(layer "F.Fab")
			(effects
				(font
					(size 1.27 1.27)
				)
			)
		)
		(duplicate_pad_numbers_are_jumpers no)
		(fp_line
			(start -0.7874 -0.4064)
			(end 0.7874 -0.4064)
			(stroke
				(width 0.1524)
				(type default)
			)
			(layer "F.SilkS")
		)
		(fp_line
			(start -0.7874 0.4064)
			(end -0.7874 -0.4064)
			(stroke
				(width 0.1524)
				(type default)
			)
			(layer "F.SilkS")
		)
		(fp_line
			(start 0.7874 -0.4064)
			(end 0.7874 0.4064)
			(stroke
				(width 0.1524)
				(type default)
			)
			(layer "F.SilkS")
		)
		(fp_line
			(start 0.7874 0.4064)
			(end -0.7874 0.4064)
			(stroke
				(width 0.1524)
				(type default)
			)
			(layer "F.SilkS")
		)
		(fp_line
			(start -0.67945 -0.305054)
			(end -0.12065 -0.305054)
			(stroke
				(width 0.1)
				(type default)
			)
			(layer "F.Fab")
		)
		(fp_line
			(start -0.67945 0.3048)
			(end -0.67945 -0.305054)
			(stroke
				(width 0.1)
				(type default)
			)
			(layer "F.Fab")
		)
		(fp_line
			(start -0.12065 -0.305054)
			(end -0.12065 -0.2794)
			(stroke
				(width 0.1)
				(type default)
			)
			(layer "F.Fab")
		)
		(fp_line
			(start -0.12065 -0.2794)
			(end 0.12065 -0.2794)
			(stroke
				(width 0.1)
				(type default)
			)
			(layer "F.Fab")
		)
		(fp_line
			(start -0.12065 0.2794)
			(end -0.12065 0.3048)
			(stroke
				(width 0.1)
				(type default)
			)
			(layer "F.Fab")
		)
		(fp_line
			(start -0.12065 0.3048)
			(end -0.67945 0.3048)
			(stroke
				(width 0.1)
				(type default)
			)
			(layer "F.Fab")
		)
		(fp_line
			(start 0.120396 0.2794)
			(end -0.12065 0.2794)
			(stroke
				(width 0.1)
				(type default)
			)
			(layer "F.Fab")
		)
		(fp_line
			(start 0.120396 0.3048)
			(end 0.120396 0.2794)
			(stroke
				(width 0.1)
				(type default)
			)
			(layer "F.Fab")
		)
		(fp_line
			(start 0.12065 -0.3048)
			(end 0.67945 -0.3048)
			(stroke
				(width 0.1)
				(type default)
			)
			(layer "F.Fab")
		)
		(fp_line
			(start 0.12065 -0.2794)
			(end 0.12065 -0.3048)
			(stroke
				(width 0.1)
				(type default)
			)
			(layer "F.Fab")
		)
		(fp_line
			(start 0.67945 -0.3048)
			(end 0.67945 0.3048)
			(stroke
				(width 0.1)
				(type default)
			)
			(layer "F.Fab")
		)
		(fp_line
			(start 0.67945 0.3048)
			(end 0.120396 0.3048)
			(stroke
				(width 0.1)
				(type default)
			)
			(layer "F.Fab")
		)
		(pad "1" smd circle
			(at -0.40005 0)
			(size 0 0)
			(layers "F.Cu" "F.Mask" "F.Paste")
			(net "GND")
		)
		(pad "2" smd circle
			(at 0.40005 0)
			(size 0 0)
			(layers "F.Cu" "F.Mask" "F.Paste")
			(net "MAX31790_U317_PWM_START0")
		)
	)
	(footprint ""
		(layer "F.Cu")
		(at 11.445494 -71.812912)
		(property "Reference" "C2063"
			(at 0 0 0)
			(layer "F.SilkS")
			(hide yes)
			(effects
				(font
					(size 1.27 1.27)
				)
			)
		)
		(property "Value" ""
			(at 0 0 0)
			(layer "F.Fab")
			(effects
				(font
					(size 1.27 1.27)
				)
			)
		)
		(duplicate_pad_numbers_are_jumpers no)
		(fp_line
			(start -0.7874 -0.4064)
			(end 0.7874 -0.4064)
			(stroke
				(width 0.1524)
				(type default)
			)
			(layer "F.SilkS")
		)
		(fp_line
			(start -0.7874 0.4064)
			(end -0.7874 -0.4064)
			(stroke
				(width 0.1524)
				(type default)
			)
			(layer "F.SilkS")
		)
		(fp_line
			(start 0.7874 -0.4064)
			(end 0.7874 0.4064)
			(stroke
				(width 0.1524)
				(type default)
			)
			(layer "F.SilkS")
		)
		(fp_line
			(start 0.7874 0.4064)
			(end -0.7874 0.4064)
			(stroke
				(width 0.1524)
				(type default)
			)
			(layer "F.SilkS")
		)
		(fp_line
			(start -0.67945 -0.305054)
			(end -0.12065 -0.305054)
			(stroke
				(width 0.1)
				(type default)
			)
			(layer "F.Fab")
		)
		(fp_line
			(start -0.67945 0.3048)
			(end -0.67945 -0.305054)
			(stroke
				(width 0.1)
				(type default)
			)
			(layer "F.Fab")
		)
		(fp_line
			(start -0.12065 -0.305054)
			(end -0.12065 -0.2794)
			(stroke
				(width 0.1)
				(type default)
			)
			(layer "F.Fab")
		)
		(fp_line
			(start -0.12065 -0.2794)
			(end 0.12065 -0.2794)
			(stroke
				(width 0.1)
				(type default)
			)
			(layer "F.Fab")
		)
		(fp_line
			(start -0.12065 0.2794)
			(end -0.12065 0.3048)
			(stroke
				(width 0.1)
				(type default)
			)
			(layer "F.Fab")
		)
		(fp_line
			(start -0.12065 0.3048)
			(end -0.67945 0.3048)
			(stroke
				(width 0.1)
				(type default)
			)
			(layer "F.Fab")
		)
		(fp_line
			(start 0.120396 0.2794)
			(end -0.12065 0.2794)
			(stroke
				(width 0.1)
				(type default)
			)
			(layer "F.Fab")
		)
		(fp_line
			(start 0.120396 0.3048)
			(end 0.120396 0.2794)
			(stroke
				(width 0.1)
				(type default)
			)
			(layer "F.Fab")
		)
		(fp_line
			(start 0.12065 -0.3048)
			(end 0.67945 -0.3048)
			(stroke
				(width 0.1)
				(type default)
			)
			(layer "F.Fab")
		)
		(fp_line
			(start 0.12065 -0.2794)
			(end 0.12065 -0.3048)
			(stroke
				(width 0.1)
				(type default)
			)
			(layer "F.Fab")
		)
		(fp_line
			(start 0.67945 -0.3048)
			(end 0.67945 0.3048)
			(stroke
				(width 0.1)
				(type default)
			)
			(layer "F.Fab")
		)
		(fp_line
			(start 0.67945 0.3048)
			(end 0.120396 0.3048)
			(stroke
				(width 0.1)
				(type default)
			)
			(layer "F.Fab")
		)
		(pad "1" smd circle
			(at -0.40005 0)
			(size 0 0)
			(layers "F.Cu" "F.Mask" "F.Paste")
			(net "P3V3_AUX")
		)
		(pad "2" smd circle
			(at 0.40005 0)
			(size 0 0)
			(layers "F.Cu" "F.Mask" "F.Paste")
			(net "GND")
		)
	)
	(footprint ""
		(layer "F.Cu")
		(at 19.558 -114.681 -90)
		(property "Reference" "R5363"
			(at 0 0 270)
			(layer "F.SilkS")
			(hide yes)
			(effects
				(font
					(size 1.27 1.27)
				)
			)
		)
		(property "Value" ""
			(at 0 0 270)
			(layer "F.Fab")
			(effects
				(font
					(size 1.27 1.27)
				)
			)
		)
		(duplicate_pad_numbers_are_jumpers no)
		(fp_line
			(start -0.7874 0.4064)
			(end -0.7874 -0.4064)
			(stroke
				(width 0.1524)
				(type default)
			)
			(layer "F.SilkS")
		)
		(fp_line
			(start 0.7874 0.4064)
			(end -0.7874 0.4064)
			(stroke
				(width 0.1524)
				(type default)
			)
			(layer "F.SilkS")
		)
		(fp_line
			(start -0.7874 -0.4064)
			(end 0.7874 -0.4064)
			(stroke
				(width 0.1524)
				(type default)
			)
			(layer "F.SilkS")
		)
		(fp_line
			(start 0.7874 -0.4064)
			(end 0.7874 0.4064)
			(stroke
				(width 0.1524)
				(type default)
			)
			(layer "F.SilkS")
		)
		(fp_line
			(start -0.67945 0.3048)
			(end -0.67945 -0.305054)
			(stroke
				(width 0.1)
				(type default)
			)
			(layer "F.Fab")
		)
		(fp_line
			(start -0.12065 0.3048)
			(end -0.67945 0.3048)
			(stroke
				(width 0.1)
				(type default)
			)
			(layer "F.Fab")
		)
		(fp_line
			(start 0.120396 0.3048)
			(end 0.120396 0.2794)
			(stroke
				(width 0.1)
				(type default)
			)
			(layer "F.Fab")
		)
		(fp_line
			(start 0.67945 0.3048)
			(end 0.120396 0.3048)
			(stroke
				(width 0.1)
				(type default)
			)
			(layer "F.Fab")
		)
		(fp_line
			(start -0.12065 0.2794)
			(end -0.12065 0.3048)
			(stroke
				(width 0.1)
				(type default)
			)
			(layer "F.Fab")
		)
		(fp_line
			(start 0.120396 0.2794)
			(end -0.12065 0.2794)
			(stroke
				(width 0.1)
				(type default)
			)
			(layer "F.Fab")
		)
		(fp_line
			(start -0.12065 -0.2794)
			(end 0.12065 -0.2794)
			(stroke
				(width 0.1)
				(type default)
			)
			(layer "F.Fab")
		)
		(fp_line
			(start 0.12065 -0.2794)
			(end 0.12065 -0.3048)
			(stroke
				(width 0.1)
				(type default)
			)
			(layer "F.Fab")
		)
		(fp_line
			(start 0.12065 -0.3048)
			(end 0.67945 -0.3048)
			(stroke
				(width 0.1)
				(type default)
			)
			(layer "F.Fab")
		)
		(fp_line
			(start 0.67945 -0.3048)
			(end 0.67945 0.3048)
			(stroke
				(width 0.1)
				(type default)
			)
			(layer "F.Fab")
		)
		(fp_line
			(start -0.67945 -0.305054)
			(end -0.12065 -0.305054)
			(stroke
				(width 0.1)
				(type default)
			)
			(layer "F.Fab")
		)
		(fp_line
			(start -0.12065 -0.305054)
			(end -0.12065 -0.2794)
			(stroke
				(width 0.1)
				(type default)
			)
			(layer "F.Fab")
		)
		(pad "1" smd circle
			(at -0.40005 0 270)
			(size 0 0)
			(layers "F.Cu" "F.Mask" "F.Paste")
			(net "P3V3_AUX")
		)
		(pad "2" smd circle
			(at 0.40005 0 270)
			(size 0 0)
			(layers "F.Cu" "F.Mask" "F.Paste")
			(net "FAN_5_OK_R_LED")
		)
	)
	(footprint ""
		(layer "F.Cu")
		(at 17.907 -170.815 180)
		(property "Reference" "R5500"
			(at 0 0 180)
			(layer "F.SilkS")
			(hide yes)
			(effects
				(font
					(size 1.27 1.27)
				)
			)
		)
		(property "Value" ""
			(at 0 0 180)
			(layer "F.Fab")
			(effects
				(font
					(size 1.27 1.27)
				)
			)
		)
		(duplicate_pad_numbers_are_jumpers no)
		(fp_line
			(start 0.7874 0.4064)
			(end -0.7874 0.4064)
			(stroke
				(width 0.1524)
				(type default)
			)
			(layer "F.SilkS")
		)
		(fp_line
			(start 0.7874 -0.4064)
			(end 0.7874 0.4064)
			(stroke
				(width 0.1524)
				(type default)
			)
			(layer "F.SilkS")
		)
		(fp_line
			(start -0.7874 0.4064)
			(end -0.7874 -0.4064)
			(stroke
				(width 0.1524)
				(type default)
			)
			(layer "F.SilkS")
		)
		(fp_line
			(start -0.7874 -0.4064)
			(end 0.7874 -0.4064)
			(stroke
				(width 0.1524)
				(type default)
			)
			(layer "F.SilkS")
		)
		(fp_line
			(start 0.67945 0.3048)
			(end 0.120396 0.3048)
			(stroke
				(width 0.1)
				(type default)
			)
			(layer "F.Fab")
		)
		(fp_line
			(start 0.67945 -0.3048)
			(end 0.67945 0.3048)
			(stroke
				(width 0.1)
				(type default)
			)
			(layer "F.Fab")
		)
		(fp_line
			(start 0.12065 -0.2794)
			(end 0.12065 -0.3048)
			(stroke
				(width 0.1)
				(type default)
			)
			(layer "F.Fab")
		)
		(fp_line
			(start 0.12065 -0.3048)
			(end 0.67945 -0.3048)
			(stroke
				(width 0.1)
				(type default)
			)
			(layer "F.Fab")
		)
		(fp_line
			(start 0.120396 0.3048)
			(end 0.120396 0.2794)
			(stroke
				(width 0.1)
				(type default)
			)
			(layer "F.Fab")
		)
		(fp_line
			(start 0.120396 0.2794)
			(end -0.12065 0.2794)
			(stroke
				(width 0.1)
				(type default)
			)
			(layer "F.Fab")
		)
		(fp_line
			(start -0.12065 0.3048)
			(end -0.67945 0.3048)
			(stroke
				(width 0.1)
				(type default)
			)
			(layer "F.Fab")
		)
		(fp_line
			(start -0.12065 0.2794)
			(end -0.12065 0.3048)
			(stroke
				(width 0.1)
				(type default)
			)
			(layer "F.Fab")
		)
		(fp_line
			(start -0.12065 -0.2794)
			(end 0.12065 -0.2794)
			(stroke
				(width 0.1)
				(type default)
			)
			(layer "F.Fab")
		)
		(fp_line
			(start -0.12065 -0.305054)
			(end -0.12065 -0.2794)
			(stroke
				(width 0.1)
				(type default)
			)
			(layer "F.Fab")
		)
		(fp_line
			(start -0.67945 0.3048)
			(end -0.67945 -0.305054)
			(stroke
				(width 0.1)
				(type default)
			)
			(layer "F.Fab")
		)
		(fp_line
			(start -0.67945 -0.305054)
			(end -0.12065 -0.305054)
			(stroke
				(width 0.1)
				(type default)
			)
			(layer "F.Fab")
		)
		(pad "1" smd circle
			(at -0.40005 0 180)
			(size 0 0)
			(layers "F.Cu" "F.Mask" "F.Paste")
			(net "FAN_5_PRESENT_R_N")
		)
		(pad "2" smd circle
			(at 0.40005 0 180)
			(size 0 0)
			(layers "F.Cu" "F.Mask" "F.Paste")
			(net "FAN_5_PRESENT_N")
		)
	)
	(footprint ""
		(layer "F.Cu")
		(at 21.717 -303.53 90)
		(property "Reference" "C100"
			(at 0 0 90)
			(layer "F.SilkS")
			(hide yes)
			(effects
				(font
					(size 1.27 1.27)
				)
			)
		)
		(property "Value" ""
			(at 0 0 90)
			(layer "F.Fab")
			(effects
				(font
					(size 1.27 1.27)
				)
			)
		)
		(duplicate_pad_numbers_are_jumpers no)
		(fp_line
			(start 0.7874 -0.4064)
			(end 0.7874 0.4064)
			(stroke
				(width 0.1524)
				(type default)
			)
			(layer "F.SilkS")
		)
		(fp_line
			(start -0.7874 -0.4064)
			(end 0.7874 -0.4064)
			(stroke
				(width 0.1524)
				(type default)
			)
			(layer "F.SilkS")
		)
		(fp_line
			(start 0.7874 0.4064)
			(end -0.7874 0.4064)
			(stroke
				(width 0.1524)
				(type default)
			)
			(layer "F.SilkS")
		)
		(fp_line
			(start -0.7874 0.4064)
			(end -0.7874 -0.4064)
			(stroke
				(width 0.1524)
				(type default)
			)
			(layer "F.SilkS")
		)
		(fp_line
			(start -0.12065 -0.305054)
			(end -0.12065 -0.2794)
			(stroke
				(width 0.1)
				(type default)
			)
			(layer "F.Fab")
		)
		(fp_line
			(start -0.67945 -0.305054)
			(end -0.12065 -0.305054)
			(stroke
				(width 0.1)
				(type default)
			)
			(layer "F.Fab")
		)
		(fp_line
			(start 0.67945 -0.3048)
			(end 0.67945 0.3048)
			(stroke
				(width 0.1)
				(type default)
			)
			(layer "F.Fab")
		)
		(fp_line
			(start 0.12065 -0.3048)
			(end 0.67945 -0.3048)
			(stroke
				(width 0.1)
				(type default)
			)
			(layer "F.Fab")
		)
		(fp_line
			(start 0.12065 -0.2794)
			(end 0.12065 -0.3048)
			(stroke
				(width 0.1)
				(type default)
			)
			(layer "F.Fab")
		)
		(fp_line
			(start -0.12065 -0.2794)
			(end 0.12065 -0.2794)
			(stroke
				(width 0.1)
				(type default)
			)
			(layer "F.Fab")
		)
		(fp_line
			(start 0.120396 0.2794)
			(end -0.12065 0.2794)
			(stroke
				(width 0.1)
				(type default)
			)
			(layer "F.Fab")
		)
		(fp_line
			(start -0.12065 0.2794)
			(end -0.12065 0.3048)
			(stroke
				(width 0.1)
				(type default)
			)
			(layer "F.Fab")
		)
		(fp_line
			(start 0.67945 0.3048)
			(end 0.120396 0.3048)
			(stroke
				(width 0.1)
				(type default)
			)
			(layer "F.Fab")
		)
		(fp_line
			(start 0.120396 0.3048)
			(end 0.120396 0.2794)
			(stroke
				(width 0.1)
				(type default)
			)
			(layer "F.Fab")
		)
		(fp_line
			(start -0.12065 0.3048)
			(end -0.67945 0.3048)
			(stroke
				(width 0.1)
				(type default)
			)
			(layer "F.Fab")
		)
		(fp_line
			(start -0.67945 0.3048)
			(end -0.67945 -0.305054)
			(stroke
				(width 0.1)
				(type default)
			)
			(layer "F.Fab")
		)
		(pad "1" smd circle
			(at -0.40005 0 90)
			(size 0 0)
			(layers "F.Cu" "F.Mask" "F.Paste")
			(net "P3V3_AUX")
		)
		(pad "2" smd circle
			(at 0.40005 0 90)
			(size 0 0)
			(layers "F.Cu" "F.Mask" "F.Paste")
			(net "GND")
		)
	)
	(footprint ""
		(layer "F.Cu")
		(at 45.085 -124.079 -90)
		(property "Reference" "R5694"
			(at 0 0 270)
			(layer "F.SilkS")
			(hide yes)
			(effects
				(font
					(size 1.27 1.27)
				)
			)
		)
		(property "Value" ""
			(at 0 0 270)
			(layer "F.Fab")
			(effects
				(font
					(size 1.27 1.27)
				)
			)
		)
		(duplicate_pad_numbers_are_jumpers no)
		(fp_line
			(start -0.7874 0.4064)
			(end -0.7874 -0.4064)
			(stroke
				(width 0.1524)
				(type default)
			)
			(layer "F.SilkS")
		)
		(fp_line
			(start 0.7874 0.4064)
			(end -0.7874 0.4064)
			(stroke
				(width 0.1524)
				(type default)
			)
			(layer "F.SilkS")
		)
		(fp_line
			(start -0.7874 -0.4064)
			(end 0.7874 -0.4064)
			(stroke
				(width 0.1524)
				(type default)
			)
			(layer "F.SilkS")
		)
		(fp_line
			(start 0.7874 -0.4064)
			(end 0.7874 0.4064)
			(stroke
				(width 0.1524)
				(type default)
			)
			(layer "F.SilkS")
		)
		(fp_line
			(start -0.67945 0.3048)
			(end -0.67945 -0.305054)
			(stroke
				(width 0.1)
				(type default)
			)
			(layer "F.Fab")
		)
		(fp_line
			(start -0.12065 0.3048)
			(end -0.67945 0.3048)
			(stroke
				(width 0.1)
				(type default)
			)
			(layer "F.Fab")
		)
		(fp_line
			(start 0.120396 0.3048)
			(end 0.120396 0.2794)
			(stroke
				(width 0.1)
				(type default)
			)
			(layer "F.Fab")
		)
		(fp_line
			(start 0.67945 0.3048)
			(end 0.120396 0.3048)
			(stroke
				(width 0.1)
				(type default)
			)
			(layer "F.Fab")
		)
		(fp_line
			(start -0.12065 0.2794)
			(end -0.12065 0.3048)
			(stroke
				(width 0.1)
				(type default)
			)
			(layer "F.Fab")
		)
		(fp_line
			(start 0.120396 0.2794)
			(end -0.12065 0.2794)
			(stroke
				(width 0.1)
				(type default)
			)
			(layer "F.Fab")
		)
		(fp_line
			(start -0.12065 -0.2794)
			(end 0.12065 -0.2794)
			(stroke
				(width 0.1)
				(type default)
			)
			(layer "F.Fab")
		)
		(fp_line
			(start 0.12065 -0.2794)
			(end 0.12065 -0.3048)
			(stroke
				(width 0.1)
				(type default)
			)
			(layer "F.Fab")
		)
		(fp_line
			(start 0.12065 -0.3048)
			(end 0.67945 -0.3048)
			(stroke
				(width 0.1)
				(type default)
			)
			(layer "F.Fab")
		)
		(fp_line
			(start 0.67945 -0.3048)
			(end 0.67945 0.3048)
			(stroke
				(width 0.1)
				(type default)
			)
			(layer "F.Fab")
		)
		(fp_line
			(start -0.67945 -0.305054)
			(end -0.12065 -0.305054)
			(stroke
				(width 0.1)
				(type default)
			)
			(layer "F.Fab")
		)
		(fp_line
			(start -0.12065 -0.305054)
			(end -0.12065 -0.2794)
			(stroke
				(width 0.1)
				(type default)
			)
			(layer "F.Fab")
		)
		(pad "1" smd rect
			(at -0.40005 0 90)
			(size 0.4572 0.508)
			(layers "F.Cu" "F.Mask" "F.Paste")
			(net "P12V_LED_R_FAN2")
		)
		(pad "2" smd rect
			(at 0.40005 0 90)
			(size 0.4572 0.508)
			(layers "F.Cu" "F.Mask" "F.Paste")
			(net "P12V_LED_R1_FAN2")
		)
	)
	(footprint ""
		(layer "F.Cu")
		(at 24.638 -185.674 180)
		(property "Reference" "C2085"
			(at 0 0 180)
			(layer "F.SilkS")
			(hide yes)
			(effects
				(font
					(size 1.27 1.27)
				)
			)
		)
		(property "Value" ""
			(at 0 0 180)
			(layer "F.Fab")
			(effects
				(font
					(size 1.27 1.27)
				)
			)
		)
		(duplicate_pad_numbers_are_jumpers no)
		(fp_line
			(start 0.7874 0.4064)
			(end -0.7874 0.4064)
			(stroke
				(width 0.1524)
				(type default)
			)
			(layer "F.SilkS")
		)
		(fp_line
			(start 0.7874 -0.4064)
			(end 0.7874 0.4064)
			(stroke
				(width 0.1524)
				(type default)
			)
			(layer "F.SilkS")
		)
		(fp_line
			(start -0.7874 0.4064)
			(end -0.7874 -0.4064)
			(stroke
				(width 0.1524)
				(type default)
			)
			(layer "F.SilkS")
		)
		(fp_line
			(start -0.7874 -0.4064)
			(end 0.7874 -0.4064)
			(stroke
				(width 0.1524)
				(type default)
			)
			(layer "F.SilkS")
		)
		(fp_line
			(start 0.67945 0.3048)
			(end 0.120396 0.3048)
			(stroke
				(width 0.1)
				(type default)
			)
			(layer "F.Fab")
		)
		(fp_line
			(start 0.67945 -0.3048)
			(end 0.67945 0.3048)
			(stroke
				(width 0.1)
				(type default)
			)
			(layer "F.Fab")
		)
		(fp_line
			(start 0.12065 -0.2794)
			(end 0.12065 -0.3048)
			(stroke
				(width 0.1)
				(type default)
			)
			(layer "F.Fab")
		)
		(fp_line
			(start 0.12065 -0.3048)
			(end 0.67945 -0.3048)
			(stroke
				(width 0.1)
				(type default)
			)
			(layer "F.Fab")
		)
		(fp_line
			(start 0.120396 0.3048)
			(end 0.120396 0.2794)
			(stroke
				(width 0.1)
				(type default)
			)
			(layer "F.Fab")
		)
		(fp_line
			(start 0.120396 0.2794)
			(end -0.12065 0.2794)
			(stroke
				(width 0.1)
				(type default)
			)
			(layer "F.Fab")
		)
		(fp_line
			(start -0.12065 0.3048)
			(end -0.67945 0.3048)
			(stroke
				(width 0.1)
				(type default)
			)
			(layer "F.Fab")
		)
		(fp_line
			(start -0.12065 0.2794)
			(end -0.12065 0.3048)
			(stroke
				(width 0.1)
				(type default)
			)
			(layer "F.Fab")
		)
		(fp_line
			(start -0.12065 -0.2794)
			(end 0.12065 -0.2794)
			(stroke
				(width 0.1)
				(type default)
			)
			(layer "F.Fab")
		)
		(fp_line
			(start -0.12065 -0.305054)
			(end -0.12065 -0.2794)
			(stroke
				(width 0.1)
				(type default)
			)
			(layer "F.Fab")
		)
		(fp_line
			(start -0.67945 0.3048)
			(end -0.67945 -0.305054)
			(stroke
				(width 0.1)
				(type default)
			)
			(layer "F.Fab")
		)
		(fp_line
			(start -0.67945 -0.305054)
			(end -0.12065 -0.305054)
			(stroke
				(width 0.1)
				(type default)
			)
			(layer "F.Fab")
		)
		(pad "1" smd circle
			(at -0.40005 0 180)
			(size 0 0)
			(layers "F.Cu" "F.Mask" "F.Paste")
			(net "P52V_FAN_6_BUFF_EN_R")
		)
		(pad "2" smd circle
			(at 0.40005 0 180)
			(size 0 0)
			(layers "F.Cu" "F.Mask" "F.Paste")
			(net "GND")
		)
	)
	(footprint ""
		(layer "F.Cu")
		(at 33.02 -300.609 180)
		(property "Reference" "C2022"
			(at 0 0 180)
			(layer "F.SilkS")
			(hide yes)
			(effects
				(font
					(size 1.27 1.27)
				)
			)
		)
		(property "Value" ""
			(at 0 0 180)
			(layer "F.Fab")
			(effects
				(font
					(size 1.27 1.27)
				)
			)
		)
		(duplicate_pad_numbers_are_jumpers no)
		(fp_line
			(start 0.7874 0.4064)
			(end -0.7874 0.4064)
			(stroke
				(width 0.1524)
				(type default)
			)
			(layer "F.SilkS")
		)
		(fp_line
			(start 0.7874 -0.4064)
			(end 0.7874 0.4064)
			(stroke
				(width 0.1524)
				(type default)
			)
			(layer "F.SilkS")
		)
		(fp_line
			(start -0.7874 0.4064)
			(end -0.7874 -0.4064)
			(stroke
				(width 0.1524)
				(type default)
			)
			(layer "F.SilkS")
		)
		(fp_line
			(start -0.7874 -0.4064)
			(end 0.7874 -0.4064)
			(stroke
				(width 0.1524)
				(type default)
			)
			(layer "F.SilkS")
		)
		(fp_line
			(start 0.67945 0.3048)
			(end 0.120396 0.3048)
			(stroke
				(width 0.1)
				(type default)
			)
			(layer "F.Fab")
		)
		(fp_line
			(start 0.67945 -0.3048)
			(end 0.67945 0.3048)
			(stroke
				(width 0.1)
				(type default)
			)
			(layer "F.Fab")
		)
		(fp_line
			(start 0.12065 -0.2794)
			(end 0.12065 -0.3048)
			(stroke
				(width 0.1)
				(type default)
			)
			(layer "F.Fab")
		)
		(fp_line
			(start 0.12065 -0.3048)
			(end 0.67945 -0.3048)
			(stroke
				(width 0.1)
				(type default)
			)
			(layer "F.Fab")
		)
		(fp_line
			(start 0.120396 0.3048)
			(end 0.120396 0.2794)
			(stroke
				(width 0.1)
				(type default)
			)
			(layer "F.Fab")
		)
		(fp_line
			(start 0.120396 0.2794)
			(end -0.12065 0.2794)
			(stroke
				(width 0.1)
				(type default)
			)
			(layer "F.Fab")
		)
		(fp_line
			(start -0.12065 0.3048)
			(end -0.67945 0.3048)
			(stroke
				(width 0.1)
				(type default)
			)
			(layer "F.Fab")
		)
		(fp_line
			(start -0.12065 0.2794)
			(end -0.12065 0.3048)
			(stroke
				(width 0.1)
				(type default)
			)
			(layer "F.Fab")
		)
		(fp_line
			(start -0.12065 -0.2794)
			(end 0.12065 -0.2794)
			(stroke
				(width 0.1)
				(type default)
			)
			(layer "F.Fab")
		)
		(fp_line
			(start -0.12065 -0.305054)
			(end -0.12065 -0.2794)
			(stroke
				(width 0.1)
				(type default)
			)
			(layer "F.Fab")
		)
		(fp_line
			(start -0.67945 0.3048)
			(end -0.67945 -0.305054)
			(stroke
				(width 0.1)
				(type default)
			)
			(layer "F.Fab")
		)
		(fp_line
			(start -0.67945 -0.305054)
			(end -0.12065 -0.305054)
			(stroke
				(width 0.1)
				(type default)
			)
			(layer "F.Fab")
		)
		(pad "1" smd circle
			(at -0.40005 0 180)
			(size 0 0)
			(layers "F.Cu" "F.Mask" "F.Paste")
			(net "FAN_0_TACH_IL_R")
		)
		(pad "2" smd circle
			(at 0.40005 0 180)
			(size 0 0)
			(layers "F.Cu" "F.Mask" "F.Paste")
			(net "GND")
		)
	)
	(footprint ""
		(layer "F.Cu")
		(at 37.719 -98.806 90)
		(property "Reference" "R5656"
			(at 0 0 90)
			(layer "F.SilkS")
			(hide yes)
			(effects
				(font
					(size 1.27 1.27)
				)
			)
		)
		(property "Value" ""
			(at 0 0 90)
			(layer "F.Fab")
			(effects
				(font
					(size 1.27 1.27)
				)
			)
		)
		(duplicate_pad_numbers_are_jumpers no)
		(fp_line
			(start 0.7874 -0.4064)
			(end 0.7874 0.4064)
			(stroke
				(width 0.1524)
				(type default)
			)
			(layer "F.SilkS")
		)
		(fp_line
			(start -0.7874 -0.4064)
			(end 0.7874 -0.4064)
			(stroke
				(width 0.1524)
				(type default)
			)
			(layer "F.SilkS")
		)
		(fp_line
			(start 0.7874 0.4064)
			(end -0.7874 0.4064)
			(stroke
				(width 0.1524)
				(type default)
			)
			(layer "F.SilkS")
		)
		(fp_line
			(start -0.7874 0.4064)
			(end -0.7874 -0.4064)
			(stroke
				(width 0.1524)
				(type default)
			)
			(layer "F.SilkS")
		)
		(fp_line
			(start -0.12065 -0.305054)
			(end -0.12065 -0.2794)
			(stroke
				(width 0.1)
				(type default)
			)
			(layer "F.Fab")
		)
		(fp_line
			(start -0.67945 -0.305054)
			(end -0.12065 -0.305054)
			(stroke
				(width 0.1)
				(type default)
			)
			(layer "F.Fab")
		)
		(fp_line
			(start 0.67945 -0.3048)
			(end 0.67945 0.3048)
			(stroke
				(width 0.1)
				(type default)
			)
			(layer "F.Fab")
		)
		(fp_line
			(start 0.12065 -0.3048)
			(end 0.67945 -0.3048)
			(stroke
				(width 0.1)
				(type default)
			)
			(layer "F.Fab")
		)
		(fp_line
			(start 0.12065 -0.2794)
			(end 0.12065 -0.3048)
			(stroke
				(width 0.1)
				(type default)
			)
			(layer "F.Fab")
		)
		(fp_line
			(start -0.12065 -0.2794)
			(end 0.12065 -0.2794)
			(stroke
				(width 0.1)
				(type default)
			)
			(layer "F.Fab")
		)
		(fp_line
			(start 0.120396 0.2794)
			(end -0.12065 0.2794)
			(stroke
				(width 0.1)
				(type default)
			)
			(layer "F.Fab")
		)
		(fp_line
			(start -0.12065 0.2794)
			(end -0.12065 0.3048)
			(stroke
				(width 0.1)
				(type default)
			)
			(layer "F.Fab")
		)
		(fp_line
			(start 0.67945 0.3048)
			(end 0.120396 0.3048)
			(stroke
				(width 0.1)
				(type default)
			)
			(layer "F.Fab")
		)
		(fp_line
			(start 0.120396 0.3048)
			(end 0.120396 0.2794)
			(stroke
				(width 0.1)
				(type default)
			)
			(layer "F.Fab")
		)
		(fp_line
			(start -0.12065 0.3048)
			(end -0.67945 0.3048)
			(stroke
				(width 0.1)
				(type default)
			)
			(layer "F.Fab")
		)
		(fp_line
			(start -0.67945 0.3048)
			(end -0.67945 -0.305054)
			(stroke
				(width 0.1)
				(type default)
			)
			(layer "F.Fab")
		)
		(pad "1" smd circle
			(at -0.40005 0 90)
			(size 0 0)
			(layers "F.Cu" "F.Mask" "F.Paste")
			(net "FAN_2_PRESENT")
		)
		(pad "2" smd circle
			(at 0.40005 0 90)
			(size 0 0)
			(layers "F.Cu" "F.Mask" "F.Paste")
			(net "GND")
		)
	)
	(footprint ""
		(layer "F.Cu")
		(at 14.87805 -122.047)
		(property "Reference" "R5609"
			(at 0 0 0)
			(layer "F.SilkS")
			(hide yes)
			(effects
				(font
					(size 1.27 1.27)
				)
			)
		)
		(property "Value" ""
			(at 0 0 0)
			(layer "F.Fab")
			(effects
				(font
					(size 1.27 1.27)
				)
			)
		)
		(duplicate_pad_numbers_are_jumpers no)
		(fp_line
			(start -0.7874 -0.4064)
			(end 0.7874 -0.4064)
			(stroke
				(width 0.1524)
				(type default)
			)
			(layer "F.SilkS")
		)
		(fp_line
			(start -0.7874 0.4064)
			(end -0.7874 -0.4064)
			(stroke
				(width 0.1524)
				(type default)
			)
			(layer "F.SilkS")
		)
		(fp_line
			(start 0.7874 -0.4064)
			(end 0.7874 0.4064)
			(stroke
				(width 0.1524)
				(type default)
			)
			(layer "F.SilkS")
		)
		(fp_line
			(start 0.7874 0.4064)
			(end -0.7874 0.4064)
			(stroke
				(width 0.1524)
				(type default)
			)
			(layer "F.SilkS")
		)
		(fp_line
			(start -0.67945 -0.305054)
			(end -0.12065 -0.305054)
			(stroke
				(width 0.1)
				(type default)
			)
			(layer "F.Fab")
		)
		(fp_line
			(start -0.67945 0.3048)
			(end -0.67945 -0.305054)
			(stroke
				(width 0.1)
				(type default)
			)
			(layer "F.Fab")
		)
		(fp_line
			(start -0.12065 -0.305054)
			(end -0.12065 -0.2794)
			(stroke
				(width 0.1)
				(type default)
			)
			(layer "F.Fab")
		)
		(fp_line
			(start -0.12065 -0.2794)
			(end 0.12065 -0.2794)
			(stroke
				(width 0.1)
				(type default)
			)
			(layer "F.Fab")
		)
		(fp_line
			(start -0.12065 0.2794)
			(end -0.12065 0.3048)
			(stroke
				(width 0.1)
				(type default)
			)
			(layer "F.Fab")
		)
		(fp_line
			(start -0.12065 0.3048)
			(end -0.67945 0.3048)
			(stroke
				(width 0.1)
				(type default)
			)
			(layer "F.Fab")
		)
		(fp_line
			(start 0.120396 0.2794)
			(end -0.12065 0.2794)
			(stroke
				(width 0.1)
				(type default)
			)
			(layer "F.Fab")
		)
		(fp_line
			(start 0.120396 0.3048)
			(end 0.120396 0.2794)
			(stroke
				(width 0.1)
				(type default)
			)
			(layer "F.Fab")
		)
		(fp_line
			(start 0.12065 -0.3048)
			(end 0.67945 -0.3048)
			(stroke
				(width 0.1)
				(type default)
			)
			(layer "F.Fab")
		)
		(fp_line
			(start 0.12065 -0.2794)
			(end 0.12065 -0.3048)
			(stroke
				(width 0.1)
				(type default)
			)
			(layer "F.Fab")
		)
		(fp_line
			(start 0.67945 -0.3048)
			(end 0.67945 0.3048)
			(stroke
				(width 0.1)
				(type default)
			)
			(layer "F.Fab")
		)
		(fp_line
			(start 0.67945 0.3048)
			(end 0.120396 0.3048)
			(stroke
				(width 0.1)
				(type default)
			)
			(layer "F.Fab")
		)
		(pad "1" smd rect
			(at -0.40005 0 180)
			(size 0.4572 0.508)
			(layers "F.Cu" "F.Mask" "F.Paste")
			(net "FAN_4_PWM")
		)
		(pad "2" smd rect
			(at 0.40005 0 180)
			(size 0.4572 0.508)
			(layers "F.Cu" "F.Mask" "F.Paste")
			(net "FAN_4_PWM_R1")
		)
	)
	(footprint ""
		(layer "F.Cu")
		(at 42.037 -187.96)
		(property "Reference" "R4964"
			(at 0 0 0)
			(layer "F.SilkS")
			(hide yes)
			(effects
				(font
					(size 1.27 1.27)
				)
			)
		)
		(property "Value" ""
			(at 0 0 0)
			(layer "F.Fab")
			(effects
				(font
					(size 1.27 1.27)
				)
			)
		)
		(duplicate_pad_numbers_are_jumpers no)
		(fp_line
			(start -0.7874 -0.4064)
			(end 0.7874 -0.4064)
			(stroke
				(width 0.1524)
				(type default)
			)
			(layer "F.SilkS")
		)
		(fp_line
			(start -0.7874 0.4064)
			(end -0.7874 -0.4064)
			(stroke
				(width 0.1524)
				(type default)
			)
			(layer "F.SilkS")
		)
		(fp_line
			(start 0.7874 -0.4064)
			(end 0.7874 0.4064)
			(stroke
				(width 0.1524)
				(type default)
			)
			(layer "F.SilkS")
		)
		(fp_line
			(start 0.7874 0.4064)
			(end -0.7874 0.4064)
			(stroke
				(width 0.1524)
				(type default)
			)
			(layer "F.SilkS")
		)
		(fp_line
			(start -0.67945 -0.305054)
			(end -0.12065 -0.305054)
			(stroke
				(width 0.1)
				(type default)
			)
			(layer "F.Fab")
		)
		(fp_line
			(start -0.67945 0.3048)
			(end -0.67945 -0.305054)
			(stroke
				(width 0.1)
				(type default)
			)
			(layer "F.Fab")
		)
		(fp_line
			(start -0.12065 -0.305054)
			(end -0.12065 -0.2794)
			(stroke
				(width 0.1)
				(type default)
			)
			(layer "F.Fab")
		)
		(fp_line
			(start -0.12065 -0.2794)
			(end 0.12065 -0.2794)
			(stroke
				(width 0.1)
				(type default)
			)
			(layer "F.Fab")
		)
		(fp_line
			(start -0.12065 0.2794)
			(end -0.12065 0.3048)
			(stroke
				(width 0.1)
				(type default)
			)
			(layer "F.Fab")
		)
		(fp_line
			(start -0.12065 0.3048)
			(end -0.67945 0.3048)
			(stroke
				(width 0.1)
				(type default)
			)
			(layer "F.Fab")
		)
		(fp_line
			(start 0.120396 0.2794)
			(end -0.12065 0.2794)
			(stroke
				(width 0.1)
				(type default)
			)
			(layer "F.Fab")
		)
		(fp_line
			(start 0.120396 0.3048)
			(end 0.120396 0.2794)
			(stroke
				(width 0.1)
				(type default)
			)
			(layer "F.Fab")
		)
		(fp_line
			(start 0.12065 -0.3048)
			(end 0.67945 -0.3048)
			(stroke
				(width 0.1)
				(type default)
			)
			(layer "F.Fab")
		)
		(fp_line
			(start 0.12065 -0.2794)
			(end 0.12065 -0.3048)
			(stroke
				(width 0.1)
				(type default)
			)
			(layer "F.Fab")
		)
		(fp_line
			(start 0.67945 -0.3048)
			(end 0.67945 0.3048)
			(stroke
				(width 0.1)
				(type default)
			)
			(layer "F.Fab")
		)
		(fp_line
			(start 0.67945 0.3048)
			(end 0.120396 0.3048)
			(stroke
				(width 0.1)
				(type default)
			)
			(layer "F.Fab")
		)
		(pad "1" smd circle
			(at -0.40005 0)
			(size 0 0)
			(layers "F.Cu" "F.Mask" "F.Paste")
			(net "PD_FAN_BUFF_INPUT_U337E")
		)
		(pad "2" smd circle
			(at 0.40005 0)
			(size 0 0)
			(layers "F.Cu" "F.Mask" "F.Paste")
			(net "P3V3_AUX")
		)
	)
	(footprint ""
		(layer "F.Cu")
		(at 25.273 -20.713954)
		(property "Reference" "R4970"
			(at 0 0 0)
			(layer "F.SilkS")
			(hide yes)
			(effects
				(font
					(size 1.27 1.27)
				)
			)
		)
		(property "Value" ""
			(at 0 0 0)
			(layer "F.Fab")
			(effects
				(font
					(size 1.27 1.27)
				)
			)
		)
		(duplicate_pad_numbers_are_jumpers no)
		(fp_line
			(start -0.7874 -0.4064)
			(end 0.7874 -0.4064)
			(stroke
				(width 0.1524)
				(type default)
			)
			(layer "F.SilkS")
		)
		(fp_line
			(start -0.7874 0.4064)
			(end -0.7874 -0.4064)
			(stroke
				(width 0.1524)
				(type default)
			)
			(layer "F.SilkS")
		)
		(fp_line
			(start 0.7874 -0.4064)
			(end 0.7874 0.4064)
			(stroke
				(width 0.1524)
				(type default)
			)
			(layer "F.SilkS")
		)
		(fp_line
			(start 0.7874 0.4064)
			(end -0.7874 0.4064)
			(stroke
				(width 0.1524)
				(type default)
			)
			(layer "F.SilkS")
		)
		(fp_line
			(start -0.67945 -0.305054)
			(end -0.12065 -0.305054)
			(stroke
				(width 0.1)
				(type default)
			)
			(layer "F.Fab")
		)
		(fp_line
			(start -0.67945 0.3048)
			(end -0.67945 -0.305054)
			(stroke
				(width 0.1)
				(type default)
			)
			(layer "F.Fab")
		)
		(fp_line
			(start -0.12065 -0.305054)
			(end -0.12065 -0.2794)
			(stroke
				(width 0.1)
				(type default)
			)
			(layer "F.Fab")
		)
		(fp_line
			(start -0.12065 -0.2794)
			(end 0.12065 -0.2794)
			(stroke
				(width 0.1)
				(type default)
			)
			(layer "F.Fab")
		)
		(fp_line
			(start -0.12065 0.2794)
			(end -0.12065 0.3048)
			(stroke
				(width 0.1)
				(type default)
			)
			(layer "F.Fab")
		)
		(fp_line
			(start -0.12065 0.3048)
			(end -0.67945 0.3048)
			(stroke
				(width 0.1)
				(type default)
			)
			(layer "F.Fab")
		)
		(fp_line
			(start 0.120396 0.2794)
			(end -0.12065 0.2794)
			(stroke
				(width 0.1)
				(type default)
			)
			(layer "F.Fab")
		)
		(fp_line
			(start 0.120396 0.3048)
			(end 0.120396 0.2794)
			(stroke
				(width 0.1)
				(type default)
			)
			(layer "F.Fab")
		)
		(fp_line
			(start 0.12065 -0.3048)
			(end 0.67945 -0.3048)
			(stroke
				(width 0.1)
				(type default)
			)
			(layer "F.Fab")
		)
		(fp_line
			(start 0.12065 -0.2794)
			(end 0.12065 -0.3048)
			(stroke
				(width 0.1)
				(type default)
			)
			(layer "F.Fab")
		)
		(fp_line
			(start 0.67945 -0.3048)
			(end 0.67945 0.3048)
			(stroke
				(width 0.1)
				(type default)
			)
			(layer "F.Fab")
		)
		(fp_line
			(start 0.67945 0.3048)
			(end 0.120396 0.3048)
			(stroke
				(width 0.1)
				(type default)
			)
			(layer "F.Fab")
		)
		(pad "1" smd circle
			(at -0.40005 0)
			(size 0 0)
			(layers "F.Cu" "F.Mask" "F.Paste")
			(net "P52V_FAN_EN_R")
		)
		(pad "2" smd circle
			(at 0.40005 0)
			(size 0 0)
			(layers "F.Cu" "F.Mask" "F.Paste")
			(net "P52V_FAN_EN")
		)
	)
	(footprint ""
		(layer "F.Cu")
		(at 14.859 -128.524)
		(property "Reference" "R5614"
			(at 0 0 0)
			(layer "F.SilkS")
			(hide yes)
			(effects
				(font
					(size 1.27 1.27)
				)
			)
		)
		(property "Value" ""
			(at 0 0 0)
			(layer "F.Fab")
			(effects
				(font
					(size 1.27 1.27)
				)
			)
		)
		(duplicate_pad_numbers_are_jumpers no)
		(fp_line
			(start -0.7874 -0.4064)
			(end 0.7874 -0.4064)
			(stroke
				(width 0.1524)
				(type default)
			)
			(layer "F.SilkS")
		)
		(fp_line
			(start -0.7874 0.4064)
			(end -0.7874 -0.4064)
			(stroke
				(width 0.1524)
				(type default)
			)
			(layer "F.SilkS")
		)
		(fp_line
			(start 0.7874 -0.4064)
			(end 0.7874 0.4064)
			(stroke
				(width 0.1524)
				(type default)
			)
			(layer "F.SilkS")
		)
		(fp_line
			(start 0.7874 0.4064)
			(end -0.7874 0.4064)
			(stroke
				(width 0.1524)
				(type default)
			)
			(layer "F.SilkS")
		)
		(fp_line
			(start -0.67945 -0.305054)
			(end -0.12065 -0.305054)
			(stroke
				(width 0.1)
				(type default)
			)
			(layer "F.Fab")
		)
		(fp_line
			(start -0.67945 0.3048)
			(end -0.67945 -0.305054)
			(stroke
				(width 0.1)
				(type default)
			)
			(layer "F.Fab")
		)
		(fp_line
			(start -0.12065 -0.305054)
			(end -0.12065 -0.2794)
			(stroke
				(width 0.1)
				(type default)
			)
			(layer "F.Fab")
		)
		(fp_line
			(start -0.12065 -0.2794)
			(end 0.12065 -0.2794)
			(stroke
				(width 0.1)
				(type default)
			)
			(layer "F.Fab")
		)
		(fp_line
			(start -0.12065 0.2794)
			(end -0.12065 0.3048)
			(stroke
				(width 0.1)
				(type default)
			)
			(layer "F.Fab")
		)
		(fp_line
			(start -0.12065 0.3048)
			(end -0.67945 0.3048)
			(stroke
				(width 0.1)
				(type default)
			)
			(layer "F.Fab")
		)
		(fp_line
			(start 0.120396 0.2794)
			(end -0.12065 0.2794)
			(stroke
				(width 0.1)
				(type default)
			)
			(layer "F.Fab")
		)
		(fp_line
			(start 0.120396 0.3048)
			(end 0.120396 0.2794)
			(stroke
				(width 0.1)
				(type default)
			)
			(layer "F.Fab")
		)
		(fp_line
			(start 0.12065 -0.3048)
			(end 0.67945 -0.3048)
			(stroke
				(width 0.1)
				(type default)
			)
			(layer "F.Fab")
		)
		(fp_line
			(start 0.12065 -0.2794)
			(end 0.12065 -0.3048)
			(stroke
				(width 0.1)
				(type default)
			)
			(layer "F.Fab")
		)
		(fp_line
			(start 0.67945 -0.3048)
			(end 0.67945 0.3048)
			(stroke
				(width 0.1)
				(type default)
			)
			(layer "F.Fab")
		)
		(fp_line
			(start 0.67945 0.3048)
			(end 0.120396 0.3048)
			(stroke
				(width 0.1)
				(type default)
			)
			(layer "F.Fab")
		)
		(pad "1" smd rect
			(at -0.40005 0 180)
			(size 0.4572 0.508)
			(layers "F.Cu" "F.Mask" "F.Paste")
			(net "FAN_5_TACH_OL")
		)
		(pad "2" smd rect
			(at 0.40005 0 180)
			(size 0.4572 0.508)
			(layers "F.Cu" "F.Mask" "F.Paste")
			(net "FAN_5_TACH_OL_R1")
		)
	)
	(footprint ""
		(layer "F.Cu")
		(at 14.351 -296.799 180)
		(property "Reference" "R5382"
			(at 0 0 180)
			(layer "F.SilkS")
			(hide yes)
			(effects
				(font
					(size 1.27 1.27)
				)
			)
		)
		(property "Value" ""
			(at 0 0 180)
			(layer "F.Fab")
			(effects
				(font
					(size 1.27 1.27)
				)
			)
		)
		(duplicate_pad_numbers_are_jumpers no)
		(fp_line
			(start 0.7874 0.4064)
			(end -0.7874 0.4064)
			(stroke
				(width 0.1524)
				(type default)
			)
			(layer "F.SilkS")
		)
		(fp_line
			(start 0.7874 -0.4064)
			(end 0.7874 0.4064)
			(stroke
				(width 0.1524)
				(type default)
			)
			(layer "F.SilkS")
		)
		(fp_line
			(start -0.7874 0.4064)
			(end -0.7874 -0.4064)
			(stroke
				(width 0.1524)
				(type default)
			)
			(layer "F.SilkS")
		)
		(fp_line
			(start -0.7874 -0.4064)
			(end 0.7874 -0.4064)
			(stroke
				(width 0.1524)
				(type default)
			)
			(layer "F.SilkS")
		)
		(fp_line
			(start 0.67945 0.3048)
			(end 0.120396 0.3048)
			(stroke
				(width 0.1)
				(type default)
			)
			(layer "F.Fab")
		)
		(fp_line
			(start 0.67945 -0.3048)
			(end 0.67945 0.3048)
			(stroke
				(width 0.1)
				(type default)
			)
			(layer "F.Fab")
		)
		(fp_line
			(start 0.12065 -0.2794)
			(end 0.12065 -0.3048)
			(stroke
				(width 0.1)
				(type default)
			)
			(layer "F.Fab")
		)
		(fp_line
			(start 0.12065 -0.3048)
			(end 0.67945 -0.3048)
			(stroke
				(width 0.1)
				(type default)
			)
			(layer "F.Fab")
		)
		(fp_line
			(start 0.120396 0.3048)
			(end 0.120396 0.2794)
			(stroke
				(width 0.1)
				(type default)
			)
			(layer "F.Fab")
		)
		(fp_line
			(start 0.120396 0.2794)
			(end -0.12065 0.2794)
			(stroke
				(width 0.1)
				(type default)
			)
			(layer "F.Fab")
		)
		(fp_line
			(start -0.12065 0.3048)
			(end -0.67945 0.3048)
			(stroke
				(width 0.1)
				(type default)
			)
			(layer "F.Fab")
		)
		(fp_line
			(start -0.12065 0.2794)
			(end -0.12065 0.3048)
			(stroke
				(width 0.1)
				(type default)
			)
			(layer "F.Fab")
		)
		(fp_line
			(start -0.12065 -0.2794)
			(end 0.12065 -0.2794)
			(stroke
				(width 0.1)
				(type default)
			)
			(layer "F.Fab")
		)
		(fp_line
			(start -0.12065 -0.305054)
			(end -0.12065 -0.2794)
			(stroke
				(width 0.1)
				(type default)
			)
			(layer "F.Fab")
		)
		(fp_line
			(start -0.67945 0.3048)
			(end -0.67945 -0.305054)
			(stroke
				(width 0.1)
				(type default)
			)
			(layer "F.Fab")
		)
		(fp_line
			(start -0.67945 -0.305054)
			(end -0.12065 -0.305054)
			(stroke
				(width 0.1)
				(type default)
			)
			(layer "F.Fab")
		)
		(pad "1" smd rect
			(at -0.40005 0)
			(size 0.4572 0.508)
			(layers "F.Cu" "F.Mask" "F.Paste")
			(net "FAN_7_FAIL_LED_R_N")
		)
		(pad "2" smd rect
			(at 0.40005 0)
			(size 0.4572 0.508)
			(layers "F.Cu" "F.Mask" "F.Paste")
			(net "FAN_7_FAIL_R_LED_N")
		)
	)
	(footprint ""
		(layer "F.Cu")
		(at 23.241 -119.126 -90)
		(property "Reference" "R5513"
			(at 0 0 270)
			(layer "F.SilkS")
			(hide yes)
			(effects
				(font
					(size 1.27 1.27)
				)
			)
		)
		(property "Value" ""
			(at 0 0 270)
			(layer "F.Fab")
			(effects
				(font
					(size 1.27 1.27)
				)
			)
		)
		(duplicate_pad_numbers_are_jumpers no)
		(fp_line
			(start -0.7874 0.4064)
			(end -0.7874 -0.4064)
			(stroke
				(width 0.1524)
				(type default)
			)
			(layer "F.SilkS")
		)
		(fp_line
			(start 0.7874 0.4064)
			(end -0.7874 0.4064)
			(stroke
				(width 0.1524)
				(type default)
			)
			(layer "F.SilkS")
		)
		(fp_line
			(start -0.7874 -0.4064)
			(end 0.7874 -0.4064)
			(stroke
				(width 0.1524)
				(type default)
			)
			(layer "F.SilkS")
		)
		(fp_line
			(start 0.7874 -0.4064)
			(end 0.7874 0.4064)
			(stroke
				(width 0.1524)
				(type default)
			)
			(layer "F.SilkS")
		)
		(fp_line
			(start -0.67945 0.3048)
			(end -0.67945 -0.305054)
			(stroke
				(width 0.1)
				(type default)
			)
			(layer "F.Fab")
		)
		(fp_line
			(start -0.12065 0.3048)
			(end -0.67945 0.3048)
			(stroke
				(width 0.1)
				(type default)
			)
			(layer "F.Fab")
		)
		(fp_line
			(start 0.120396 0.3048)
			(end 0.120396 0.2794)
			(stroke
				(width 0.1)
				(type default)
			)
			(layer "F.Fab")
		)
		(fp_line
			(start 0.67945 0.3048)
			(end 0.120396 0.3048)
			(stroke
				(width 0.1)
				(type default)
			)
			(layer "F.Fab")
		)
		(fp_line
			(start -0.12065 0.2794)
			(end -0.12065 0.3048)
			(stroke
				(width 0.1)
				(type default)
			)
			(layer "F.Fab")
		)
		(fp_line
			(start 0.120396 0.2794)
			(end -0.12065 0.2794)
			(stroke
				(width 0.1)
				(type default)
			)
			(layer "F.Fab")
		)
		(fp_line
			(start -0.12065 -0.2794)
			(end 0.12065 -0.2794)
			(stroke
				(width 0.1)
				(type default)
			)
			(layer "F.Fab")
		)
		(fp_line
			(start 0.12065 -0.2794)
			(end 0.12065 -0.3048)
			(stroke
				(width 0.1)
				(type default)
			)
			(layer "F.Fab")
		)
		(fp_line
			(start 0.12065 -0.3048)
			(end 0.67945 -0.3048)
			(stroke
				(width 0.1)
				(type default)
			)
			(layer "F.Fab")
		)
		(fp_line
			(start 0.67945 -0.3048)
			(end 0.67945 0.3048)
			(stroke
				(width 0.1)
				(type default)
			)
			(layer "F.Fab")
		)
		(fp_line
			(start -0.67945 -0.305054)
			(end -0.12065 -0.305054)
			(stroke
				(width 0.1)
				(type default)
			)
			(layer "F.Fab")
		)
		(fp_line
			(start -0.12065 -0.305054)
			(end -0.12065 -0.2794)
			(stroke
				(width 0.1)
				(type default)
			)
			(layer "F.Fab")
		)
		(pad "1" smd circle
			(at -0.40005 0 270)
			(size 0 0)
			(layers "F.Cu" "F.Mask" "F.Paste")
			(net "P3V3_AUX")
		)
		(pad "2" smd circle
			(at 0.40005 0 270)
			(size 0 0)
			(layers "F.Cu" "F.Mask" "F.Paste")
			(net "FAN_2_PWM_BUF")
		)
	)
	(footprint ""
		(layer "F.Cu")
		(at 15.621 -164.338)
		(property "Reference" "C54"
			(at 0 0 0)
			(layer "F.SilkS")
			(hide yes)
			(effects
				(font
					(size 1.27 1.27)
				)
			)
		)
		(property "Value" ""
			(at 0 0 0)
			(layer "F.Fab")
			(effects
				(font
					(size 1.27 1.27)
				)
			)
		)
		(duplicate_pad_numbers_are_jumpers no)
		(fp_line
			(start -0.7874 -0.4064)
			(end 0.7874 -0.4064)
			(stroke
				(width 0.1524)
				(type default)
			)
			(layer "F.SilkS")
		)
		(fp_line
			(start -0.7874 0.4064)
			(end -0.7874 -0.4064)
			(stroke
				(width 0.1524)
				(type default)
			)
			(layer "F.SilkS")
		)
		(fp_line
			(start 0.7874 -0.4064)
			(end 0.7874 0.4064)
			(stroke
				(width 0.1524)
				(type default)
			)
			(layer "F.SilkS")
		)
		(fp_line
			(start 0.7874 0.4064)
			(end -0.7874 0.4064)
			(stroke
				(width 0.1524)
				(type default)
			)
			(layer "F.SilkS")
		)
		(fp_line
			(start -0.67945 -0.305054)
			(end -0.12065 -0.305054)
			(stroke
				(width 0.1)
				(type default)
			)
			(layer "F.Fab")
		)
		(fp_line
			(start -0.67945 0.3048)
			(end -0.67945 -0.305054)
			(stroke
				(width 0.1)
				(type default)
			)
			(layer "F.Fab")
		)
		(fp_line
			(start -0.12065 -0.305054)
			(end -0.12065 -0.2794)
			(stroke
				(width 0.1)
				(type default)
			)
			(layer "F.Fab")
		)
		(fp_line
			(start -0.12065 -0.2794)
			(end 0.12065 -0.2794)
			(stroke
				(width 0.1)
				(type default)
			)
			(layer "F.Fab")
		)
		(fp_line
			(start -0.12065 0.2794)
			(end -0.12065 0.3048)
			(stroke
				(width 0.1)
				(type default)
			)
			(layer "F.Fab")
		)
		(fp_line
			(start -0.12065 0.3048)
			(end -0.67945 0.3048)
			(stroke
				(width 0.1)
				(type default)
			)
			(layer "F.Fab")
		)
		(fp_line
			(start 0.120396 0.2794)
			(end -0.12065 0.2794)
			(stroke
				(width 0.1)
				(type default)
			)
			(layer "F.Fab")
		)
		(fp_line
			(start 0.120396 0.3048)
			(end 0.120396 0.2794)
			(stroke
				(width 0.1)
				(type default)
			)
			(layer "F.Fab")
		)
		(fp_line
			(start 0.12065 -0.3048)
			(end 0.67945 -0.3048)
			(stroke
				(width 0.1)
				(type default)
			)
			(layer "F.Fab")
		)
		(fp_line
			(start 0.12065 -0.2794)
			(end 0.12065 -0.3048)
			(stroke
				(width 0.1)
				(type default)
			)
			(layer "F.Fab")
		)
		(fp_line
			(start 0.67945 -0.3048)
			(end 0.67945 0.3048)
			(stroke
				(width 0.1)
				(type default)
			)
			(layer "F.Fab")
		)
		(fp_line
			(start 0.67945 0.3048)
			(end 0.120396 0.3048)
			(stroke
				(width 0.1)
				(type default)
			)
			(layer "F.Fab")
		)
		(pad "1" smd circle
			(at -0.40005 0)
			(size 0 0)
			(layers "F.Cu" "F.Mask" "F.Paste")
			(net "FAN_1_PRESENT_N")
		)
		(pad "2" smd circle
			(at 0.40005 0)
			(size 0 0)
			(layers "F.Cu" "F.Mask" "F.Paste")
			(net "GND")
		)
	)
	(footprint ""
		(layer "F.Cu")
		(at 25.527 -121.539 180)
		(property "Reference" "R5460"
			(at 0 0 180)
			(layer "F.SilkS")
			(hide yes)
			(effects
				(font
					(size 1.27 1.27)
				)
			)
		)
		(property "Value" ""
			(at 0 0 180)
			(layer "F.Fab")
			(effects
				(font
					(size 1.27 1.27)
				)
			)
		)
		(duplicate_pad_numbers_are_jumpers no)
		(fp_line
			(start 0.7874 0.4064)
			(end -0.7874 0.4064)
			(stroke
				(width 0.1524)
				(type default)
			)
			(layer "F.SilkS")
		)
		(fp_line
			(start 0.7874 -0.4064)
			(end 0.7874 0.4064)
			(stroke
				(width 0.1524)
				(type default)
			)
			(layer "F.SilkS")
		)
		(fp_line
			(start -0.7874 0.4064)
			(end -0.7874 -0.4064)
			(stroke
				(width 0.1524)
				(type default)
			)
			(layer "F.SilkS")
		)
		(fp_line
			(start -0.7874 -0.4064)
			(end 0.7874 -0.4064)
			(stroke
				(width 0.1524)
				(type default)
			)
			(layer "F.SilkS")
		)
		(fp_line
			(start 0.67945 0.3048)
			(end 0.120396 0.3048)
			(stroke
				(width 0.1)
				(type default)
			)
			(layer "F.Fab")
		)
		(fp_line
			(start 0.67945 -0.3048)
			(end 0.67945 0.3048)
			(stroke
				(width 0.1)
				(type default)
			)
			(layer "F.Fab")
		)
		(fp_line
			(start 0.12065 -0.2794)
			(end 0.12065 -0.3048)
			(stroke
				(width 0.1)
				(type default)
			)
			(layer "F.Fab")
		)
		(fp_line
			(start 0.12065 -0.3048)
			(end 0.67945 -0.3048)
			(stroke
				(width 0.1)
				(type default)
			)
			(layer "F.Fab")
		)
		(fp_line
			(start 0.120396 0.3048)
			(end 0.120396 0.2794)
			(stroke
				(width 0.1)
				(type default)
			)
			(layer "F.Fab")
		)
		(fp_line
			(start 0.120396 0.2794)
			(end -0.12065 0.2794)
			(stroke
				(width 0.1)
				(type default)
			)
			(layer "F.Fab")
		)
		(fp_line
			(start -0.12065 0.3048)
			(end -0.67945 0.3048)
			(stroke
				(width 0.1)
				(type default)
			)
			(layer "F.Fab")
		)
		(fp_line
			(start -0.12065 0.2794)
			(end -0.12065 0.3048)
			(stroke
				(width 0.1)
				(type default)
			)
			(layer "F.Fab")
		)
		(fp_line
			(start -0.12065 -0.2794)
			(end 0.12065 -0.2794)
			(stroke
				(width 0.1)
				(type default)
			)
			(layer "F.Fab")
		)
		(fp_line
			(start -0.12065 -0.305054)
			(end -0.12065 -0.2794)
			(stroke
				(width 0.1)
				(type default)
			)
			(layer "F.Fab")
		)
		(fp_line
			(start -0.67945 0.3048)
			(end -0.67945 -0.305054)
			(stroke
				(width 0.1)
				(type default)
			)
			(layer "F.Fab")
		)
		(fp_line
			(start -0.67945 -0.305054)
			(end -0.12065 -0.305054)
			(stroke
				(width 0.1)
				(type default)
			)
			(layer "F.Fab")
		)
		(pad "1" smd circle
			(at -0.40005 0 180)
			(size 0 0)
			(layers "F.Cu" "F.Mask" "F.Paste")
			(net "SMB_PDBV_FAN_SDA")
		)
		(pad "2" smd circle
			(at 0.40005 0 180)
			(size 0 0)
			(layers "F.Cu" "F.Mask" "F.Paste")
			(net "SMB_PDBV_FAN_R_U330_SDA")
		)
	)
	(footprint ""
		(layer "F.Cu")
		(at 14.351 -107.880912 180)
		(property "Reference" "R5203"
			(at 0 0 180)
			(layer "F.SilkS")
			(hide yes)
			(effects
				(font
					(size 1.27 1.27)
				)
			)
		)
		(property "Value" ""
			(at 0 0 180)
			(layer "F.Fab")
			(effects
				(font
					(size 1.27 1.27)
				)
			)
		)
		(duplicate_pad_numbers_are_jumpers no)
		(fp_line
			(start 0.7874 0.4064)
			(end -0.7874 0.4064)
			(stroke
				(width 0.1524)
				(type default)
			)
			(layer "F.SilkS")
		)
		(fp_line
			(start 0.7874 -0.4064)
			(end 0.7874 0.4064)
			(stroke
				(width 0.1524)
				(type default)
			)
			(layer "F.SilkS")
		)
		(fp_line
			(start -0.7874 0.4064)
			(end -0.7874 -0.4064)
			(stroke
				(width 0.1524)
				(type default)
			)
			(layer "F.SilkS")
		)
		(fp_line
			(start -0.7874 -0.4064)
			(end 0.7874 -0.4064)
			(stroke
				(width 0.1524)
				(type default)
			)
			(layer "F.SilkS")
		)
		(fp_line
			(start 0.67945 0.3048)
			(end 0.120396 0.3048)
			(stroke
				(width 0.1)
				(type default)
			)
			(layer "F.Fab")
		)
		(fp_line
			(start 0.67945 -0.3048)
			(end 0.67945 0.3048)
			(stroke
				(width 0.1)
				(type default)
			)
			(layer "F.Fab")
		)
		(fp_line
			(start 0.12065 -0.2794)
			(end 0.12065 -0.3048)
			(stroke
				(width 0.1)
				(type default)
			)
			(layer "F.Fab")
		)
		(fp_line
			(start 0.12065 -0.3048)
			(end 0.67945 -0.3048)
			(stroke
				(width 0.1)
				(type default)
			)
			(layer "F.Fab")
		)
		(fp_line
			(start 0.120396 0.3048)
			(end 0.120396 0.2794)
			(stroke
				(width 0.1)
				(type default)
			)
			(layer "F.Fab")
		)
		(fp_line
			(start 0.120396 0.2794)
			(end -0.12065 0.2794)
			(stroke
				(width 0.1)
				(type default)
			)
			(layer "F.Fab")
		)
		(fp_line
			(start -0.12065 0.3048)
			(end -0.67945 0.3048)
			(stroke
				(width 0.1)
				(type default)
			)
			(layer "F.Fab")
		)
		(fp_line
			(start -0.12065 0.2794)
			(end -0.12065 0.3048)
			(stroke
				(width 0.1)
				(type default)
			)
			(layer "F.Fab")
		)
		(fp_line
			(start -0.12065 -0.2794)
			(end 0.12065 -0.2794)
			(stroke
				(width 0.1)
				(type default)
			)
			(layer "F.Fab")
		)
		(fp_line
			(start -0.12065 -0.305054)
			(end -0.12065 -0.2794)
			(stroke
				(width 0.1)
				(type default)
			)
			(layer "F.Fab")
		)
		(fp_line
			(start -0.67945 0.3048)
			(end -0.67945 -0.305054)
			(stroke
				(width 0.1)
				(type default)
			)
			(layer "F.Fab")
		)
		(fp_line
			(start -0.67945 -0.305054)
			(end -0.12065 -0.305054)
			(stroke
				(width 0.1)
				(type default)
			)
			(layer "F.Fab")
		)
		(pad "1" smd circle
			(at -0.40005 0 180)
			(size 0 0)
			(layers "F.Cu" "F.Mask" "F.Paste")
			(net "SMB_FAN5_SCL")
		)
		(pad "2" smd circle
			(at 0.40005 0 180)
			(size 0 0)
			(layers "F.Cu" "F.Mask" "F.Paste")
			(net "SMB_FAN5_SCL_R")
		)
	)
	(footprint ""
		(layer "F.Cu")
		(at 46.101 -124.079 90)
		(property "Reference" "R5693"
			(at 0 0 90)
			(layer "F.SilkS")
			(hide yes)
			(effects
				(font
					(size 1.27 1.27)
				)
			)
		)
		(property "Value" ""
			(at 0 0 90)
			(layer "F.Fab")
			(effects
				(font
					(size 1.27 1.27)
				)
			)
		)
		(duplicate_pad_numbers_are_jumpers no)
		(fp_line
			(start 0.7874 -0.4064)
			(end 0.7874 0.4064)
			(stroke
				(width 0.1524)
				(type default)
			)
			(layer "F.SilkS")
		)
		(fp_line
			(start -0.7874 -0.4064)
			(end 0.7874 -0.4064)
			(stroke
				(width 0.1524)
				(type default)
			)
			(layer "F.SilkS")
		)
		(fp_line
			(start 0.7874 0.4064)
			(end -0.7874 0.4064)
			(stroke
				(width 0.1524)
				(type default)
			)
			(layer "F.SilkS")
		)
		(fp_line
			(start -0.7874 0.4064)
			(end -0.7874 -0.4064)
			(stroke
				(width 0.1524)
				(type default)
			)
			(layer "F.SilkS")
		)
		(fp_line
			(start -0.12065 -0.305054)
			(end -0.12065 -0.2794)
			(stroke
				(width 0.1)
				(type default)
			)
			(layer "F.Fab")
		)
		(fp_line
			(start -0.67945 -0.305054)
			(end -0.12065 -0.305054)
			(stroke
				(width 0.1)
				(type default)
			)
			(layer "F.Fab")
		)
		(fp_line
			(start 0.67945 -0.3048)
			(end 0.67945 0.3048)
			(stroke
				(width 0.1)
				(type default)
			)
			(layer "F.Fab")
		)
		(fp_line
			(start 0.12065 -0.3048)
			(end 0.67945 -0.3048)
			(stroke
				(width 0.1)
				(type default)
			)
			(layer "F.Fab")
		)
		(fp_line
			(start 0.12065 -0.2794)
			(end 0.12065 -0.3048)
			(stroke
				(width 0.1)
				(type default)
			)
			(layer "F.Fab")
		)
		(fp_line
			(start -0.12065 -0.2794)
			(end 0.12065 -0.2794)
			(stroke
				(width 0.1)
				(type default)
			)
			(layer "F.Fab")
		)
		(fp_line
			(start 0.120396 0.2794)
			(end -0.12065 0.2794)
			(stroke
				(width 0.1)
				(type default)
			)
			(layer "F.Fab")
		)
		(fp_line
			(start -0.12065 0.2794)
			(end -0.12065 0.3048)
			(stroke
				(width 0.1)
				(type default)
			)
			(layer "F.Fab")
		)
		(fp_line
			(start 0.67945 0.3048)
			(end 0.120396 0.3048)
			(stroke
				(width 0.1)
				(type default)
			)
			(layer "F.Fab")
		)
		(fp_line
			(start 0.120396 0.3048)
			(end 0.120396 0.2794)
			(stroke
				(width 0.1)
				(type default)
			)
			(layer "F.Fab")
		)
		(fp_line
			(start -0.12065 0.3048)
			(end -0.67945 0.3048)
			(stroke
				(width 0.1)
				(type default)
			)
			(layer "F.Fab")
		)
		(fp_line
			(start -0.67945 0.3048)
			(end -0.67945 -0.305054)
			(stroke
				(width 0.1)
				(type default)
			)
			(layer "F.Fab")
		)
		(pad "1" smd rect
			(at -0.40005 0 270)
			(size 0.4572 0.508)
			(layers "F.Cu" "F.Mask" "F.Paste")
			(net "P12V_LED_FAN2")
		)
		(pad "2" smd rect
			(at 0.40005 0 270)
			(size 0.4572 0.508)
			(layers "F.Cu" "F.Mask" "F.Paste")
			(net "P12V_LED_R_FAN2")
		)
	)
	(footprint ""
		(layer "F.Cu")
		(at 4.191 -174.244 180)
		(property "Reference" "R4867"
			(at 0 0 180)
			(layer "F.SilkS")
			(hide yes)
			(effects
				(font
					(size 1.27 1.27)
				)
			)
		)
		(property "Value" ""
			(at 0 0 180)
			(layer "F.Fab")
			(effects
				(font
					(size 1.27 1.27)
				)
			)
		)
		(duplicate_pad_numbers_are_jumpers no)
		(fp_line
			(start 0.7874 0.4064)
			(end -0.7874 0.4064)
			(stroke
				(width 0.1524)
				(type default)
			)
			(layer "F.SilkS")
		)
		(fp_line
			(start 0.7874 -0.4064)
			(end 0.7874 0.4064)
			(stroke
				(width 0.1524)
				(type default)
			)
			(layer "F.SilkS")
		)
		(fp_line
			(start -0.7874 0.4064)
			(end -0.7874 -0.4064)
			(stroke
				(width 0.1524)
				(type default)
			)
			(layer "F.SilkS")
		)
		(fp_line
			(start -0.7874 -0.4064)
			(end 0.7874 -0.4064)
			(stroke
				(width 0.1524)
				(type default)
			)
			(layer "F.SilkS")
		)
		(fp_line
			(start 0.67945 0.3048)
			(end 0.120396 0.3048)
			(stroke
				(width 0.1)
				(type default)
			)
			(layer "F.Fab")
		)
		(fp_line
			(start 0.67945 -0.3048)
			(end 0.67945 0.3048)
			(stroke
				(width 0.1)
				(type default)
			)
			(layer "F.Fab")
		)
		(fp_line
			(start 0.12065 -0.2794)
			(end 0.12065 -0.3048)
			(stroke
				(width 0.1)
				(type default)
			)
			(layer "F.Fab")
		)
		(fp_line
			(start 0.12065 -0.3048)
			(end 0.67945 -0.3048)
			(stroke
				(width 0.1)
				(type default)
			)
			(layer "F.Fab")
		)
		(fp_line
			(start 0.120396 0.3048)
			(end 0.120396 0.2794)
			(stroke
				(width 0.1)
				(type default)
			)
			(layer "F.Fab")
		)
		(fp_line
			(start 0.120396 0.2794)
			(end -0.12065 0.2794)
			(stroke
				(width 0.1)
				(type default)
			)
			(layer "F.Fab")
		)
		(fp_line
			(start -0.12065 0.3048)
			(end -0.67945 0.3048)
			(stroke
				(width 0.1)
				(type default)
			)
			(layer "F.Fab")
		)
		(fp_line
			(start -0.12065 0.2794)
			(end -0.12065 0.3048)
			(stroke
				(width 0.1)
				(type default)
			)
			(layer "F.Fab")
		)
		(fp_line
			(start -0.12065 -0.2794)
			(end 0.12065 -0.2794)
			(stroke
				(width 0.1)
				(type default)
			)
			(layer "F.Fab")
		)
		(fp_line
			(start -0.12065 -0.305054)
			(end -0.12065 -0.2794)
			(stroke
				(width 0.1)
				(type default)
			)
			(layer "F.Fab")
		)
		(fp_line
			(start -0.67945 0.3048)
			(end -0.67945 -0.305054)
			(stroke
				(width 0.1)
				(type default)
			)
			(layer "F.Fab")
		)
		(fp_line
			(start -0.67945 -0.305054)
			(end -0.12065 -0.305054)
			(stroke
				(width 0.1)
				(type default)
			)
			(layer "F.Fab")
		)
		(pad "1" smd circle
			(at -0.40005 0 180)
			(size 0 0)
			(layers "F.Cu" "F.Mask" "F.Paste")
			(net "FAN_7_PRSNT_BUF_R_N")
		)
		(pad "2" smd circle
			(at 0.40005 0 180)
			(size 0 0)
			(layers "F.Cu" "F.Mask" "F.Paste")
			(net "FAN_7_PRSNT_BUF_N")
		)
	)
	(footprint ""
		(layer "F.Cu")
		(at 15.113 -23.114 -90)
		(property "Reference" "R5358"
			(at 0 0 270)
			(layer "F.SilkS")
			(hide yes)
			(effects
				(font
					(size 1.27 1.27)
				)
			)
		)
		(property "Value" ""
			(at 0 0 270)
			(layer "F.Fab")
			(effects
				(font
					(size 1.27 1.27)
				)
			)
		)
		(duplicate_pad_numbers_are_jumpers no)
		(fp_line
			(start -0.7874 0.4064)
			(end -0.7874 -0.4064)
			(stroke
				(width 0.1524)
				(type default)
			)
			(layer "F.SilkS")
		)
		(fp_line
			(start 0.7874 0.4064)
			(end -0.7874 0.4064)
			(stroke
				(width 0.1524)
				(type default)
			)
			(layer "F.SilkS")
		)
		(fp_line
			(start -0.7874 -0.4064)
			(end 0.7874 -0.4064)
			(stroke
				(width 0.1524)
				(type default)
			)
			(layer "F.SilkS")
		)
		(fp_line
			(start 0.7874 -0.4064)
			(end 0.7874 0.4064)
			(stroke
				(width 0.1524)
				(type default)
			)
			(layer "F.SilkS")
		)
		(fp_line
			(start -0.67945 0.3048)
			(end -0.67945 -0.305054)
			(stroke
				(width 0.1)
				(type default)
			)
			(layer "F.Fab")
		)
		(fp_line
			(start -0.12065 0.3048)
			(end -0.67945 0.3048)
			(stroke
				(width 0.1)
				(type default)
			)
			(layer "F.Fab")
		)
		(fp_line
			(start 0.120396 0.3048)
			(end 0.120396 0.2794)
			(stroke
				(width 0.1)
				(type default)
			)
			(layer "F.Fab")
		)
		(fp_line
			(start 0.67945 0.3048)
			(end 0.120396 0.3048)
			(stroke
				(width 0.1)
				(type default)
			)
			(layer "F.Fab")
		)
		(fp_line
			(start -0.12065 0.2794)
			(end -0.12065 0.3048)
			(stroke
				(width 0.1)
				(type default)
			)
			(layer "F.Fab")
		)
		(fp_line
			(start 0.120396 0.2794)
			(end -0.12065 0.2794)
			(stroke
				(width 0.1)
				(type default)
			)
			(layer "F.Fab")
		)
		(fp_line
			(start -0.12065 -0.2794)
			(end 0.12065 -0.2794)
			(stroke
				(width 0.1)
				(type default)
			)
			(layer "F.Fab")
		)
		(fp_line
			(start 0.12065 -0.2794)
			(end 0.12065 -0.3048)
			(stroke
				(width 0.1)
				(type default)
			)
			(layer "F.Fab")
		)
		(fp_line
			(start 0.12065 -0.3048)
			(end 0.67945 -0.3048)
			(stroke
				(width 0.1)
				(type default)
			)
			(layer "F.Fab")
		)
		(fp_line
			(start 0.67945 -0.3048)
			(end 0.67945 0.3048)
			(stroke
				(width 0.1)
				(type default)
			)
			(layer "F.Fab")
		)
		(fp_line
			(start -0.67945 -0.305054)
			(end -0.12065 -0.305054)
			(stroke
				(width 0.1)
				(type default)
			)
			(layer "F.Fab")
		)
		(fp_line
			(start -0.12065 -0.305054)
			(end -0.12065 -0.2794)
			(stroke
				(width 0.1)
				(type default)
			)
			(layer "F.Fab")
		)
		(pad "1" smd rect
			(at -0.40005 0 90)
			(size 0.4572 0.508)
			(layers "F.Cu" "F.Mask" "F.Paste")
			(net "FAN_4_FAIL_LED_R_N")
		)
		(pad "2" smd rect
			(at 0.40005 0 90)
			(size 0.4572 0.508)
			(layers "F.Cu" "F.Mask" "F.Paste")
			(net "FAN_4_FAIL_R_LED_N")
		)
	)
	(footprint ""
		(layer "F.Cu")
		(at 44.667932 -255.905 -90)
		(property "Reference" "C2065"
			(at 0 0 270)
			(layer "F.SilkS")
			(hide yes)
			(effects
				(font
					(size 1.27 1.27)
				)
			)
		)
		(property "Value" ""
			(at 0 0 270)
			(layer "F.Fab")
			(effects
				(font
					(size 1.27 1.27)
				)
			)
		)
		(duplicate_pad_numbers_are_jumpers no)
		(fp_line
			(start -0.7874 0.4064)
			(end -0.7874 -0.4064)
			(stroke
				(width 0.1524)
				(type default)
			)
			(layer "F.SilkS")
		)
		(fp_line
			(start 0.7874 0.4064)
			(end -0.7874 0.4064)
			(stroke
				(width 0.1524)
				(type default)
			)
			(layer "F.SilkS")
		)
		(fp_line
			(start -0.7874 -0.4064)
			(end 0.7874 -0.4064)
			(stroke
				(width 0.1524)
				(type default)
			)
			(layer "F.SilkS")
		)
		(fp_line
			(start 0.7874 -0.4064)
			(end 0.7874 0.4064)
			(stroke
				(width 0.1524)
				(type default)
			)
			(layer "F.SilkS")
		)
		(fp_line
			(start -0.67945 0.3048)
			(end -0.67945 -0.305054)
			(stroke
				(width 0.1)
				(type default)
			)
			(layer "F.Fab")
		)
		(fp_line
			(start -0.12065 0.3048)
			(end -0.67945 0.3048)
			(stroke
				(width 0.1)
				(type default)
			)
			(layer "F.Fab")
		)
		(fp_line
			(start 0.120396 0.3048)
			(end 0.120396 0.2794)
			(stroke
				(width 0.1)
				(type default)
			)
			(layer "F.Fab")
		)
		(fp_line
			(start 0.67945 0.3048)
			(end 0.120396 0.3048)
			(stroke
				(width 0.1)
				(type default)
			)
			(layer "F.Fab")
		)
		(fp_line
			(start -0.12065 0.2794)
			(end -0.12065 0.3048)
			(stroke
				(width 0.1)
				(type default)
			)
			(layer "F.Fab")
		)
		(fp_line
			(start 0.120396 0.2794)
			(end -0.12065 0.2794)
			(stroke
				(width 0.1)
				(type default)
			)
			(layer "F.Fab")
		)
		(fp_line
			(start -0.12065 -0.2794)
			(end 0.12065 -0.2794)
			(stroke
				(width 0.1)
				(type default)
			)
			(layer "F.Fab")
		)
		(fp_line
			(start 0.12065 -0.2794)
			(end 0.12065 -0.3048)
			(stroke
				(width 0.1)
				(type default)
			)
			(layer "F.Fab")
		)
		(fp_line
			(start 0.12065 -0.3048)
			(end 0.67945 -0.3048)
			(stroke
				(width 0.1)
				(type default)
			)
			(layer "F.Fab")
		)
		(fp_line
			(start 0.67945 -0.3048)
			(end 0.67945 0.3048)
			(stroke
				(width 0.1)
				(type default)
			)
			(layer "F.Fab")
		)
		(fp_line
			(start -0.67945 -0.305054)
			(end -0.12065 -0.305054)
			(stroke
				(width 0.1)
				(type default)
			)
			(layer "F.Fab")
		)
		(fp_line
			(start -0.12065 -0.305054)
			(end -0.12065 -0.2794)
			(stroke
				(width 0.1)
				(type default)
			)
			(layer "F.Fab")
		)
		(pad "1" smd circle
			(at -0.40005 0 270)
			(size 0 0)
			(layers "F.Cu" "F.Mask" "F.Paste")
			(net "P3V3_AUX")
		)
		(pad "2" smd circle
			(at 0.40005 0 270)
			(size 0 0)
			(layers "F.Cu" "F.Mask" "F.Paste")
			(net "GND")
		)
	)
	(footprint ""
		(layer "F.Cu")
		(at 18.415 -178.816 180)
		(property "Reference" "R5684"
			(at 0 0 180)
			(layer "F.SilkS")
			(hide yes)
			(effects
				(font
					(size 1.27 1.27)
				)
			)
		)
		(property "Value" ""
			(at 0 0 180)
			(layer "F.Fab")
			(effects
				(font
					(size 1.27 1.27)
				)
			)
		)
		(duplicate_pad_numbers_are_jumpers no)
		(fp_line
			(start 0.7874 0.4064)
			(end -0.7874 0.4064)
			(stroke
				(width 0.1524)
				(type default)
			)
			(layer "F.SilkS")
		)
		(fp_line
			(start 0.7874 -0.4064)
			(end 0.7874 0.4064)
			(stroke
				(width 0.1524)
				(type default)
			)
			(layer "F.SilkS")
		)
		(fp_line
			(start -0.7874 0.4064)
			(end -0.7874 -0.4064)
			(stroke
				(width 0.1524)
				(type default)
			)
			(layer "F.SilkS")
		)
		(fp_line
			(start -0.7874 -0.4064)
			(end 0.7874 -0.4064)
			(stroke
				(width 0.1524)
				(type default)
			)
			(layer "F.SilkS")
		)
		(fp_line
			(start 0.67945 0.3048)
			(end 0.120396 0.3048)
			(stroke
				(width 0.1)
				(type default)
			)
			(layer "F.Fab")
		)
		(fp_line
			(start 0.67945 -0.3048)
			(end 0.67945 0.3048)
			(stroke
				(width 0.1)
				(type default)
			)
			(layer "F.Fab")
		)
		(fp_line
			(start 0.12065 -0.2794)
			(end 0.12065 -0.3048)
			(stroke
				(width 0.1)
				(type default)
			)
			(layer "F.Fab")
		)
		(fp_line
			(start 0.12065 -0.3048)
			(end 0.67945 -0.3048)
			(stroke
				(width 0.1)
				(type default)
			)
			(layer "F.Fab")
		)
		(fp_line
			(start 0.120396 0.3048)
			(end 0.120396 0.2794)
			(stroke
				(width 0.1)
				(type default)
			)
			(layer "F.Fab")
		)
		(fp_line
			(start 0.120396 0.2794)
			(end -0.12065 0.2794)
			(stroke
				(width 0.1)
				(type default)
			)
			(layer "F.Fab")
		)
		(fp_line
			(start -0.12065 0.3048)
			(end -0.67945 0.3048)
			(stroke
				(width 0.1)
				(type default)
			)
			(layer "F.Fab")
		)
		(fp_line
			(start -0.12065 0.2794)
			(end -0.12065 0.3048)
			(stroke
				(width 0.1)
				(type default)
			)
			(layer "F.Fab")
		)
		(fp_line
			(start -0.12065 -0.2794)
			(end 0.12065 -0.2794)
			(stroke
				(width 0.1)
				(type default)
			)
			(layer "F.Fab")
		)
		(fp_line
			(start -0.12065 -0.305054)
			(end -0.12065 -0.2794)
			(stroke
				(width 0.1)
				(type default)
			)
			(layer "F.Fab")
		)
		(fp_line
			(start -0.67945 0.3048)
			(end -0.67945 -0.305054)
			(stroke
				(width 0.1)
				(type default)
			)
			(layer "F.Fab")
		)
		(fp_line
			(start -0.67945 -0.305054)
			(end -0.12065 -0.305054)
			(stroke
				(width 0.1)
				(type default)
			)
			(layer "F.Fab")
		)
		(pad "1" smd circle
			(at -0.40005 0 180)
			(size 0 0)
			(layers "F.Cu" "F.Mask" "F.Paste")
			(net "P3V3_AUX")
		)
		(pad "2" smd circle
			(at 0.40005 0 180)
			(size 0 0)
			(layers "F.Cu" "F.Mask" "F.Paste")
			(net "FM_BOARD_ID1")
		)
	)
	(footprint ""
		(layer "F.Cu")
		(at 37.465 -32.217868)
		(property "Reference" "R5236"
			(at 0 0 0)
			(layer "F.SilkS")
			(hide yes)
			(effects
				(font
					(size 1.27 1.27)
				)
			)
		)
		(property "Value" ""
			(at 0 0 0)
			(layer "F.Fab")
			(effects
				(font
					(size 1.27 1.27)
				)
			)
		)
		(duplicate_pad_numbers_are_jumpers no)
		(fp_line
			(start -0.7874 -0.4064)
			(end 0.7874 -0.4064)
			(stroke
				(width 0.1524)
				(type default)
			)
			(layer "F.SilkS")
		)
		(fp_line
			(start -0.7874 0.4064)
			(end -0.7874 -0.4064)
			(stroke
				(width 0.1524)
				(type default)
			)
			(layer "F.SilkS")
		)
		(fp_line
			(start 0.7874 -0.4064)
			(end 0.7874 0.4064)
			(stroke
				(width 0.1524)
				(type default)
			)
			(layer "F.SilkS")
		)
		(fp_line
			(start 0.7874 0.4064)
			(end -0.7874 0.4064)
			(stroke
				(width 0.1524)
				(type default)
			)
			(layer "F.SilkS")
		)
		(fp_line
			(start -0.67945 -0.305054)
			(end -0.12065 -0.305054)
			(stroke
				(width 0.1)
				(type default)
			)
			(layer "F.Fab")
		)
		(fp_line
			(start -0.67945 0.3048)
			(end -0.67945 -0.305054)
			(stroke
				(width 0.1)
				(type default)
			)
			(layer "F.Fab")
		)
		(fp_line
			(start -0.12065 -0.305054)
			(end -0.12065 -0.2794)
			(stroke
				(width 0.1)
				(type default)
			)
			(layer "F.Fab")
		)
		(fp_line
			(start -0.12065 -0.2794)
			(end 0.12065 -0.2794)
			(stroke
				(width 0.1)
				(type default)
			)
			(layer "F.Fab")
		)
		(fp_line
			(start -0.12065 0.2794)
			(end -0.12065 0.3048)
			(stroke
				(width 0.1)
				(type default)
			)
			(layer "F.Fab")
		)
		(fp_line
			(start -0.12065 0.3048)
			(end -0.67945 0.3048)
			(stroke
				(width 0.1)
				(type default)
			)
			(layer "F.Fab")
		)
		(fp_line
			(start 0.120396 0.2794)
			(end -0.12065 0.2794)
			(stroke
				(width 0.1)
				(type default)
			)
			(layer "F.Fab")
		)
		(fp_line
			(start 0.120396 0.3048)
			(end 0.120396 0.2794)
			(stroke
				(width 0.1)
				(type default)
			)
			(layer "F.Fab")
		)
		(fp_line
			(start 0.12065 -0.3048)
			(end 0.67945 -0.3048)
			(stroke
				(width 0.1)
				(type default)
			)
			(layer "F.Fab")
		)
		(fp_line
			(start 0.12065 -0.2794)
			(end 0.12065 -0.3048)
			(stroke
				(width 0.1)
				(type default)
			)
			(layer "F.Fab")
		)
		(fp_line
			(start 0.67945 -0.3048)
			(end 0.67945 0.3048)
			(stroke
				(width 0.1)
				(type default)
			)
			(layer "F.Fab")
		)
		(fp_line
			(start 0.67945 0.3048)
			(end 0.120396 0.3048)
			(stroke
				(width 0.1)
				(type default)
			)
			(layer "F.Fab")
		)
		(pad "1" smd circle
			(at -0.40005 0)
			(size 0 0)
			(layers "F.Cu" "F.Mask" "F.Paste")
			(net "FAN_3_PWM_OL")
		)
		(pad "2" smd circle
			(at 0.40005 0)
			(size 0 0)
			(layers "F.Cu" "F.Mask" "F.Paste")
			(net "FAN_3_PWM_OL_R")
		)
	)
	(footprint ""
		(layer "F.Cu")
		(at 36.322 -101.784912)
		(property "Reference" "D277"
			(at -0.889 1.532382 0)
			(unlocked yes)
			(layer "F.SilkS")
			(effects
				(font
					(size 0.7874 0.5842)
					(thickness 0.1524)
				)
				(justify left)
			)
		)
		(property "Value" ""
			(at 0 0 0)
			(layer "F.Fab")
			(effects
				(font
					(size 1.27 1.27)
				)
			)
		)
		(duplicate_pad_numbers_are_jumpers no)
		(fp_line
			(start -0.854964 -0.450088)
			(end -0.854964 0.450088)
			(stroke
				(width 0.1524)
				(type default)
			)
			(layer "F.SilkS")
		)
		(fp_line
			(start -0.854964 0.450088)
			(end 0.925068 0.450088)
			(stroke
				(width 0.1524)
				(type default)
			)
			(layer "F.SilkS")
		)
		(fp_line
			(start 0.845058 0.4064)
			(end 0.845058 -0.381)
			(stroke
				(width 0.1524)
				(type default)
			)
			(layer "F.SilkS")
		)
		(fp_line
			(start 0.870458 -0.2794)
			(end 0.845058 0.4064)
			(stroke
				(width 0.1524)
				(type default)
			)
			(layer "F.SilkS")
		)
		(fp_line
			(start 0.94488 -0.450088)
			(end -0.854964 -0.450088)
			(stroke
				(width 0.1524)
				(type default)
			)
			(layer "F.SilkS")
		)
		(fp_line
			(start 0.94488 0.450088)
			(end 0.94488 -0.450088)
			(stroke
				(width 0.1524)
				(type default)
			)
			(layer "F.SilkS")
		)
		(fp_line
			(start -0.54991 -0.350012)
			(end -0.54991 0.350012)
			(stroke
				(width 0.1)
				(type default)
			)
			(layer "F.Fab")
		)
		(fp_line
			(start -0.54991 0.350012)
			(end 0.54991 0.350012)
			(stroke
				(width 0.1)
				(type default)
			)
			(layer "F.Fab")
		)
		(fp_line
			(start 0.54991 -0.350012)
			(end -0.54991 -0.350012)
			(stroke
				(width 0.1)
				(type default)
			)
			(layer "F.Fab")
		)
		(fp_line
			(start 0.54991 0.350012)
			(end 0.54991 -0.350012)
			(stroke
				(width 0.1)
				(type default)
			)
			(layer "F.Fab")
		)
		(fp_text user "+"
			(at -0.762 1.042162 180)
			(unlocked yes)
			(layer "F.SilkS")
			(effects
				(font
					(size 1.905 1.4224)
					(thickness 0.1524)
				)
				(justify left)
			)
		)
		(fp_text user "-"
			(at 2.286 0.407162 180)
			(unlocked yes)
			(layer "F.SilkS")
			(effects
				(font
					(size 1.905 1.4224)
					(thickness 0.1524)
				)
				(justify left)
			)
		)
		(fp_text user "+"
			(at -0.808228 0.239014 180)
			(unlocked yes)
			(layer "F.Fab")
			(effects
				(font
					(size 1.905 1.4224)
					(thickness 0.1524)
				)
				(justify left)
			)
		)
		(fp_text user "-"
			(at 2.48539 0.239014 180)
			(unlocked yes)
			(layer "F.Fab")
			(effects
				(font
					(size 1.905 1.4224)
					(thickness 0.1524)
				)
				(justify left)
			)
		)
		(pad "A" smd rect
			(at -0.424942 0)
			(size 0.5588 0.6096)
			(layers "F.Cu" "F.Mask" "F.Paste")
			(net "GND")
		)
		(pad "C" smd rect
			(at 0.424942 0 180)
			(size 0.5588 0.6096)
			(layers "F.Cu" "F.Mask" "F.Paste")
			(net "FAN_2_TACH_OL_D")
		)
	)
	(footprint ""
		(layer "F.Cu")
		(at 31.115 -27.432 90)
		(property "Reference" "R5324"
			(at 0 0 90)
			(layer "F.SilkS")
			(hide yes)
			(effects
				(font
					(size 1.27 1.27)
				)
			)
		)
		(property "Value" ""
			(at 0 0 90)
			(layer "F.Fab")
			(effects
				(font
					(size 1.27 1.27)
				)
			)
		)
		(duplicate_pad_numbers_are_jumpers no)
		(fp_line
			(start 1.2954 -0.5842)
			(end 1.2954 0.5842)
			(stroke
				(width 0.1524)
				(type default)
			)
			(layer "F.SilkS")
		)
		(fp_line
			(start -1.2954 -0.5842)
			(end 1.2954 -0.5842)
			(stroke
				(width 0.1524)
				(type default)
			)
			(layer "F.SilkS")
		)
		(fp_line
			(start 1.2954 0.5842)
			(end -1.2954 0.5842)
			(stroke
				(width 0.1524)
				(type default)
			)
			(layer "F.SilkS")
		)
		(fp_line
			(start -1.2954 0.5842)
			(end -1.2954 -0.5842)
			(stroke
				(width 0.1524)
				(type default)
			)
			(layer "F.SilkS")
		)
		(fp_line
			(start 0.8636 -0.4572)
			(end 0.8636 -0.406654)
			(stroke
				(width 0.1)
				(type default)
			)
			(layer "F.Fab")
		)
		(fp_line
			(start -0.8636 -0.4572)
			(end 0.8636 -0.4572)
			(stroke
				(width 0.1)
				(type default)
			)
			(layer "F.Fab")
		)
		(fp_line
			(start 1.1938 -0.406654)
			(end 1.1938 0.4064)
			(stroke
				(width 0.1)
				(type default)
			)
			(layer "F.Fab")
		)
		(fp_line
			(start 0.8636 -0.406654)
			(end 1.1938 -0.406654)
			(stroke
				(width 0.1)
				(type default)
			)
			(layer "F.Fab")
		)
		(fp_line
			(start -0.8636 -0.406654)
			(end -0.8636 -0.4572)
			(stroke
				(width 0.1)
				(type default)
			)
			(layer "F.Fab")
		)
		(fp_line
			(start -1.1938 -0.406654)
			(end -0.8636 -0.406654)
			(stroke
				(width 0.1)
				(type default)
			)
			(layer "F.Fab")
		)
		(fp_line
			(start 1.1938 0.4064)
			(end 0.8636 0.4064)
			(stroke
				(width 0.1)
				(type default)
			)
			(layer "F.Fab")
		)
		(fp_line
			(start 0.8636 0.4064)
			(end 0.8636 0.4572)
			(stroke
				(width 0.1)
				(type default)
			)
			(layer "F.Fab")
		)
		(fp_line
			(start -0.8636 0.4064)
			(end -1.1938 0.4064)
			(stroke
				(width 0.1)
				(type default)
			)
			(layer "F.Fab")
		)
		(fp_line
			(start -1.1938 0.4064)
			(end -1.1938 -0.406654)
			(stroke
				(width 0.1)
				(type default)
			)
			(layer "F.Fab")
		)
		(fp_line
			(start -0.8636 0.4318)
			(end -0.8636 0.4064)
			(stroke
				(width 0.1)
				(type default)
			)
			(layer "F.Fab")
		)
		(fp_line
			(start 0.8636 0.4572)
			(end -0.8636 0.4572)
			(stroke
				(width 0.1)
				(type default)
			)
			(layer "F.Fab")
		)
		(fp_line
			(start -0.8636 0.4572)
			(end -0.8636 0.4318)
			(stroke
				(width 0.1)
				(type default)
			)
			(layer "F.Fab")
		)
		(pad "1" smd rect
			(at -0.7366 0)
			(size 0.7112 0.8128)
			(layers "F.Cu" "F.Mask" "F.Paste")
			(net "P52V_FAN_3")
		)
		(pad "2" smd rect
			(at 0.7366 0)
			(size 0.7112 0.8128)
			(layers "F.Cu" "F.Mask" "F.Paste")
			(net "FAN_3_TACH_IL_R")
		)
	)
	(footprint ""
		(layer "F.Cu")
		(at 18.669 -199.037956 180)
		(property "Reference" "D256"
			(at 1.524 1.087374 0)
			(unlocked yes)
			(layer "F.SilkS")
			(effects
				(font
					(size 0.7874 0.5842)
					(thickness 0.1524)
				)
				(justify left)
			)
		)
		(property "Value" ""
			(at 0 0 180)
			(layer "F.Fab")
			(effects
				(font
					(size 1.27 1.27)
				)
			)
		)
		(duplicate_pad_numbers_are_jumpers no)
		(fp_line
			(start 0.94488 0.450088)
			(end 0.94488 -0.450088)
			(stroke
				(width 0.1524)
				(type default)
			)
			(layer "F.SilkS")
		)
		(fp_line
			(start 0.94488 -0.450088)
			(end -0.854964 -0.450088)
			(stroke
				(width 0.1524)
				(type default)
			)
			(layer "F.SilkS")
		)
		(fp_line
			(start 0.870458 -0.2794)
			(end 0.845058 0.4064)
			(stroke
				(width 0.1524)
				(type default)
			)
			(layer "F.SilkS")
		)
		(fp_line
			(start 0.845058 0.4064)
			(end 0.845058 -0.381)
			(stroke
				(width 0.1524)
				(type default)
			)
			(layer "F.SilkS")
		)
		(fp_line
			(start -0.854964 0.450088)
			(end 0.925068 0.450088)
			(stroke
				(width 0.1524)
				(type default)
			)
			(layer "F.SilkS")
		)
		(fp_line
			(start -0.854964 -0.450088)
			(end -0.854964 0.450088)
			(stroke
				(width 0.1524)
				(type default)
			)
			(layer "F.SilkS")
		)
		(fp_line
			(start 0.54991 0.350012)
			(end 0.54991 -0.350012)
			(stroke
				(width 0.1)
				(type default)
			)
			(layer "F.Fab")
		)
		(fp_line
			(start 0.54991 -0.350012)
			(end -0.54991 -0.350012)
			(stroke
				(width 0.1)
				(type default)
			)
			(layer "F.Fab")
		)
		(fp_line
			(start -0.54991 0.350012)
			(end 0.54991 0.350012)
			(stroke
				(width 0.1)
				(type default)
			)
			(layer "F.Fab")
		)
		(fp_line
			(start -0.54991 -0.350012)
			(end -0.54991 0.350012)
			(stroke
				(width 0.1)
				(type default)
			)
			(layer "F.Fab")
		)
		(fp_text user "-"
			(at 2.032 -0.441706 0)
			(unlocked yes)
			(layer "F.SilkS")
			(effects
				(font
					(size 1.905 1.4224)
					(thickness 0.1524)
				)
				(justify left)
			)
		)
		(fp_text user "+"
			(at -0.8636 0.396494 0)
			(unlocked yes)
			(layer "F.SilkS")
			(effects
				(font
					(size 1.905 1.4224)
					(thickness 0.1524)
				)
				(justify left)
			)
		)
		(fp_text user "-"
			(at 2.48539 0.239014 0)
			(unlocked yes)
			(layer "F.Fab")
			(effects
				(font
					(size 1.905 1.4224)
					(thickness 0.1524)
				)
				(justify left)
			)
		)
		(fp_text user "+"
			(at -0.808228 0.239014 0)
			(unlocked yes)
			(layer "F.Fab")
			(effects
				(font
					(size 1.905 1.4224)
					(thickness 0.1524)
				)
				(justify left)
			)
		)
		(pad "A" smd rect
			(at -0.424942 0 180)
			(size 0.5588 0.6096)
			(layers "F.Cu" "F.Mask" "F.Paste")
			(net "GND")
		)
		(pad "C" smd rect
			(at 0.424942 0)
			(size 0.5588 0.6096)
			(layers "F.Cu" "F.Mask" "F.Paste")
			(net "FAN_6_PWM_IL_R")
		)
	)
	(footprint ""
		(layer "F.Cu")
		(at 25.654 -143.891 -90)
		(property "Reference" "R4786"
			(at 0 0 270)
			(layer "F.SilkS")
			(hide yes)
			(effects
				(font
					(size 1.27 1.27)
				)
			)
		)
		(property "Value" ""
			(at 0 0 270)
			(layer "F.Fab")
			(effects
				(font
					(size 1.27 1.27)
				)
			)
		)
		(duplicate_pad_numbers_are_jumpers no)
		(fp_line
			(start -0.7874 0.4064)
			(end -0.7874 -0.4064)
			(stroke
				(width 0.1524)
				(type default)
			)
			(layer "F.SilkS")
		)
		(fp_line
			(start 0.7874 0.4064)
			(end -0.7874 0.4064)
			(stroke
				(width 0.1524)
				(type default)
			)
			(layer "F.SilkS")
		)
		(fp_line
			(start -0.7874 -0.4064)
			(end 0.7874 -0.4064)
			(stroke
				(width 0.1524)
				(type default)
			)
			(layer "F.SilkS")
		)
		(fp_line
			(start 0.7874 -0.4064)
			(end 0.7874 0.4064)
			(stroke
				(width 0.1524)
				(type default)
			)
			(layer "F.SilkS")
		)
		(fp_line
			(start -0.67945 0.3048)
			(end -0.67945 -0.305054)
			(stroke
				(width 0.1)
				(type default)
			)
			(layer "F.Fab")
		)
		(fp_line
			(start -0.12065 0.3048)
			(end -0.67945 0.3048)
			(stroke
				(width 0.1)
				(type default)
			)
			(layer "F.Fab")
		)
		(fp_line
			(start 0.120396 0.3048)
			(end 0.120396 0.2794)
			(stroke
				(width 0.1)
				(type default)
			)
			(layer "F.Fab")
		)
		(fp_line
			(start 0.67945 0.3048)
			(end 0.120396 0.3048)
			(stroke
				(width 0.1)
				(type default)
			)
			(layer "F.Fab")
		)
		(fp_line
			(start -0.12065 0.2794)
			(end -0.12065 0.3048)
			(stroke
				(width 0.1)
				(type default)
			)
			(layer "F.Fab")
		)
		(fp_line
			(start 0.120396 0.2794)
			(end -0.12065 0.2794)
			(stroke
				(width 0.1)
				(type default)
			)
			(layer "F.Fab")
		)
		(fp_line
			(start -0.12065 -0.2794)
			(end 0.12065 -0.2794)
			(stroke
				(width 0.1)
				(type default)
			)
			(layer "F.Fab")
		)
		(fp_line
			(start 0.12065 -0.2794)
			(end 0.12065 -0.3048)
			(stroke
				(width 0.1)
				(type default)
			)
			(layer "F.Fab")
		)
		(fp_line
			(start 0.12065 -0.3048)
			(end 0.67945 -0.3048)
			(stroke
				(width 0.1)
				(type default)
			)
			(layer "F.Fab")
		)
		(fp_line
			(start 0.67945 -0.3048)
			(end 0.67945 0.3048)
			(stroke
				(width 0.1)
				(type default)
			)
			(layer "F.Fab")
		)
		(fp_line
			(start -0.67945 -0.305054)
			(end -0.12065 -0.305054)
			(stroke
				(width 0.1)
				(type default)
			)
			(layer "F.Fab")
		)
		(fp_line
			(start -0.12065 -0.305054)
			(end -0.12065 -0.2794)
			(stroke
				(width 0.1)
				(type default)
			)
			(layer "F.Fab")
		)
		(pad "1" smd circle
			(at -0.40005 0 270)
			(size 0 0)
			(layers "F.Cu" "F.Mask" "F.Paste")
			(net "SMB_FAN1_R_SDA")
		)
		(pad "2" smd circle
			(at 0.40005 0 270)
			(size 0 0)
			(layers "F.Cu" "F.Mask" "F.Paste")
			(net "SMB_FAN1_SDA")
		)
	)
	(footprint ""
		(layer "F.Cu")
		(at 43.561 -175.895)
		(property "Reference" "R5100"
			(at 0 0 0)
			(layer "F.SilkS")
			(hide yes)
			(effects
				(font
					(size 1.27 1.27)
				)
			)
		)
		(property "Value" ""
			(at 0 0 0)
			(layer "F.Fab")
			(effects
				(font
					(size 1.27 1.27)
				)
			)
		)
		(duplicate_pad_numbers_are_jumpers no)
		(fp_line
			(start -0.7874 -0.4064)
			(end 0.7874 -0.4064)
			(stroke
				(width 0.1524)
				(type default)
			)
			(layer "F.SilkS")
		)
		(fp_line
			(start -0.7874 0.4064)
			(end -0.7874 -0.4064)
			(stroke
				(width 0.1524)
				(type default)
			)
			(layer "F.SilkS")
		)
		(fp_line
			(start 0.7874 -0.4064)
			(end 0.7874 0.4064)
			(stroke
				(width 0.1524)
				(type default)
			)
			(layer "F.SilkS")
		)
		(fp_line
			(start 0.7874 0.4064)
			(end -0.7874 0.4064)
			(stroke
				(width 0.1524)
				(type default)
			)
			(layer "F.SilkS")
		)
		(fp_line
			(start -0.67945 -0.305054)
			(end -0.12065 -0.305054)
			(stroke
				(width 0.1)
				(type default)
			)
			(layer "F.Fab")
		)
		(fp_line
			(start -0.67945 0.3048)
			(end -0.67945 -0.305054)
			(stroke
				(width 0.1)
				(type default)
			)
			(layer "F.Fab")
		)
		(fp_line
			(start -0.12065 -0.305054)
			(end -0.12065 -0.2794)
			(stroke
				(width 0.1)
				(type default)
			)
			(layer "F.Fab")
		)
		(fp_line
			(start -0.12065 -0.2794)
			(end 0.12065 -0.2794)
			(stroke
				(width 0.1)
				(type default)
			)
			(layer "F.Fab")
		)
		(fp_line
			(start -0.12065 0.2794)
			(end -0.12065 0.3048)
			(stroke
				(width 0.1)
				(type default)
			)
			(layer "F.Fab")
		)
		(fp_line
			(start -0.12065 0.3048)
			(end -0.67945 0.3048)
			(stroke
				(width 0.1)
				(type default)
			)
			(layer "F.Fab")
		)
		(fp_line
			(start 0.120396 0.2794)
			(end -0.12065 0.2794)
			(stroke
				(width 0.1)
				(type default)
			)
			(layer "F.Fab")
		)
		(fp_line
			(start 0.120396 0.3048)
			(end 0.120396 0.2794)
			(stroke
				(width 0.1)
				(type default)
			)
			(layer "F.Fab")
		)
		(fp_line
			(start 0.12065 -0.3048)
			(end 0.67945 -0.3048)
			(stroke
				(width 0.1)
				(type default)
			)
			(layer "F.Fab")
		)
		(fp_line
			(start 0.12065 -0.2794)
			(end 0.12065 -0.3048)
			(stroke
				(width 0.1)
				(type default)
			)
			(layer "F.Fab")
		)
		(fp_line
			(start 0.67945 -0.3048)
			(end 0.67945 0.3048)
			(stroke
				(width 0.1)
				(type default)
			)
			(layer "F.Fab")
		)
		(fp_line
			(start 0.67945 0.3048)
			(end 0.120396 0.3048)
			(stroke
				(width 0.1)
				(type default)
			)
			(layer "F.Fab")
		)
		(pad "1" smd circle
			(at -0.40005 0)
			(size 0 0)
			(layers "F.Cu" "F.Mask" "F.Paste")
			(net "FAN_3_OK_LED")
		)
		(pad "2" smd circle
			(at 0.40005 0)
			(size 0 0)
			(layers "F.Cu" "F.Mask" "F.Paste")
			(net "FAN_3_OK_R_LED")
		)
	)
	(footprint ""
		(layer "F.Cu")
		(at 14.0589 -131.064 180)
		(property "Reference" "R5592"
			(at 0 0 180)
			(layer "F.SilkS")
			(hide yes)
			(effects
				(font
					(size 1.27 1.27)
				)
			)
		)
		(property "Value" ""
			(at 0 0 180)
			(layer "F.Fab")
			(effects
				(font
					(size 1.27 1.27)
				)
			)
		)
		(duplicate_pad_numbers_are_jumpers no)
		(fp_line
			(start 0.7874 0.4064)
			(end -0.7874 0.4064)
			(stroke
				(width 0.1524)
				(type default)
			)
			(layer "F.SilkS")
		)
		(fp_line
			(start 0.7874 -0.4064)
			(end 0.7874 0.4064)
			(stroke
				(width 0.1524)
				(type default)
			)
			(layer "F.SilkS")
		)
		(fp_line
			(start -0.7874 0.4064)
			(end -0.7874 -0.4064)
			(stroke
				(width 0.1524)
				(type default)
			)
			(layer "F.SilkS")
		)
		(fp_line
			(start -0.7874 -0.4064)
			(end 0.7874 -0.4064)
			(stroke
				(width 0.1524)
				(type default)
			)
			(layer "F.SilkS")
		)
		(fp_line
			(start 0.67945 0.3048)
			(end 0.120396 0.3048)
			(stroke
				(width 0.1)
				(type default)
			)
			(layer "F.Fab")
		)
		(fp_line
			(start 0.67945 -0.3048)
			(end 0.67945 0.3048)
			(stroke
				(width 0.1)
				(type default)
			)
			(layer "F.Fab")
		)
		(fp_line
			(start 0.12065 -0.2794)
			(end 0.12065 -0.3048)
			(stroke
				(width 0.1)
				(type default)
			)
			(layer "F.Fab")
		)
		(fp_line
			(start 0.12065 -0.3048)
			(end 0.67945 -0.3048)
			(stroke
				(width 0.1)
				(type default)
			)
			(layer "F.Fab")
		)
		(fp_line
			(start 0.120396 0.3048)
			(end 0.120396 0.2794)
			(stroke
				(width 0.1)
				(type default)
			)
			(layer "F.Fab")
		)
		(fp_line
			(start 0.120396 0.2794)
			(end -0.12065 0.2794)
			(stroke
				(width 0.1)
				(type default)
			)
			(layer "F.Fab")
		)
		(fp_line
			(start -0.12065 0.3048)
			(end -0.67945 0.3048)
			(stroke
				(width 0.1)
				(type default)
			)
			(layer "F.Fab")
		)
		(fp_line
			(start -0.12065 0.2794)
			(end -0.12065 0.3048)
			(stroke
				(width 0.1)
				(type default)
			)
			(layer "F.Fab")
		)
		(fp_line
			(start -0.12065 -0.2794)
			(end 0.12065 -0.2794)
			(stroke
				(width 0.1)
				(type default)
			)
			(layer "F.Fab")
		)
		(fp_line
			(start -0.12065 -0.305054)
			(end -0.12065 -0.2794)
			(stroke
				(width 0.1)
				(type default)
			)
			(layer "F.Fab")
		)
		(fp_line
			(start -0.67945 0.3048)
			(end -0.67945 -0.305054)
			(stroke
				(width 0.1)
				(type default)
			)
			(layer "F.Fab")
		)
		(fp_line
			(start -0.67945 -0.305054)
			(end -0.12065 -0.305054)
			(stroke
				(width 0.1)
				(type default)
			)
			(layer "F.Fab")
		)
		(pad "1" smd rect
			(at -0.40005 0)
			(size 0.4572 0.508)
			(layers "F.Cu" "F.Mask" "F.Paste")
			(net "FAN_6_TACH_IL")
		)
		(pad "2" smd rect
			(at 0.40005 0)
			(size 0.4572 0.508)
			(layers "F.Cu" "F.Mask" "F.Paste")
			(net "FAN_6_TACH_IL_R2")
		)
	)
	(footprint ""
		(layer "F.Cu")
		(at 8.709914 -66.986912 180)
		(property "Reference" "C2061"
			(at 0 0 180)
			(layer "F.SilkS")
			(hide yes)
			(effects
				(font
					(size 1.27 1.27)
				)
			)
		)
		(property "Value" ""
			(at 0 0 180)
			(layer "F.Fab")
			(effects
				(font
					(size 1.27 1.27)
				)
			)
		)
		(duplicate_pad_numbers_are_jumpers no)
		(fp_line
			(start 0.7874 0.4064)
			(end -0.7874 0.4064)
			(stroke
				(width 0.1524)
				(type default)
			)
			(layer "F.SilkS")
		)
		(fp_line
			(start 0.7874 -0.4064)
			(end 0.7874 0.4064)
			(stroke
				(width 0.1524)
				(type default)
			)
			(layer "F.SilkS")
		)
		(fp_line
			(start -0.7874 0.4064)
			(end -0.7874 -0.4064)
			(stroke
				(width 0.1524)
				(type default)
			)
			(layer "F.SilkS")
		)
		(fp_line
			(start -0.7874 -0.4064)
			(end 0.7874 -0.4064)
			(stroke
				(width 0.1524)
				(type default)
			)
			(layer "F.SilkS")
		)
		(fp_line
			(start 0.67945 0.3048)
			(end 0.120396 0.3048)
			(stroke
				(width 0.1)
				(type default)
			)
			(layer "F.Fab")
		)
		(fp_line
			(start 0.67945 -0.3048)
			(end 0.67945 0.3048)
			(stroke
				(width 0.1)
				(type default)
			)
			(layer "F.Fab")
		)
		(fp_line
			(start 0.12065 -0.2794)
			(end 0.12065 -0.3048)
			(stroke
				(width 0.1)
				(type default)
			)
			(layer "F.Fab")
		)
		(fp_line
			(start 0.12065 -0.3048)
			(end 0.67945 -0.3048)
			(stroke
				(width 0.1)
				(type default)
			)
			(layer "F.Fab")
		)
		(fp_line
			(start 0.120396 0.3048)
			(end 0.120396 0.2794)
			(stroke
				(width 0.1)
				(type default)
			)
			(layer "F.Fab")
		)
		(fp_line
			(start 0.120396 0.2794)
			(end -0.12065 0.2794)
			(stroke
				(width 0.1)
				(type default)
			)
			(layer "F.Fab")
		)
		(fp_line
			(start -0.12065 0.3048)
			(end -0.67945 0.3048)
			(stroke
				(width 0.1)
				(type default)
			)
			(layer "F.Fab")
		)
		(fp_line
			(start -0.12065 0.2794)
			(end -0.12065 0.3048)
			(stroke
				(width 0.1)
				(type default)
			)
			(layer "F.Fab")
		)
		(fp_line
			(start -0.12065 -0.2794)
			(end 0.12065 -0.2794)
			(stroke
				(width 0.1)
				(type default)
			)
			(layer "F.Fab")
		)
		(fp_line
			(start -0.12065 -0.305054)
			(end -0.12065 -0.2794)
			(stroke
				(width 0.1)
				(type default)
			)
			(layer "F.Fab")
		)
		(fp_line
			(start -0.67945 0.3048)
			(end -0.67945 -0.305054)
			(stroke
				(width 0.1)
				(type default)
			)
			(layer "F.Fab")
		)
		(fp_line
			(start -0.67945 -0.305054)
			(end -0.12065 -0.305054)
			(stroke
				(width 0.1)
				(type default)
			)
			(layer "F.Fab")
		)
		(pad "1" smd circle
			(at -0.40005 0 180)
			(size 0 0)
			(layers "F.Cu" "F.Mask" "F.Paste")
			(net "P3V3_AUX")
		)
		(pad "2" smd circle
			(at 0.40005 0 180)
			(size 0 0)
			(layers "F.Cu" "F.Mask" "F.Paste")
			(net "GND")
		)
	)
	(footprint ""
		(layer "F.Cu")
		(at 32.893 -27.362912)
		(property "Reference" "D286"
			(at -5.461 0.084582 0)
			(unlocked yes)
			(layer "F.SilkS")
			(effects
				(font
					(size 0.7874 0.5842)
					(thickness 0.1524)
				)
				(justify left)
			)
		)
		(property "Value" ""
			(at 0 0 0)
			(layer "F.Fab")
			(effects
				(font
					(size 1.27 1.27)
				)
			)
		)
		(duplicate_pad_numbers_are_jumpers no)
		(fp_line
			(start -0.854964 -0.450088)
			(end -0.854964 0.450088)
			(stroke
				(width 0.1524)
				(type default)
			)
			(layer "F.SilkS")
		)
		(fp_line
			(start -0.854964 0.450088)
			(end 0.925068 0.450088)
			(stroke
				(width 0.1524)
				(type default)
			)
			(layer "F.SilkS")
		)
		(fp_line
			(start 0.845058 0.4064)
			(end 0.845058 -0.381)
			(stroke
				(width 0.1524)
				(type default)
			)
			(layer "F.SilkS")
		)
		(fp_line
			(start 0.870458 -0.2794)
			(end 0.845058 0.4064)
			(stroke
				(width 0.1524)
				(type default)
			)
			(layer "F.SilkS")
		)
		(fp_line
			(start 0.94488 -0.450088)
			(end -0.854964 -0.450088)
			(stroke
				(width 0.1524)
				(type default)
			)
			(layer "F.SilkS")
		)
		(fp_line
			(start 0.94488 0.450088)
			(end 0.94488 -0.450088)
			(stroke
				(width 0.1524)
				(type default)
			)
			(layer "F.SilkS")
		)
		(fp_line
			(start -0.54991 -0.350012)
			(end -0.54991 0.350012)
			(stroke
				(width 0.1)
				(type default)
			)
			(layer "F.Fab")
		)
		(fp_line
			(start -0.54991 0.350012)
			(end 0.54991 0.350012)
			(stroke
				(width 0.1)
				(type default)
			)
			(layer "F.Fab")
		)
		(fp_line
			(start 0.54991 -0.350012)
			(end -0.54991 -0.350012)
			(stroke
				(width 0.1)
				(type default)
			)
			(layer "F.Fab")
		)
		(fp_line
			(start 0.54991 0.350012)
			(end 0.54991 -0.350012)
			(stroke
				(width 0.1)
				(type default)
			)
			(layer "F.Fab")
		)
		(fp_text user "+"
			(at 0.1016 1.346962 180)
			(unlocked yes)
			(layer "F.SilkS")
			(effects
				(font
					(size 1.905 1.4224)
					(thickness 0.1524)
				)
				(justify left)
			)
		)
		(fp_text user "-"
			(at 1.651 1.042162 180)
			(unlocked yes)
			(layer "F.SilkS")
			(effects
				(font
					(size 1.905 1.4224)
					(thickness 0.1524)
				)
				(justify left)
			)
		)
		(fp_text user "+"
			(at -0.808228 0.239014 180)
			(unlocked yes)
			(layer "F.Fab")
			(effects
				(font
					(size 1.905 1.4224)
					(thickness 0.1524)
				)
				(justify left)
			)
		)
		(fp_text user "-"
			(at 2.48539 0.239014 180)
			(unlocked yes)
			(layer "F.Fab")
			(effects
				(font
					(size 1.905 1.4224)
					(thickness 0.1524)
				)
				(justify left)
			)
		)
		(pad "A" smd rect
			(at -0.424942 0)
			(size 0.5588 0.6096)
			(layers "F.Cu" "F.Mask" "F.Paste")
			(net "GND")
		)
		(pad "C" smd rect
			(at 0.424942 0 180)
			(size 0.5588 0.6096)
			(layers "F.Cu" "F.Mask" "F.Paste")
			(net "FAN_3_PWM_IL_R")
		)
	)
	(footprint ""
		(layer "F.Cu")
		(at 18.034 -133.985 90)
		(property "Reference" "R4945"
			(at 0 0 90)
			(layer "F.SilkS")
			(hide yes)
			(effects
				(font
					(size 1.27 1.27)
				)
			)
		)
		(property "Value" ""
			(at 0 0 90)
			(layer "F.Fab")
			(effects
				(font
					(size 1.27 1.27)
				)
			)
		)
		(duplicate_pad_numbers_are_jumpers no)
		(fp_line
			(start 0.7874 -0.4064)
			(end 0.7874 0.4064)
			(stroke
				(width 0.1524)
				(type default)
			)
			(layer "F.SilkS")
		)
		(fp_line
			(start -0.7874 -0.4064)
			(end 0.7874 -0.4064)
			(stroke
				(width 0.1524)
				(type default)
			)
			(layer "F.SilkS")
		)
		(fp_line
			(start 0.7874 0.4064)
			(end -0.7874 0.4064)
			(stroke
				(width 0.1524)
				(type default)
			)
			(layer "F.SilkS")
		)
		(fp_line
			(start -0.7874 0.4064)
			(end -0.7874 -0.4064)
			(stroke
				(width 0.1524)
				(type default)
			)
			(layer "F.SilkS")
		)
		(fp_line
			(start -0.12065 -0.305054)
			(end -0.12065 -0.2794)
			(stroke
				(width 0.1)
				(type default)
			)
			(layer "F.Fab")
		)
		(fp_line
			(start -0.67945 -0.305054)
			(end -0.12065 -0.305054)
			(stroke
				(width 0.1)
				(type default)
			)
			(layer "F.Fab")
		)
		(fp_line
			(start 0.67945 -0.3048)
			(end 0.67945 0.3048)
			(stroke
				(width 0.1)
				(type default)
			)
			(layer "F.Fab")
		)
		(fp_line
			(start 0.12065 -0.3048)
			(end 0.67945 -0.3048)
			(stroke
				(width 0.1)
				(type default)
			)
			(layer "F.Fab")
		)
		(fp_line
			(start 0.12065 -0.2794)
			(end 0.12065 -0.3048)
			(stroke
				(width 0.1)
				(type default)
			)
			(layer "F.Fab")
		)
		(fp_line
			(start -0.12065 -0.2794)
			(end 0.12065 -0.2794)
			(stroke
				(width 0.1)
				(type default)
			)
			(layer "F.Fab")
		)
		(fp_line
			(start 0.120396 0.2794)
			(end -0.12065 0.2794)
			(stroke
				(width 0.1)
				(type default)
			)
			(layer "F.Fab")
		)
		(fp_line
			(start -0.12065 0.2794)
			(end -0.12065 0.3048)
			(stroke
				(width 0.1)
				(type default)
			)
			(layer "F.Fab")
		)
		(fp_line
			(start 0.67945 0.3048)
			(end 0.120396 0.3048)
			(stroke
				(width 0.1)
				(type default)
			)
			(layer "F.Fab")
		)
		(fp_line
			(start 0.120396 0.3048)
			(end 0.120396 0.2794)
			(stroke
				(width 0.1)
				(type default)
			)
			(layer "F.Fab")
		)
		(fp_line
			(start -0.12065 0.3048)
			(end -0.67945 0.3048)
			(stroke
				(width 0.1)
				(type default)
			)
			(layer "F.Fab")
		)
		(fp_line
			(start -0.67945 0.3048)
			(end -0.67945 -0.305054)
			(stroke
				(width 0.1)
				(type default)
			)
			(layer "F.Fab")
		)
		(pad "1" smd circle
			(at -0.40005 0 90)
			(size 0 0)
			(layers "F.Cu" "F.Mask" "F.Paste")
			(net "MAX31790_U330_WD_START")
		)
		(pad "2" smd circle
			(at 0.40005 0 90)
			(size 0 0)
			(layers "F.Cu" "F.Mask" "F.Paste")
			(net "P3V3_AUX")
		)
	)
	(footprint ""
		(layer "F.Cu")
		(at 29.21 -107.188 -90)
		(property "Reference" "R5520"
			(at 0 0 270)
			(layer "F.SilkS")
			(hide yes)
			(effects
				(font
					(size 1.27 1.27)
				)
			)
		)
		(property "Value" ""
			(at 0 0 270)
			(layer "F.Fab")
			(effects
				(font
					(size 1.27 1.27)
				)
			)
		)
		(duplicate_pad_numbers_are_jumpers no)
		(fp_line
			(start -0.7874 0.4064)
			(end -0.7874 -0.4064)
			(stroke
				(width 0.1524)
				(type default)
			)
			(layer "F.SilkS")
		)
		(fp_line
			(start 0.7874 0.4064)
			(end -0.7874 0.4064)
			(stroke
				(width 0.1524)
				(type default)
			)
			(layer "F.SilkS")
		)
		(fp_line
			(start -0.7874 -0.4064)
			(end 0.7874 -0.4064)
			(stroke
				(width 0.1524)
				(type default)
			)
			(layer "F.SilkS")
		)
		(fp_line
			(start 0.7874 -0.4064)
			(end 0.7874 0.4064)
			(stroke
				(width 0.1524)
				(type default)
			)
			(layer "F.SilkS")
		)
		(fp_line
			(start -0.67945 0.3048)
			(end -0.67945 -0.305054)
			(stroke
				(width 0.1)
				(type default)
			)
			(layer "F.Fab")
		)
		(fp_line
			(start -0.12065 0.3048)
			(end -0.67945 0.3048)
			(stroke
				(width 0.1)
				(type default)
			)
			(layer "F.Fab")
		)
		(fp_line
			(start 0.120396 0.3048)
			(end 0.120396 0.2794)
			(stroke
				(width 0.1)
				(type default)
			)
			(layer "F.Fab")
		)
		(fp_line
			(start 0.67945 0.3048)
			(end 0.120396 0.3048)
			(stroke
				(width 0.1)
				(type default)
			)
			(layer "F.Fab")
		)
		(fp_line
			(start -0.12065 0.2794)
			(end -0.12065 0.3048)
			(stroke
				(width 0.1)
				(type default)
			)
			(layer "F.Fab")
		)
		(fp_line
			(start 0.120396 0.2794)
			(end -0.12065 0.2794)
			(stroke
				(width 0.1)
				(type default)
			)
			(layer "F.Fab")
		)
		(fp_line
			(start -0.12065 -0.2794)
			(end 0.12065 -0.2794)
			(stroke
				(width 0.1)
				(type default)
			)
			(layer "F.Fab")
		)
		(fp_line
			(start 0.12065 -0.2794)
			(end 0.12065 -0.3048)
			(stroke
				(width 0.1)
				(type default)
			)
			(layer "F.Fab")
		)
		(fp_line
			(start 0.12065 -0.3048)
			(end 0.67945 -0.3048)
			(stroke
				(width 0.1)
				(type default)
			)
			(layer "F.Fab")
		)
		(fp_line
			(start 0.67945 -0.3048)
			(end 0.67945 0.3048)
			(stroke
				(width 0.1)
				(type default)
			)
			(layer "F.Fab")
		)
		(fp_line
			(start -0.67945 -0.305054)
			(end -0.12065 -0.305054)
			(stroke
				(width 0.1)
				(type default)
			)
			(layer "F.Fab")
		)
		(fp_line
			(start -0.12065 -0.305054)
			(end -0.12065 -0.2794)
			(stroke
				(width 0.1)
				(type default)
			)
			(layer "F.Fab")
		)
		(pad "1" smd circle
			(at -0.40005 0 270)
			(size 0 0)
			(layers "F.Cu" "F.Mask" "F.Paste")
			(net "P3V3_AUX")
		)
		(pad "2" smd circle
			(at 0.40005 0 270)
			(size 0 0)
			(layers "F.Cu" "F.Mask" "F.Paste")
			(net "FAN_5_PWM")
		)
	)
	(footprint ""
		(layer "F.Cu")
		(at 32.766 -210.594956)
		(property "Reference" "R5304"
			(at 0 0 0)
			(layer "F.SilkS")
			(hide yes)
			(effects
				(font
					(size 1.27 1.27)
				)
			)
		)
		(property "Value" ""
			(at 0 0 0)
			(layer "F.Fab")
			(effects
				(font
					(size 1.27 1.27)
				)
			)
		)
		(duplicate_pad_numbers_are_jumpers no)
		(fp_line
			(start -1.2954 -0.5842)
			(end 1.2954 -0.5842)
			(stroke
				(width 0.1524)
				(type default)
			)
			(layer "F.SilkS")
		)
		(fp_line
			(start -1.2954 0.5842)
			(end -1.2954 -0.5842)
			(stroke
				(width 0.1524)
				(type default)
			)
			(layer "F.SilkS")
		)
		(fp_line
			(start 1.2954 -0.5842)
			(end 1.2954 0.5842)
			(stroke
				(width 0.1524)
				(type default)
			)
			(layer "F.SilkS")
		)
		(fp_line
			(start 1.2954 0.5842)
			(end -1.2954 0.5842)
			(stroke
				(width 0.1524)
				(type default)
			)
			(layer "F.SilkS")
		)
		(fp_line
			(start -1.1938 -0.406654)
			(end -0.8636 -0.406654)
			(stroke
				(width 0.1)
				(type default)
			)
			(layer "F.Fab")
		)
		(fp_line
			(start -1.1938 0.4064)
			(end -1.1938 -0.406654)
			(stroke
				(width 0.1)
				(type default)
			)
			(layer "F.Fab")
		)
		(fp_line
			(start -0.8636 -0.4572)
			(end 0.8636 -0.4572)
			(stroke
				(width 0.1)
				(type default)
			)
			(layer "F.Fab")
		)
		(fp_line
			(start -0.8636 -0.406654)
			(end -0.8636 -0.4572)
			(stroke
				(width 0.1)
				(type default)
			)
			(layer "F.Fab")
		)
		(fp_line
			(start -0.8636 0.4064)
			(end -1.1938 0.4064)
			(stroke
				(width 0.1)
				(type default)
			)
			(layer "F.Fab")
		)
		(fp_line
			(start -0.8636 0.4318)
			(end -0.8636 0.4064)
			(stroke
				(width 0.1)
				(type default)
			)
			(layer "F.Fab")
		)
		(fp_line
			(start -0.8636 0.4572)
			(end -0.8636 0.4318)
			(stroke
				(width 0.1)
				(type default)
			)
			(layer "F.Fab")
		)
		(fp_line
			(start 0.8636 -0.4572)
			(end 0.8636 -0.406654)
			(stroke
				(width 0.1)
				(type default)
			)
			(layer "F.Fab")
		)
		(fp_line
			(start 0.8636 -0.406654)
			(end 1.1938 -0.406654)
			(stroke
				(width 0.1)
				(type default)
			)
			(layer "F.Fab")
		)
		(fp_line
			(start 0.8636 0.4064)
			(end 0.8636 0.4572)
			(stroke
				(width 0.1)
				(type default)
			)
			(layer "F.Fab")
		)
		(fp_line
			(start 0.8636 0.4572)
			(end -0.8636 0.4572)
			(stroke
				(width 0.1)
				(type default)
			)
			(layer "F.Fab")
		)
		(fp_line
			(start 1.1938 -0.406654)
			(end 1.1938 0.4064)
			(stroke
				(width 0.1)
				(type default)
			)
			(layer "F.Fab")
		)
		(fp_line
			(start 1.1938 0.4064)
			(end 0.8636 0.4064)
			(stroke
				(width 0.1)
				(type default)
			)
			(layer "F.Fab")
		)
		(pad "1" smd rect
			(at -0.7366 0 270)
			(size 0.7112 0.8128)
			(layers "F.Cu" "F.Mask" "F.Paste")
			(net "P52V_FAN_1")
		)
		(pad "2" smd rect
			(at 0.7366 0 270)
			(size 0.7112 0.8128)
			(layers "F.Cu" "F.Mask" "F.Paste")
			(net "FAN_1_TACH_IL_R")
		)
	)
	(footprint ""
		(layer "F.Cu")
		(at 36.322 -28.661868)
		(property "Reference" "D284"
			(at 3.302 0.875538 0)
			(unlocked yes)
			(layer "F.SilkS")
			(effects
				(font
					(size 0.7874 0.5842)
					(thickness 0.1524)
				)
				(justify left)
			)
		)
		(property "Value" ""
			(at 0 0 0)
			(layer "F.Fab")
			(effects
				(font
					(size 1.27 1.27)
				)
			)
		)
		(duplicate_pad_numbers_are_jumpers no)
		(fp_line
			(start -0.854964 -0.450088)
			(end -0.854964 0.450088)
			(stroke
				(width 0.1524)
				(type default)
			)
			(layer "F.SilkS")
		)
		(fp_line
			(start -0.854964 0.450088)
			(end 0.925068 0.450088)
			(stroke
				(width 0.1524)
				(type default)
			)
			(layer "F.SilkS")
		)
		(fp_line
			(start 0.845058 0.4064)
			(end 0.845058 -0.381)
			(stroke
				(width 0.1524)
				(type default)
			)
			(layer "F.SilkS")
		)
		(fp_line
			(start 0.870458 -0.2794)
			(end 0.845058 0.4064)
			(stroke
				(width 0.1524)
				(type default)
			)
			(layer "F.SilkS")
		)
		(fp_line
			(start 0.94488 -0.450088)
			(end -0.854964 -0.450088)
			(stroke
				(width 0.1524)
				(type default)
			)
			(layer "F.SilkS")
		)
		(fp_line
			(start 0.94488 0.450088)
			(end 0.94488 -0.450088)
			(stroke
				(width 0.1524)
				(type default)
			)
			(layer "F.SilkS")
		)
		(fp_line
			(start -0.54991 -0.350012)
			(end -0.54991 0.350012)
			(stroke
				(width 0.1)
				(type default)
			)
			(layer "F.Fab")
		)
		(fp_line
			(start -0.54991 0.350012)
			(end 0.54991 0.350012)
			(stroke
				(width 0.1)
				(type default)
			)
			(layer "F.Fab")
		)
		(fp_line
			(start 0.54991 -0.350012)
			(end -0.54991 -0.350012)
			(stroke
				(width 0.1)
				(type default)
			)
			(layer "F.Fab")
		)
		(fp_line
			(start 0.54991 0.350012)
			(end 0.54991 -0.350012)
			(stroke
				(width 0.1)
				(type default)
			)
			(layer "F.Fab")
		)
		(fp_text user "+"
			(at -0.635 0.309118 180)
			(unlocked yes)
			(layer "F.SilkS")
			(effects
				(font
					(size 1.905 1.4224)
					(thickness 0.1524)
				)
				(justify left)
			)
		)
		(fp_text user "-"
			(at 2.159 0.309118 180)
			(unlocked yes)
			(layer "F.SilkS")
			(effects
				(font
					(size 1.905 1.4224)
					(thickness 0.1524)
				)
				(justify left)
			)
		)
		(fp_text user "+"
			(at -0.808228 0.239014 180)
			(unlocked yes)
			(layer "F.Fab")
			(effects
				(font
					(size 1.905 1.4224)
					(thickness 0.1524)
				)
				(justify left)
			)
		)
		(fp_text user "-"
			(at 2.48539 0.239014 180)
			(unlocked yes)
			(layer "F.Fab")
			(effects
				(font
					(size 1.905 1.4224)
					(thickness 0.1524)
				)
				(justify left)
			)
		)
		(pad "A" smd rect
			(at -0.424942 0)
			(size 0.5588 0.6096)
			(layers "F.Cu" "F.Mask" "F.Paste")
			(net "GND")
		)
		(pad "C" smd rect
			(at 0.424942 0 180)
			(size 0.5588 0.6096)
			(layers "F.Cu" "F.Mask" "F.Paste")
			(net "FAN_3_TACH_IL_D")
		)
	)
	(footprint ""
		(layer "F.Cu")
		(at 37.846 -135.128 180)
		(property "Reference" "R5599"
			(at 0 0 180)
			(layer "F.SilkS")
			(hide yes)
			(effects
				(font
					(size 1.27 1.27)
				)
			)
		)
		(property "Value" ""
			(at 0 0 180)
			(layer "F.Fab")
			(effects
				(font
					(size 1.27 1.27)
				)
			)
		)
		(duplicate_pad_numbers_are_jumpers no)
		(fp_line
			(start 0.7874 0.4064)
			(end -0.7874 0.4064)
			(stroke
				(width 0.1524)
				(type default)
			)
			(layer "F.SilkS")
		)
		(fp_line
			(start 0.7874 -0.4064)
			(end 0.7874 0.4064)
			(stroke
				(width 0.1524)
				(type default)
			)
			(layer "F.SilkS")
		)
		(fp_line
			(start -0.7874 0.4064)
			(end -0.7874 -0.4064)
			(stroke
				(width 0.1524)
				(type default)
			)
			(layer "F.SilkS")
		)
		(fp_line
			(start -0.7874 -0.4064)
			(end 0.7874 -0.4064)
			(stroke
				(width 0.1524)
				(type default)
			)
			(layer "F.SilkS")
		)
		(fp_line
			(start 0.67945 0.3048)
			(end 0.120396 0.3048)
			(stroke
				(width 0.1)
				(type default)
			)
			(layer "F.Fab")
		)
		(fp_line
			(start 0.67945 -0.3048)
			(end 0.67945 0.3048)
			(stroke
				(width 0.1)
				(type default)
			)
			(layer "F.Fab")
		)
		(fp_line
			(start 0.12065 -0.2794)
			(end 0.12065 -0.3048)
			(stroke
				(width 0.1)
				(type default)
			)
			(layer "F.Fab")
		)
		(fp_line
			(start 0.12065 -0.3048)
			(end 0.67945 -0.3048)
			(stroke
				(width 0.1)
				(type default)
			)
			(layer "F.Fab")
		)
		(fp_line
			(start 0.120396 0.3048)
			(end 0.120396 0.2794)
			(stroke
				(width 0.1)
				(type default)
			)
			(layer "F.Fab")
		)
		(fp_line
			(start 0.120396 0.2794)
			(end -0.12065 0.2794)
			(stroke
				(width 0.1)
				(type default)
			)
			(layer "F.Fab")
		)
		(fp_line
			(start -0.12065 0.3048)
			(end -0.67945 0.3048)
			(stroke
				(width 0.1)
				(type default)
			)
			(layer "F.Fab")
		)
		(fp_line
			(start -0.12065 0.2794)
			(end -0.12065 0.3048)
			(stroke
				(width 0.1)
				(type default)
			)
			(layer "F.Fab")
		)
		(fp_line
			(start -0.12065 -0.2794)
			(end 0.12065 -0.2794)
			(stroke
				(width 0.1)
				(type default)
			)
			(layer "F.Fab")
		)
		(fp_line
			(start -0.12065 -0.305054)
			(end -0.12065 -0.2794)
			(stroke
				(width 0.1)
				(type default)
			)
			(layer "F.Fab")
		)
		(fp_line
			(start -0.67945 0.3048)
			(end -0.67945 -0.305054)
			(stroke
				(width 0.1)
				(type default)
			)
			(layer "F.Fab")
		)
		(fp_line
			(start -0.67945 -0.305054)
			(end -0.12065 -0.305054)
			(stroke
				(width 0.1)
				(type default)
			)
			(layer "F.Fab")
		)
		(pad "1" smd rect
			(at -0.40005 0)
			(size 0.4572 0.508)
			(layers "F.Cu" "F.Mask" "F.Paste")
			(net "FAN_1_TACH_IL")
		)
		(pad "2" smd rect
			(at 0.40005 0)
			(size 0.4572 0.508)
			(layers "F.Cu" "F.Mask" "F.Paste")
			(net "FAN_1_TACH_IL_R1")
		)
	)
	(footprint ""
		(layer "F.Cu")
		(at 33.274 -185.039 180)
		(property "Reference" "R513"
			(at 0 0 180)
			(layer "F.SilkS")
			(hide yes)
			(effects
				(font
					(size 1.27 1.27)
				)
			)
		)
		(property "Value" ""
			(at 0 0 180)
			(layer "F.Fab")
			(effects
				(font
					(size 1.27 1.27)
				)
			)
		)
		(duplicate_pad_numbers_are_jumpers no)
		(fp_line
			(start 0.7874 0.4064)
			(end -0.7874 0.4064)
			(stroke
				(width 0.1524)
				(type default)
			)
			(layer "F.SilkS")
		)
		(fp_line
			(start 0.7874 -0.4064)
			(end 0.7874 0.4064)
			(stroke
				(width 0.1524)
				(type default)
			)
			(layer "F.SilkS")
		)
		(fp_line
			(start -0.7874 0.4064)
			(end -0.7874 -0.4064)
			(stroke
				(width 0.1524)
				(type default)
			)
			(layer "F.SilkS")
		)
		(fp_line
			(start -0.7874 -0.4064)
			(end 0.7874 -0.4064)
			(stroke
				(width 0.1524)
				(type default)
			)
			(layer "F.SilkS")
		)
		(fp_line
			(start 0.67945 0.3048)
			(end 0.120396 0.3048)
			(stroke
				(width 0.1)
				(type default)
			)
			(layer "F.Fab")
		)
		(fp_line
			(start 0.67945 -0.3048)
			(end 0.67945 0.3048)
			(stroke
				(width 0.1)
				(type default)
			)
			(layer "F.Fab")
		)
		(fp_line
			(start 0.12065 -0.2794)
			(end 0.12065 -0.3048)
			(stroke
				(width 0.1)
				(type default)
			)
			(layer "F.Fab")
		)
		(fp_line
			(start 0.12065 -0.3048)
			(end 0.67945 -0.3048)
			(stroke
				(width 0.1)
				(type default)
			)
			(layer "F.Fab")
		)
		(fp_line
			(start 0.120396 0.3048)
			(end 0.120396 0.2794)
			(stroke
				(width 0.1)
				(type default)
			)
			(layer "F.Fab")
		)
		(fp_line
			(start 0.120396 0.2794)
			(end -0.12065 0.2794)
			(stroke
				(width 0.1)
				(type default)
			)
			(layer "F.Fab")
		)
		(fp_line
			(start -0.12065 0.3048)
			(end -0.67945 0.3048)
			(stroke
				(width 0.1)
				(type default)
			)
			(layer "F.Fab")
		)
		(fp_line
			(start -0.12065 0.2794)
			(end -0.12065 0.3048)
			(stroke
				(width 0.1)
				(type default)
			)
			(layer "F.Fab")
		)
		(fp_line
			(start -0.12065 -0.2794)
			(end 0.12065 -0.2794)
			(stroke
				(width 0.1)
				(type default)
			)
			(layer "F.Fab")
		)
		(fp_line
			(start -0.12065 -0.305054)
			(end -0.12065 -0.2794)
			(stroke
				(width 0.1)
				(type default)
			)
			(layer "F.Fab")
		)
		(fp_line
			(start -0.67945 0.3048)
			(end -0.67945 -0.305054)
			(stroke
				(width 0.1)
				(type default)
			)
			(layer "F.Fab")
		)
		(fp_line
			(start -0.67945 -0.305054)
			(end -0.12065 -0.305054)
			(stroke
				(width 0.1)
				(type default)
			)
			(layer "F.Fab")
		)
		(pad "1" smd circle
			(at -0.40005 0 180)
			(size 0 0)
			(layers "F.Cu" "F.Mask" "F.Paste")
			(net "P52V_FAN_BUFF_EN_R")
		)
		(pad "2" smd circle
			(at 0.40005 0 180)
			(size 0 0)
			(layers "F.Cu" "F.Mask" "F.Paste")
			(net "P52V_FAN_EN")
		)
	)
	(footprint ""
		(layer "F.Cu")
		(at 37.338 -295.91)
		(property "Reference" "R5689"
			(at 0 0 0)
			(layer "F.SilkS")
			(hide yes)
			(effects
				(font
					(size 1.27 1.27)
				)
			)
		)
		(property "Value" ""
			(at 0 0 0)
			(layer "F.Fab")
			(effects
				(font
					(size 1.27 1.27)
				)
			)
		)
		(duplicate_pad_numbers_are_jumpers no)
		(fp_line
			(start -0.7874 -0.4064)
			(end 0.7874 -0.4064)
			(stroke
				(width 0.1524)
				(type default)
			)
			(layer "F.SilkS")
		)
		(fp_line
			(start -0.7874 0.4064)
			(end -0.7874 -0.4064)
			(stroke
				(width 0.1524)
				(type default)
			)
			(layer "F.SilkS")
		)
		(fp_line
			(start 0.7874 -0.4064)
			(end 0.7874 0.4064)
			(stroke
				(width 0.1524)
				(type default)
			)
			(layer "F.SilkS")
		)
		(fp_line
			(start 0.7874 0.4064)
			(end -0.7874 0.4064)
			(stroke
				(width 0.1524)
				(type default)
			)
			(layer "F.SilkS")
		)
		(fp_line
			(start -0.67945 -0.305054)
			(end -0.12065 -0.305054)
			(stroke
				(width 0.1)
				(type default)
			)
			(layer "F.Fab")
		)
		(fp_line
			(start -0.67945 0.3048)
			(end -0.67945 -0.305054)
			(stroke
				(width 0.1)
				(type default)
			)
			(layer "F.Fab")
		)
		(fp_line
			(start -0.12065 -0.305054)
			(end -0.12065 -0.2794)
			(stroke
				(width 0.1)
				(type default)
			)
			(layer "F.Fab")
		)
		(fp_line
			(start -0.12065 -0.2794)
			(end 0.12065 -0.2794)
			(stroke
				(width 0.1)
				(type default)
			)
			(layer "F.Fab")
		)
		(fp_line
			(start -0.12065 0.2794)
			(end -0.12065 0.3048)
			(stroke
				(width 0.1)
				(type default)
			)
			(layer "F.Fab")
		)
		(fp_line
			(start -0.12065 0.3048)
			(end -0.67945 0.3048)
			(stroke
				(width 0.1)
				(type default)
			)
			(layer "F.Fab")
		)
		(fp_line
			(start 0.120396 0.2794)
			(end -0.12065 0.2794)
			(stroke
				(width 0.1)
				(type default)
			)
			(layer "F.Fab")
		)
		(fp_line
			(start 0.120396 0.3048)
			(end 0.120396 0.2794)
			(stroke
				(width 0.1)
				(type default)
			)
			(layer "F.Fab")
		)
		(fp_line
			(start 0.12065 -0.3048)
			(end 0.67945 -0.3048)
			(stroke
				(width 0.1)
				(type default)
			)
			(layer "F.Fab")
		)
		(fp_line
			(start 0.12065 -0.2794)
			(end 0.12065 -0.3048)
			(stroke
				(width 0.1)
				(type default)
			)
			(layer "F.Fab")
		)
		(fp_line
			(start 0.67945 -0.3048)
			(end 0.67945 0.3048)
			(stroke
				(width 0.1)
				(type default)
			)
			(layer "F.Fab")
		)
		(fp_line
			(start 0.67945 0.3048)
			(end 0.120396 0.3048)
			(stroke
				(width 0.1)
				(type default)
			)
			(layer "F.Fab")
		)
		(pad "1" smd rect
			(at -0.40005 0 180)
			(size 0.4572 0.508)
			(layers "F.Cu" "F.Mask" "F.Paste")
			(net "P12V_LED_FAN0")
		)
		(pad "2" smd rect
			(at 0.40005 0 180)
			(size 0.4572 0.508)
			(layers "F.Cu" "F.Mask" "F.Paste")
			(net "P12V_LED_R_FAN0")
		)
	)
	(footprint ""
		(layer "F.Cu")
		(at 30.353 -187.452)
		(property "Reference" "R4956"
			(at 0 0 0)
			(layer "F.SilkS")
			(hide yes)
			(effects
				(font
					(size 1.27 1.27)
				)
			)
		)
		(property "Value" ""
			(at 0 0 0)
			(layer "F.Fab")
			(effects
				(font
					(size 1.27 1.27)
				)
			)
		)
		(duplicate_pad_numbers_are_jumpers no)
		(fp_line
			(start -0.7874 -0.4064)
			(end 0.7874 -0.4064)
			(stroke
				(width 0.1524)
				(type default)
			)
			(layer "F.SilkS")
		)
		(fp_line
			(start -0.7874 0.4064)
			(end -0.7874 -0.4064)
			(stroke
				(width 0.1524)
				(type default)
			)
			(layer "F.SilkS")
		)
		(fp_line
			(start 0.7874 -0.4064)
			(end 0.7874 0.4064)
			(stroke
				(width 0.1524)
				(type default)
			)
			(layer "F.SilkS")
		)
		(fp_line
			(start 0.7874 0.4064)
			(end -0.7874 0.4064)
			(stroke
				(width 0.1524)
				(type default)
			)
			(layer "F.SilkS")
		)
		(fp_line
			(start -0.67945 -0.305054)
			(end -0.12065 -0.305054)
			(stroke
				(width 0.1)
				(type default)
			)
			(layer "F.Fab")
		)
		(fp_line
			(start -0.67945 0.3048)
			(end -0.67945 -0.305054)
			(stroke
				(width 0.1)
				(type default)
			)
			(layer "F.Fab")
		)
		(fp_line
			(start -0.12065 -0.305054)
			(end -0.12065 -0.2794)
			(stroke
				(width 0.1)
				(type default)
			)
			(layer "F.Fab")
		)
		(fp_line
			(start -0.12065 -0.2794)
			(end 0.12065 -0.2794)
			(stroke
				(width 0.1)
				(type default)
			)
			(layer "F.Fab")
		)
		(fp_line
			(start -0.12065 0.2794)
			(end -0.12065 0.3048)
			(stroke
				(width 0.1)
				(type default)
			)
			(layer "F.Fab")
		)
		(fp_line
			(start -0.12065 0.3048)
			(end -0.67945 0.3048)
			(stroke
				(width 0.1)
				(type default)
			)
			(layer "F.Fab")
		)
		(fp_line
			(start 0.120396 0.2794)
			(end -0.12065 0.2794)
			(stroke
				(width 0.1)
				(type default)
			)
			(layer "F.Fab")
		)
		(fp_line
			(start 0.120396 0.3048)
			(end 0.120396 0.2794)
			(stroke
				(width 0.1)
				(type default)
			)
			(layer "F.Fab")
		)
		(fp_line
			(start 0.12065 -0.3048)
			(end 0.67945 -0.3048)
			(stroke
				(width 0.1)
				(type default)
			)
			(layer "F.Fab")
		)
		(fp_line
			(start 0.12065 -0.2794)
			(end 0.12065 -0.3048)
			(stroke
				(width 0.1)
				(type default)
			)
			(layer "F.Fab")
		)
		(fp_line
			(start 0.67945 -0.3048)
			(end 0.67945 0.3048)
			(stroke
				(width 0.1)
				(type default)
			)
			(layer "F.Fab")
		)
		(fp_line
			(start 0.67945 0.3048)
			(end 0.120396 0.3048)
			(stroke
				(width 0.1)
				(type default)
			)
			(layer "F.Fab")
		)
		(pad "1" smd circle
			(at -0.40005 0)
			(size 0 0)
			(layers "F.Cu" "F.Mask" "F.Paste")
			(net "P3V3_AUX")
		)
		(pad "2" smd circle
			(at 0.40005 0)
			(size 0 0)
			(layers "F.Cu" "F.Mask" "F.Paste")
			(net "P52V_FAN_5_BUFF_EN")
		)
	)
	(footprint ""
		(layer "F.Cu")
		(at 33.02 -119.564912)
		(property "Reference" "D279"
			(at 2.032 -1.058418 0)
			(unlocked yes)
			(layer "F.SilkS")
			(effects
				(font
					(size 0.7874 0.5842)
					(thickness 0.1524)
				)
				(justify left)
			)
		)
		(property "Value" ""
			(at 0 0 0)
			(layer "F.Fab")
			(effects
				(font
					(size 1.27 1.27)
				)
			)
		)
		(duplicate_pad_numbers_are_jumpers no)
		(fp_line
			(start -0.854964 -0.450088)
			(end -0.854964 0.450088)
			(stroke
				(width 0.1524)
				(type default)
			)
			(layer "F.SilkS")
		)
		(fp_line
			(start -0.854964 0.450088)
			(end 0.925068 0.450088)
			(stroke
				(width 0.1524)
				(type default)
			)
			(layer "F.SilkS")
		)
		(fp_line
			(start 0.845058 0.4064)
			(end 0.845058 -0.381)
			(stroke
				(width 0.1524)
				(type default)
			)
			(layer "F.SilkS")
		)
		(fp_line
			(start 0.870458 -0.2794)
			(end 0.845058 0.4064)
			(stroke
				(width 0.1524)
				(type default)
			)
			(layer "F.SilkS")
		)
		(fp_line
			(start 0.94488 -0.450088)
			(end -0.854964 -0.450088)
			(stroke
				(width 0.1524)
				(type default)
			)
			(layer "F.SilkS")
		)
		(fp_line
			(start 0.94488 0.450088)
			(end 0.94488 -0.450088)
			(stroke
				(width 0.1524)
				(type default)
			)
			(layer "F.SilkS")
		)
		(fp_line
			(start -0.54991 -0.350012)
			(end -0.54991 0.350012)
			(stroke
				(width 0.1)
				(type default)
			)
			(layer "F.Fab")
		)
		(fp_line
			(start -0.54991 0.350012)
			(end 0.54991 0.350012)
			(stroke
				(width 0.1)
				(type default)
			)
			(layer "F.Fab")
		)
		(fp_line
			(start 0.54991 -0.350012)
			(end -0.54991 -0.350012)
			(stroke
				(width 0.1)
				(type default)
			)
			(layer "F.Fab")
		)
		(fp_line
			(start 0.54991 0.350012)
			(end 0.54991 -0.350012)
			(stroke
				(width 0.1)
				(type default)
			)
			(layer "F.Fab")
		)
		(fp_text user "+"
			(at -0.508 0.915162 180)
			(unlocked yes)
			(layer "F.SilkS")
			(effects
				(font
					(size 1.905 1.4224)
					(thickness 0.1524)
				)
				(justify left)
			)
		)
		(fp_text user "-"
			(at 1.905 0.915162 180)
			(unlocked yes)
			(layer "F.SilkS")
			(effects
				(font
					(size 1.905 1.4224)
					(thickness 0.1524)
				)
				(justify left)
			)
		)
		(fp_text user "+"
			(at -0.808228 0.239014 180)
			(unlocked yes)
			(layer "F.Fab")
			(effects
				(font
					(size 1.905 1.4224)
					(thickness 0.1524)
				)
				(justify left)
			)
		)
		(fp_text user "-"
			(at 2.48539 0.239014 180)
			(unlocked yes)
			(layer "F.Fab")
			(effects
				(font
					(size 1.905 1.4224)
					(thickness 0.1524)
				)
				(justify left)
			)
		)
		(pad "A" smd rect
			(at -0.424942 0)
			(size 0.5588 0.6096)
			(layers "F.Cu" "F.Mask" "F.Paste")
			(net "GND")
		)
		(pad "C" smd rect
			(at 0.424942 0 180)
			(size 0.5588 0.6096)
			(layers "F.Cu" "F.Mask" "F.Paste")
			(net "FAN_2_PWM_OL_R")
		)
	)
	(footprint ""
		(layer "F.Cu")
		(at 33.02 -118.237 180)
		(property "Reference" "R5330"
			(at 0 0 180)
			(layer "F.SilkS")
			(hide yes)
			(effects
				(font
					(size 1.27 1.27)
				)
			)
		)
		(property "Value" ""
			(at 0 0 180)
			(layer "F.Fab")
			(effects
				(font
					(size 1.27 1.27)
				)
			)
		)
		(duplicate_pad_numbers_are_jumpers no)
		(fp_line
			(start 0.7874 0.4064)
			(end -0.7874 0.4064)
			(stroke
				(width 0.1524)
				(type default)
			)
			(layer "F.SilkS")
		)
		(fp_line
			(start 0.7874 -0.4064)
			(end 0.7874 0.4064)
			(stroke
				(width 0.1524)
				(type default)
			)
			(layer "F.SilkS")
		)
		(fp_line
			(start -0.7874 0.4064)
			(end -0.7874 -0.4064)
			(stroke
				(width 0.1524)
				(type default)
			)
			(layer "F.SilkS")
		)
		(fp_line
			(start -0.7874 -0.4064)
			(end 0.7874 -0.4064)
			(stroke
				(width 0.1524)
				(type default)
			)
			(layer "F.SilkS")
		)
		(fp_line
			(start 0.67945 0.3048)
			(end 0.120396 0.3048)
			(stroke
				(width 0.1)
				(type default)
			)
			(layer "F.Fab")
		)
		(fp_line
			(start 0.67945 -0.3048)
			(end 0.67945 0.3048)
			(stroke
				(width 0.1)
				(type default)
			)
			(layer "F.Fab")
		)
		(fp_line
			(start 0.12065 -0.2794)
			(end 0.12065 -0.3048)
			(stroke
				(width 0.1)
				(type default)
			)
			(layer "F.Fab")
		)
		(fp_line
			(start 0.12065 -0.3048)
			(end 0.67945 -0.3048)
			(stroke
				(width 0.1)
				(type default)
			)
			(layer "F.Fab")
		)
		(fp_line
			(start 0.120396 0.3048)
			(end 0.120396 0.2794)
			(stroke
				(width 0.1)
				(type default)
			)
			(layer "F.Fab")
		)
		(fp_line
			(start 0.120396 0.2794)
			(end -0.12065 0.2794)
			(stroke
				(width 0.1)
				(type default)
			)
			(layer "F.Fab")
		)
		(fp_line
			(start -0.12065 0.3048)
			(end -0.67945 0.3048)
			(stroke
				(width 0.1)
				(type default)
			)
			(layer "F.Fab")
		)
		(fp_line
			(start -0.12065 0.2794)
			(end -0.12065 0.3048)
			(stroke
				(width 0.1)
				(type default)
			)
			(layer "F.Fab")
		)
		(fp_line
			(start -0.12065 -0.2794)
			(end 0.12065 -0.2794)
			(stroke
				(width 0.1)
				(type default)
			)
			(layer "F.Fab")
		)
		(fp_line
			(start -0.12065 -0.305054)
			(end -0.12065 -0.2794)
			(stroke
				(width 0.1)
				(type default)
			)
			(layer "F.Fab")
		)
		(fp_line
			(start -0.67945 0.3048)
			(end -0.67945 -0.305054)
			(stroke
				(width 0.1)
				(type default)
			)
			(layer "F.Fab")
		)
		(fp_line
			(start -0.67945 -0.305054)
			(end -0.12065 -0.305054)
			(stroke
				(width 0.1)
				(type default)
			)
			(layer "F.Fab")
		)
		(pad "1" smd rect
			(at -0.40005 0)
			(size 0.4572 0.508)
			(layers "F.Cu" "F.Mask" "F.Paste")
			(net "FAN_2_TACH_IL_R")
		)
		(pad "2" smd rect
			(at 0.40005 0)
			(size 0.4572 0.508)
			(layers "F.Cu" "F.Mask" "F.Paste")
			(net "FAN_2_TACH_IL")
		)
	)
	(footprint ""
		(layer "F.Cu")
		(at 20.5232 -162.941 -90)
		(property "Reference" "R5472"
			(at 0 0 270)
			(layer "F.SilkS")
			(hide yes)
			(effects
				(font
					(size 1.27 1.27)
				)
			)
		)
		(property "Value" ""
			(at 0 0 270)
			(layer "F.Fab")
			(effects
				(font
					(size 1.27 1.27)
				)
			)
		)
		(duplicate_pad_numbers_are_jumpers no)
		(fp_line
			(start -0.7874 0.4064)
			(end -0.7874 -0.4064)
			(stroke
				(width 0.1524)
				(type default)
			)
			(layer "F.SilkS")
		)
		(fp_line
			(start 0.7874 0.4064)
			(end -0.7874 0.4064)
			(stroke
				(width 0.1524)
				(type default)
			)
			(layer "F.SilkS")
		)
		(fp_line
			(start -0.7874 -0.4064)
			(end 0.7874 -0.4064)
			(stroke
				(width 0.1524)
				(type default)
			)
			(layer "F.SilkS")
		)
		(fp_line
			(start 0.7874 -0.4064)
			(end 0.7874 0.4064)
			(stroke
				(width 0.1524)
				(type default)
			)
			(layer "F.SilkS")
		)
		(fp_line
			(start -0.67945 0.3048)
			(end -0.67945 -0.305054)
			(stroke
				(width 0.1)
				(type default)
			)
			(layer "F.Fab")
		)
		(fp_line
			(start -0.12065 0.3048)
			(end -0.67945 0.3048)
			(stroke
				(width 0.1)
				(type default)
			)
			(layer "F.Fab")
		)
		(fp_line
			(start 0.120396 0.3048)
			(end 0.120396 0.2794)
			(stroke
				(width 0.1)
				(type default)
			)
			(layer "F.Fab")
		)
		(fp_line
			(start 0.67945 0.3048)
			(end 0.120396 0.3048)
			(stroke
				(width 0.1)
				(type default)
			)
			(layer "F.Fab")
		)
		(fp_line
			(start -0.12065 0.2794)
			(end -0.12065 0.3048)
			(stroke
				(width 0.1)
				(type default)
			)
			(layer "F.Fab")
		)
		(fp_line
			(start 0.120396 0.2794)
			(end -0.12065 0.2794)
			(stroke
				(width 0.1)
				(type default)
			)
			(layer "F.Fab")
		)
		(fp_line
			(start -0.12065 -0.2794)
			(end 0.12065 -0.2794)
			(stroke
				(width 0.1)
				(type default)
			)
			(layer "F.Fab")
		)
		(fp_line
			(start 0.12065 -0.2794)
			(end 0.12065 -0.3048)
			(stroke
				(width 0.1)
				(type default)
			)
			(layer "F.Fab")
		)
		(fp_line
			(start 0.12065 -0.3048)
			(end 0.67945 -0.3048)
			(stroke
				(width 0.1)
				(type default)
			)
			(layer "F.Fab")
		)
		(fp_line
			(start 0.67945 -0.3048)
			(end 0.67945 0.3048)
			(stroke
				(width 0.1)
				(type default)
			)
			(layer "F.Fab")
		)
		(fp_line
			(start -0.67945 -0.305054)
			(end -0.12065 -0.305054)
			(stroke
				(width 0.1)
				(type default)
			)
			(layer "F.Fab")
		)
		(fp_line
			(start -0.12065 -0.305054)
			(end -0.12065 -0.2794)
			(stroke
				(width 0.1)
				(type default)
			)
			(layer "F.Fab")
		)
		(pad "1" smd circle
			(at -0.40005 0 270)
			(size 0 0)
			(layers "F.Cu" "F.Mask" "F.Paste")
			(net "P3V3_AUX")
		)
		(pad "2" smd circle
			(at 0.40005 0 270)
			(size 0 0)
			(layers "F.Cu" "F.Mask" "F.Paste")
			(net "PD_TCA9548_SML1_U321_A2")
		)
	)
	(footprint ""
		(layer "F.Cu")
		(at 16.764 -300.736 180)
		(property "Reference" "R5533"
			(at 0 0 180)
			(layer "F.SilkS")
			(hide yes)
			(effects
				(font
					(size 1.27 1.27)
				)
			)
		)
		(property "Value" ""
			(at 0 0 180)
			(layer "F.Fab")
			(effects
				(font
					(size 1.27 1.27)
				)
			)
		)
		(duplicate_pad_numbers_are_jumpers no)
		(fp_line
			(start 0.7874 0.4064)
			(end -0.7874 0.4064)
			(stroke
				(width 0.1524)
				(type default)
			)
			(layer "F.SilkS")
		)
		(fp_line
			(start 0.7874 -0.4064)
			(end 0.7874 0.4064)
			(stroke
				(width 0.1524)
				(type default)
			)
			(layer "F.SilkS")
		)
		(fp_line
			(start -0.7874 0.4064)
			(end -0.7874 -0.4064)
			(stroke
				(width 0.1524)
				(type default)
			)
			(layer "F.SilkS")
		)
		(fp_line
			(start -0.7874 -0.4064)
			(end 0.7874 -0.4064)
			(stroke
				(width 0.1524)
				(type default)
			)
			(layer "F.SilkS")
		)
		(fp_line
			(start 0.67945 0.3048)
			(end 0.120396 0.3048)
			(stroke
				(width 0.1)
				(type default)
			)
			(layer "F.Fab")
		)
		(fp_line
			(start 0.67945 -0.3048)
			(end 0.67945 0.3048)
			(stroke
				(width 0.1)
				(type default)
			)
			(layer "F.Fab")
		)
		(fp_line
			(start 0.12065 -0.2794)
			(end 0.12065 -0.3048)
			(stroke
				(width 0.1)
				(type default)
			)
			(layer "F.Fab")
		)
		(fp_line
			(start 0.12065 -0.3048)
			(end 0.67945 -0.3048)
			(stroke
				(width 0.1)
				(type default)
			)
			(layer "F.Fab")
		)
		(fp_line
			(start 0.120396 0.3048)
			(end 0.120396 0.2794)
			(stroke
				(width 0.1)
				(type default)
			)
			(layer "F.Fab")
		)
		(fp_line
			(start 0.120396 0.2794)
			(end -0.12065 0.2794)
			(stroke
				(width 0.1)
				(type default)
			)
			(layer "F.Fab")
		)
		(fp_line
			(start -0.12065 0.3048)
			(end -0.67945 0.3048)
			(stroke
				(width 0.1)
				(type default)
			)
			(layer "F.Fab")
		)
		(fp_line
			(start -0.12065 0.2794)
			(end -0.12065 0.3048)
			(stroke
				(width 0.1)
				(type default)
			)
			(layer "F.Fab")
		)
		(fp_line
			(start -0.12065 -0.2794)
			(end 0.12065 -0.2794)
			(stroke
				(width 0.1)
				(type default)
			)
			(layer "F.Fab")
		)
		(fp_line
			(start -0.12065 -0.305054)
			(end -0.12065 -0.2794)
			(stroke
				(width 0.1)
				(type default)
			)
			(layer "F.Fab")
		)
		(fp_line
			(start -0.67945 0.3048)
			(end -0.67945 -0.305054)
			(stroke
				(width 0.1)
				(type default)
			)
			(layer "F.Fab")
		)
		(fp_line
			(start -0.67945 -0.305054)
			(end -0.12065 -0.305054)
			(stroke
				(width 0.1)
				(type default)
			)
			(layer "F.Fab")
		)
		(pad "1" smd rect
			(at -0.40005 0)
			(size 0.4572 0.508)
			(layers "F.Cu" "F.Mask" "F.Paste")
			(net "P12V_LED_FAN7")
		)
		(pad "2" smd rect
			(at 0.40005 0)
			(size 0.4572 0.508)
			(layers "F.Cu" "F.Mask" "F.Paste")
			(net "FAN_7_OK_LED_R_N")
		)
	)
	(footprint ""
		(layer "F.Cu")
		(at 28.956 -171.577 180)
		(property "Reference" "R5110"
			(at 0 0 180)
			(layer "F.SilkS")
			(hide yes)
			(effects
				(font
					(size 1.27 1.27)
				)
			)
		)
		(property "Value" ""
			(at 0 0 180)
			(layer "F.Fab")
			(effects
				(font
					(size 1.27 1.27)
				)
			)
		)
		(duplicate_pad_numbers_are_jumpers no)
		(fp_line
			(start 0.7874 0.4064)
			(end -0.7874 0.4064)
			(stroke
				(width 0.1524)
				(type default)
			)
			(layer "F.SilkS")
		)
		(fp_line
			(start 0.7874 -0.4064)
			(end 0.7874 0.4064)
			(stroke
				(width 0.1524)
				(type default)
			)
			(layer "F.SilkS")
		)
		(fp_line
			(start -0.7874 0.4064)
			(end -0.7874 -0.4064)
			(stroke
				(width 0.1524)
				(type default)
			)
			(layer "F.SilkS")
		)
		(fp_line
			(start -0.7874 -0.4064)
			(end 0.7874 -0.4064)
			(stroke
				(width 0.1524)
				(type default)
			)
			(layer "F.SilkS")
		)
		(fp_line
			(start 0.67945 0.3048)
			(end 0.120396 0.3048)
			(stroke
				(width 0.1)
				(type default)
			)
			(layer "F.Fab")
		)
		(fp_line
			(start 0.67945 -0.3048)
			(end 0.67945 0.3048)
			(stroke
				(width 0.1)
				(type default)
			)
			(layer "F.Fab")
		)
		(fp_line
			(start 0.12065 -0.2794)
			(end 0.12065 -0.3048)
			(stroke
				(width 0.1)
				(type default)
			)
			(layer "F.Fab")
		)
		(fp_line
			(start 0.12065 -0.3048)
			(end 0.67945 -0.3048)
			(stroke
				(width 0.1)
				(type default)
			)
			(layer "F.Fab")
		)
		(fp_line
			(start 0.120396 0.3048)
			(end 0.120396 0.2794)
			(stroke
				(width 0.1)
				(type default)
			)
			(layer "F.Fab")
		)
		(fp_line
			(start 0.120396 0.2794)
			(end -0.12065 0.2794)
			(stroke
				(width 0.1)
				(type default)
			)
			(layer "F.Fab")
		)
		(fp_line
			(start -0.12065 0.3048)
			(end -0.67945 0.3048)
			(stroke
				(width 0.1)
				(type default)
			)
			(layer "F.Fab")
		)
		(fp_line
			(start -0.12065 0.2794)
			(end -0.12065 0.3048)
			(stroke
				(width 0.1)
				(type default)
			)
			(layer "F.Fab")
		)
		(fp_line
			(start -0.12065 -0.2794)
			(end 0.12065 -0.2794)
			(stroke
				(width 0.1)
				(type default)
			)
			(layer "F.Fab")
		)
		(fp_line
			(start -0.12065 -0.305054)
			(end -0.12065 -0.2794)
			(stroke
				(width 0.1)
				(type default)
			)
			(layer "F.Fab")
		)
		(fp_line
			(start -0.67945 0.3048)
			(end -0.67945 -0.305054)
			(stroke
				(width 0.1)
				(type default)
			)
			(layer "F.Fab")
		)
		(fp_line
			(start -0.67945 -0.305054)
			(end -0.12065 -0.305054)
			(stroke
				(width 0.1)
				(type default)
			)
			(layer "F.Fab")
		)
		(pad "1" smd circle
			(at -0.40005 0 180)
			(size 0 0)
			(layers "F.Cu" "F.Mask" "F.Paste")
			(net "FAN_7_OK_LED")
		)
		(pad "2" smd circle
			(at 0.40005 0 180)
			(size 0 0)
			(layers "F.Cu" "F.Mask" "F.Paste")
			(net "FAN_7_OK_R_LED")
		)
	)
	(footprint ""
		(layer "F.Cu")
		(at 11.176 -4.445)
		(property "Reference" "H13"
			(at -1.037844 -3.339338 0)
			(unlocked yes)
			(layer "F.SilkS")
			(effects
				(font
					(size 0.7874 0.5842)
					(thickness 0.1524)
				)
				(justify left)
			)
		)
		(property "Value" ""
			(at 0 0 0)
			(layer "F.Fab")
			(effects
				(font
					(size 1.27 1.27)
				)
			)
		)
		(duplicate_pad_numbers_are_jumpers no)
		(fp_circle
			(center 0 0)
			(end 2.4003 0)
			(stroke
				(width 0.1524)
				(type default)
			)
			(fill no)
			(layer "F.SilkS")
		)
		(fp_circle
			(center 0 0)
			(end 6.5913 0)
			(stroke
				(width 0.1524)
				(type default)
			)
			(fill no)
			(layer "B.SilkS")
		)
		(fp_circle
			(center 0 0)
			(end 6.5913 0)
			(stroke
				(width 0.1)
				(type default)
			)
			(fill no)
			(layer "B.Fab")
		)
		(fp_circle
			(center 0 0)
			(end 2.4003 0)
			(stroke
				(width 0.1)
				(type default)
			)
			(fill no)
			(layer "F.Fab")
		)
		(pad "" np_thru_hole circle
			(at 0 0)
			(size 3.175 3.175)
			(drill 3.175)
			(layers "*.Cu" "*.Mask")
			(clearance 0.381)
			(thermal_gap 0.381)
		)
		(zone
			(layers "F.Cu" "B.Cu" "In1.Cu" "In2.Cu" "In3.Cu" "In4.Cu")
			(hatch none 0.5)
			(connect_pads
				(clearance 0)
			)
			(min_thickness 0.25)
			(keepout
				(tracks not_allowed)
				(vias allowed)
				(pads allowed)
				(copperpour not_allowed)
				(footprints allowed)
			)
			(placement
				(enabled no)
				(sheetname "")
			)
			(fill
				(thermal_gap 0.5)
				(thermal_bridge_width 0.5)
				(island_removal_mode 0)
			)
			(polygon
				(pts
					(arc
						(start 13.2715 -4.445)
						(mid 9.0805 -4.445)
						(end 13.2715 -4.445)
					)
				)
			)
		)
	)
	(footprint ""
		(layer "F.Cu")
		(at 39.206932 -256.413)
		(property "Reference" "C2064"
			(at 0 0 0)
			(layer "F.SilkS")
			(hide yes)
			(effects
				(font
					(size 1.27 1.27)
				)
			)
		)
		(property "Value" ""
			(at 0 0 0)
			(layer "F.Fab")
			(effects
				(font
					(size 1.27 1.27)
				)
			)
		)
		(duplicate_pad_numbers_are_jumpers no)
		(fp_line
			(start -0.7874 -0.4064)
			(end 0.7874 -0.4064)
			(stroke
				(width 0.1524)
				(type default)
			)
			(layer "F.SilkS")
		)
		(fp_line
			(start -0.7874 0.4064)
			(end -0.7874 -0.4064)
			(stroke
				(width 0.1524)
				(type default)
			)
			(layer "F.SilkS")
		)
		(fp_line
			(start 0.7874 -0.4064)
			(end 0.7874 0.4064)
			(stroke
				(width 0.1524)
				(type default)
			)
			(layer "F.SilkS")
		)
		(fp_line
			(start 0.7874 0.4064)
			(end -0.7874 0.4064)
			(stroke
				(width 0.1524)
				(type default)
			)
			(layer "F.SilkS")
		)
		(fp_line
			(start -0.67945 -0.305054)
			(end -0.12065 -0.305054)
			(stroke
				(width 0.1)
				(type default)
			)
			(layer "F.Fab")
		)
		(fp_line
			(start -0.67945 0.3048)
			(end -0.67945 -0.305054)
			(stroke
				(width 0.1)
				(type default)
			)
			(layer "F.Fab")
		)
		(fp_line
			(start -0.12065 -0.305054)
			(end -0.12065 -0.2794)
			(stroke
				(width 0.1)
				(type default)
			)
			(layer "F.Fab")
		)
		(fp_line
			(start -0.12065 -0.2794)
			(end 0.12065 -0.2794)
			(stroke
				(width 0.1)
				(type default)
			)
			(layer "F.Fab")
		)
		(fp_line
			(start -0.12065 0.2794)
			(end -0.12065 0.3048)
			(stroke
				(width 0.1)
				(type default)
			)
			(layer "F.Fab")
		)
		(fp_line
			(start -0.12065 0.3048)
			(end -0.67945 0.3048)
			(stroke
				(width 0.1)
				(type default)
			)
			(layer "F.Fab")
		)
		(fp_line
			(start 0.120396 0.2794)
			(end -0.12065 0.2794)
			(stroke
				(width 0.1)
				(type default)
			)
			(layer "F.Fab")
		)
		(fp_line
			(start 0.120396 0.3048)
			(end 0.120396 0.2794)
			(stroke
				(width 0.1)
				(type default)
			)
			(layer "F.Fab")
		)
		(fp_line
			(start 0.12065 -0.3048)
			(end 0.67945 -0.3048)
			(stroke
				(width 0.1)
				(type default)
			)
			(layer "F.Fab")
		)
		(fp_line
			(start 0.12065 -0.2794)
			(end 0.12065 -0.3048)
			(stroke
				(width 0.1)
				(type default)
			)
			(layer "F.Fab")
		)
		(fp_line
			(start 0.67945 -0.3048)
			(end 0.67945 0.3048)
			(stroke
				(width 0.1)
				(type default)
			)
			(layer "F.Fab")
		)
		(fp_line
			(start 0.67945 0.3048)
			(end 0.120396 0.3048)
			(stroke
				(width 0.1)
				(type default)
			)
			(layer "F.Fab")
		)
		(pad "1" smd circle
			(at -0.40005 0)
			(size 0 0)
			(layers "F.Cu" "F.Mask" "F.Paste")
			(net "P3V3_AUX")
		)
		(pad "2" smd circle
			(at 0.40005 0)
			(size 0 0)
			(layers "F.Cu" "F.Mask" "F.Paste")
			(net "GND")
		)
	)
	(footprint ""
		(layer "F.Cu")
		(at 3.81 -129.794)
		(property "Reference" "R5566"
			(at 0 0 0)
			(layer "F.SilkS")
			(hide yes)
			(effects
				(font
					(size 1.27 1.27)
				)
			)
		)
		(property "Value" ""
			(at 0 0 0)
			(layer "F.Fab")
			(effects
				(font
					(size 1.27 1.27)
				)
			)
		)
		(duplicate_pad_numbers_are_jumpers no)
		(fp_line
			(start -0.7874 -0.4064)
			(end 0.7874 -0.4064)
			(stroke
				(width 0.1524)
				(type default)
			)
			(layer "F.SilkS")
		)
		(fp_line
			(start -0.7874 0.4064)
			(end -0.7874 -0.4064)
			(stroke
				(width 0.1524)
				(type default)
			)
			(layer "F.SilkS")
		)
		(fp_line
			(start 0.7874 -0.4064)
			(end 0.7874 0.4064)
			(stroke
				(width 0.1524)
				(type default)
			)
			(layer "F.SilkS")
		)
		(fp_line
			(start 0.7874 0.4064)
			(end -0.7874 0.4064)
			(stroke
				(width 0.1524)
				(type default)
			)
			(layer "F.SilkS")
		)
		(fp_line
			(start -0.67945 -0.305054)
			(end -0.12065 -0.305054)
			(stroke
				(width 0.1)
				(type default)
			)
			(layer "F.Fab")
		)
		(fp_line
			(start -0.67945 0.3048)
			(end -0.67945 -0.305054)
			(stroke
				(width 0.1)
				(type default)
			)
			(layer "F.Fab")
		)
		(fp_line
			(start -0.12065 -0.305054)
			(end -0.12065 -0.2794)
			(stroke
				(width 0.1)
				(type default)
			)
			(layer "F.Fab")
		)
		(fp_line
			(start -0.12065 -0.2794)
			(end 0.12065 -0.2794)
			(stroke
				(width 0.1)
				(type default)
			)
			(layer "F.Fab")
		)
		(fp_line
			(start -0.12065 0.2794)
			(end -0.12065 0.3048)
			(stroke
				(width 0.1)
				(type default)
			)
			(layer "F.Fab")
		)
		(fp_line
			(start -0.12065 0.3048)
			(end -0.67945 0.3048)
			(stroke
				(width 0.1)
				(type default)
			)
			(layer "F.Fab")
		)
		(fp_line
			(start 0.120396 0.2794)
			(end -0.12065 0.2794)
			(stroke
				(width 0.1)
				(type default)
			)
			(layer "F.Fab")
		)
		(fp_line
			(start 0.120396 0.3048)
			(end 0.120396 0.2794)
			(stroke
				(width 0.1)
				(type default)
			)
			(layer "F.Fab")
		)
		(fp_line
			(start 0.12065 -0.3048)
			(end 0.67945 -0.3048)
			(stroke
				(width 0.1)
				(type default)
			)
			(layer "F.Fab")
		)
		(fp_line
			(start 0.12065 -0.2794)
			(end 0.12065 -0.3048)
			(stroke
				(width 0.1)
				(type default)
			)
			(layer "F.Fab")
		)
		(fp_line
			(start 0.67945 -0.3048)
			(end 0.67945 0.3048)
			(stroke
				(width 0.1)
				(type default)
			)
			(layer "F.Fab")
		)
		(fp_line
			(start 0.67945 0.3048)
			(end 0.120396 0.3048)
			(stroke
				(width 0.1)
				(type default)
			)
			(layer "F.Fab")
		)
		(pad "1" smd circle
			(at -0.40005 0)
			(size 0 0)
			(layers "F.Cu" "F.Mask" "F.Paste")
			(net "P3V3_AUX")
		)
		(pad "2" smd circle
			(at 0.40005 0)
			(size 0 0)
			(layers "F.Cu" "F.Mask" "F.Paste")
			(net "U404_ADD1")
		)
	)
	(footprint ""
		(layer "F.Cu")
		(at 23.622 -136.017 -90)
		(property "Reference" "R4952"
			(at 0 0 270)
			(layer "F.SilkS")
			(hide yes)
			(effects
				(font
					(size 1.27 1.27)
				)
			)
		)
		(property "Value" ""
			(at 0 0 270)
			(layer "F.Fab")
			(effects
				(font
					(size 1.27 1.27)
				)
			)
		)
		(duplicate_pad_numbers_are_jumpers no)
		(fp_line
			(start -0.7874 0.4064)
			(end -0.7874 -0.4064)
			(stroke
				(width 0.1524)
				(type default)
			)
			(layer "F.SilkS")
		)
		(fp_line
			(start 0.7874 0.4064)
			(end -0.7874 0.4064)
			(stroke
				(width 0.1524)
				(type default)
			)
			(layer "F.SilkS")
		)
		(fp_line
			(start -0.7874 -0.4064)
			(end 0.7874 -0.4064)
			(stroke
				(width 0.1524)
				(type default)
			)
			(layer "F.SilkS")
		)
		(fp_line
			(start 0.7874 -0.4064)
			(end 0.7874 0.4064)
			(stroke
				(width 0.1524)
				(type default)
			)
			(layer "F.SilkS")
		)
		(fp_line
			(start -0.67945 0.3048)
			(end -0.67945 -0.305054)
			(stroke
				(width 0.1)
				(type default)
			)
			(layer "F.Fab")
		)
		(fp_line
			(start -0.12065 0.3048)
			(end -0.67945 0.3048)
			(stroke
				(width 0.1)
				(type default)
			)
			(layer "F.Fab")
		)
		(fp_line
			(start 0.120396 0.3048)
			(end 0.120396 0.2794)
			(stroke
				(width 0.1)
				(type default)
			)
			(layer "F.Fab")
		)
		(fp_line
			(start 0.67945 0.3048)
			(end 0.120396 0.3048)
			(stroke
				(width 0.1)
				(type default)
			)
			(layer "F.Fab")
		)
		(fp_line
			(start -0.12065 0.2794)
			(end -0.12065 0.3048)
			(stroke
				(width 0.1)
				(type default)
			)
			(layer "F.Fab")
		)
		(fp_line
			(start 0.120396 0.2794)
			(end -0.12065 0.2794)
			(stroke
				(width 0.1)
				(type default)
			)
			(layer "F.Fab")
		)
		(fp_line
			(start -0.12065 -0.2794)
			(end 0.12065 -0.2794)
			(stroke
				(width 0.1)
				(type default)
			)
			(layer "F.Fab")
		)
		(fp_line
			(start 0.12065 -0.2794)
			(end 0.12065 -0.3048)
			(stroke
				(width 0.1)
				(type default)
			)
			(layer "F.Fab")
		)
		(fp_line
			(start 0.12065 -0.3048)
			(end 0.67945 -0.3048)
			(stroke
				(width 0.1)
				(type default)
			)
			(layer "F.Fab")
		)
		(fp_line
			(start 0.67945 -0.3048)
			(end 0.67945 0.3048)
			(stroke
				(width 0.1)
				(type default)
			)
			(layer "F.Fab")
		)
		(fp_line
			(start -0.67945 -0.305054)
			(end -0.12065 -0.305054)
			(stroke
				(width 0.1)
				(type default)
			)
			(layer "F.Fab")
		)
		(fp_line
			(start -0.12065 -0.305054)
			(end -0.12065 -0.2794)
			(stroke
				(width 0.1)
				(type default)
			)
			(layer "F.Fab")
		)
		(pad "1" smd circle
			(at -0.40005 0 270)
			(size 0 0)
			(layers "F.Cu" "F.Mask" "F.Paste")
			(net "GND")
		)
		(pad "2" smd circle
			(at 0.40005 0 270)
			(size 0 0)
			(layers "F.Cu" "F.Mask" "F.Paste")
			(net "MAX31790_U330_FREQ_START")
		)
	)
	(footprint ""
		(layer "F.Cu")
		(at 14.0589 -134.874 180)
		(property "Reference" "R5595"
			(at 0 0 180)
			(layer "F.SilkS")
			(hide yes)
			(effects
				(font
					(size 1.27 1.27)
				)
			)
		)
		(property "Value" ""
			(at 0 0 180)
			(layer "F.Fab")
			(effects
				(font
					(size 1.27 1.27)
				)
			)
		)
		(duplicate_pad_numbers_are_jumpers no)
		(fp_line
			(start 0.7874 0.4064)
			(end -0.7874 0.4064)
			(stroke
				(width 0.1524)
				(type default)
			)
			(layer "F.SilkS")
		)
		(fp_line
			(start 0.7874 -0.4064)
			(end 0.7874 0.4064)
			(stroke
				(width 0.1524)
				(type default)
			)
			(layer "F.SilkS")
		)
		(fp_line
			(start -0.7874 0.4064)
			(end -0.7874 -0.4064)
			(stroke
				(width 0.1524)
				(type default)
			)
			(layer "F.SilkS")
		)
		(fp_line
			(start -0.7874 -0.4064)
			(end 0.7874 -0.4064)
			(stroke
				(width 0.1524)
				(type default)
			)
			(layer "F.SilkS")
		)
		(fp_line
			(start 0.67945 0.3048)
			(end 0.120396 0.3048)
			(stroke
				(width 0.1)
				(type default)
			)
			(layer "F.Fab")
		)
		(fp_line
			(start 0.67945 -0.3048)
			(end 0.67945 0.3048)
			(stroke
				(width 0.1)
				(type default)
			)
			(layer "F.Fab")
		)
		(fp_line
			(start 0.12065 -0.2794)
			(end 0.12065 -0.3048)
			(stroke
				(width 0.1)
				(type default)
			)
			(layer "F.Fab")
		)
		(fp_line
			(start 0.12065 -0.3048)
			(end 0.67945 -0.3048)
			(stroke
				(width 0.1)
				(type default)
			)
			(layer "F.Fab")
		)
		(fp_line
			(start 0.120396 0.3048)
			(end 0.120396 0.2794)
			(stroke
				(width 0.1)
				(type default)
			)
			(layer "F.Fab")
		)
		(fp_line
			(start 0.120396 0.2794)
			(end -0.12065 0.2794)
			(stroke
				(width 0.1)
				(type default)
			)
			(layer "F.Fab")
		)
		(fp_line
			(start -0.12065 0.3048)
			(end -0.67945 0.3048)
			(stroke
				(width 0.1)
				(type default)
			)
			(layer "F.Fab")
		)
		(fp_line
			(start -0.12065 0.2794)
			(end -0.12065 0.3048)
			(stroke
				(width 0.1)
				(type default)
			)
			(layer "F.Fab")
		)
		(fp_line
			(start -0.12065 -0.2794)
			(end 0.12065 -0.2794)
			(stroke
				(width 0.1)
				(type default)
			)
			(layer "F.Fab")
		)
		(fp_line
			(start -0.12065 -0.305054)
			(end -0.12065 -0.2794)
			(stroke
				(width 0.1)
				(type default)
			)
			(layer "F.Fab")
		)
		(fp_line
			(start -0.67945 0.3048)
			(end -0.67945 -0.305054)
			(stroke
				(width 0.1)
				(type default)
			)
			(layer "F.Fab")
		)
		(fp_line
			(start -0.67945 -0.305054)
			(end -0.12065 -0.305054)
			(stroke
				(width 0.1)
				(type default)
			)
			(layer "F.Fab")
		)
		(pad "1" smd rect
			(at -0.40005 0)
			(size 0.4572 0.508)
			(layers "F.Cu" "F.Mask" "F.Paste")
			(net "FAN_7_PWM")
		)
		(pad "2" smd rect
			(at 0.40005 0)
			(size 0.4572 0.508)
			(layers "F.Cu" "F.Mask" "F.Paste")
			(net "FAN_7_PWM_R2")
		)
	)
	(footprint ""
		(layer "F.Cu")
		(at 15.377922 -211.776056 180)
		(property "Reference" "D253"
			(at 4.328922 0.414274 0)
			(unlocked yes)
			(layer "F.SilkS")
			(effects
				(font
					(size 0.7874 0.5842)
					(thickness 0.1524)
				)
				(justify left)
			)
		)
		(property "Value" ""
			(at 0 0 180)
			(layer "F.Fab")
			(effects
				(font
					(size 1.27 1.27)
				)
			)
		)
		(duplicate_pad_numbers_are_jumpers no)
		(fp_line
			(start 0.94488 0.450088)
			(end 0.94488 -0.450088)
			(stroke
				(width 0.1524)
				(type default)
			)
			(layer "F.SilkS")
		)
		(fp_line
			(start 0.94488 -0.450088)
			(end -0.854964 -0.450088)
			(stroke
				(width 0.1524)
				(type default)
			)
			(layer "F.SilkS")
		)
		(fp_line
			(start 0.870458 -0.2794)
			(end 0.845058 0.4064)
			(stroke
				(width 0.1524)
				(type default)
			)
			(layer "F.SilkS")
		)
		(fp_line
			(start 0.845058 0.4064)
			(end 0.845058 -0.381)
			(stroke
				(width 0.1524)
				(type default)
			)
			(layer "F.SilkS")
		)
		(fp_line
			(start -0.854964 0.450088)
			(end 0.925068 0.450088)
			(stroke
				(width 0.1524)
				(type default)
			)
			(layer "F.SilkS")
		)
		(fp_line
			(start -0.854964 -0.450088)
			(end -0.854964 0.450088)
			(stroke
				(width 0.1524)
				(type default)
			)
			(layer "F.SilkS")
		)
		(fp_line
			(start 0.54991 0.350012)
			(end 0.54991 -0.350012)
			(stroke
				(width 0.1)
				(type default)
			)
			(layer "F.Fab")
		)
		(fp_line
			(start 0.54991 -0.350012)
			(end -0.54991 -0.350012)
			(stroke
				(width 0.1)
				(type default)
			)
			(layer "F.Fab")
		)
		(fp_line
			(start -0.54991 0.350012)
			(end 0.54991 0.350012)
			(stroke
				(width 0.1)
				(type default)
			)
			(layer "F.Fab")
		)
		(fp_line
			(start -0.54991 -0.350012)
			(end -0.54991 0.350012)
			(stroke
				(width 0.1)
				(type default)
			)
			(layer "F.Fab")
		)
		(fp_text user "-"
			(at 1.280922 1.425194 0)
			(unlocked yes)
			(layer "F.SilkS")
			(effects
				(font
					(size 1.905 1.4224)
					(thickness 0.1524)
				)
				(justify left)
			)
		)
		(fp_text user "+"
			(at 0.264922 1.425194 0)
			(unlocked yes)
			(layer "F.SilkS")
			(effects
				(font
					(size 1.905 1.4224)
					(thickness 0.1524)
				)
				(justify left)
			)
		)
		(fp_text user "-"
			(at 2.48539 0.239014 0)
			(unlocked yes)
			(layer "F.Fab")
			(effects
				(font
					(size 1.905 1.4224)
					(thickness 0.1524)
				)
				(justify left)
			)
		)
		(fp_text user "+"
			(at -0.808228 0.239014 0)
			(unlocked yes)
			(layer "F.Fab")
			(effects
				(font
					(size 1.905 1.4224)
					(thickness 0.1524)
				)
				(justify left)
			)
		)
		(pad "A" smd rect
			(at -0.424942 0 180)
			(size 0.5588 0.6096)
			(layers "F.Cu" "F.Mask" "F.Paste")
			(net "GND")
		)
		(pad "C" smd rect
			(at 0.424942 0)
			(size 0.5588 0.6096)
			(layers "F.Cu" "F.Mask" "F.Paste")
			(net "FAN_6_TACH_OL_D")
		)
	)
	(footprint ""
		(layer "F.Cu")
		(at 32.258 -202.057 90)
		(property "Reference" "R5389"
			(at 0 0 90)
			(layer "F.SilkS")
			(hide yes)
			(effects
				(font
					(size 1.27 1.27)
				)
			)
		)
		(property "Value" ""
			(at 0 0 90)
			(layer "F.Fab")
			(effects
				(font
					(size 1.27 1.27)
				)
			)
		)
		(duplicate_pad_numbers_are_jumpers no)
		(fp_line
			(start 0.7874 -0.4064)
			(end 0.7874 0.4064)
			(stroke
				(width 0.1524)
				(type default)
			)
			(layer "F.SilkS")
		)
		(fp_line
			(start -0.7874 -0.4064)
			(end 0.7874 -0.4064)
			(stroke
				(width 0.1524)
				(type default)
			)
			(layer "F.SilkS")
		)
		(fp_line
			(start 0.7874 0.4064)
			(end -0.7874 0.4064)
			(stroke
				(width 0.1524)
				(type default)
			)
			(layer "F.SilkS")
		)
		(fp_line
			(start -0.7874 0.4064)
			(end -0.7874 -0.4064)
			(stroke
				(width 0.1524)
				(type default)
			)
			(layer "F.SilkS")
		)
		(fp_line
			(start -0.12065 -0.305054)
			(end -0.12065 -0.2794)
			(stroke
				(width 0.1)
				(type default)
			)
			(layer "F.Fab")
		)
		(fp_line
			(start -0.67945 -0.305054)
			(end -0.12065 -0.305054)
			(stroke
				(width 0.1)
				(type default)
			)
			(layer "F.Fab")
		)
		(fp_line
			(start 0.67945 -0.3048)
			(end 0.67945 0.3048)
			(stroke
				(width 0.1)
				(type default)
			)
			(layer "F.Fab")
		)
		(fp_line
			(start 0.12065 -0.3048)
			(end 0.67945 -0.3048)
			(stroke
				(width 0.1)
				(type default)
			)
			(layer "F.Fab")
		)
		(fp_line
			(start 0.12065 -0.2794)
			(end 0.12065 -0.3048)
			(stroke
				(width 0.1)
				(type default)
			)
			(layer "F.Fab")
		)
		(fp_line
			(start -0.12065 -0.2794)
			(end 0.12065 -0.2794)
			(stroke
				(width 0.1)
				(type default)
			)
			(layer "F.Fab")
		)
		(fp_line
			(start 0.120396 0.2794)
			(end -0.12065 0.2794)
			(stroke
				(width 0.1)
				(type default)
			)
			(layer "F.Fab")
		)
		(fp_line
			(start -0.12065 0.2794)
			(end -0.12065 0.3048)
			(stroke
				(width 0.1)
				(type default)
			)
			(layer "F.Fab")
		)
		(fp_line
			(start 0.67945 0.3048)
			(end 0.120396 0.3048)
			(stroke
				(width 0.1)
				(type default)
			)
			(layer "F.Fab")
		)
		(fp_line
			(start 0.120396 0.3048)
			(end 0.120396 0.2794)
			(stroke
				(width 0.1)
				(type default)
			)
			(layer "F.Fab")
		)
		(fp_line
			(start -0.12065 0.3048)
			(end -0.67945 0.3048)
			(stroke
				(width 0.1)
				(type default)
			)
			(layer "F.Fab")
		)
		(fp_line
			(start -0.67945 0.3048)
			(end -0.67945 -0.305054)
			(stroke
				(width 0.1)
				(type default)
			)
			(layer "F.Fab")
		)
		(pad "1" smd circle
			(at -0.40005 0 90)
			(size 0 0)
			(layers "F.Cu" "F.Mask" "F.Paste")
			(net "P3V3_AUX")
		)
		(pad "2" smd circle
			(at 0.40005 0 90)
			(size 0 0)
			(layers "F.Cu" "F.Mask" "F.Paste")
			(net "FAN_1_FAIL_R_LED")
		)
	)
	(footprint ""
		(layer "F.Cu")
		(at 40.4876 -224.3836)
		(property "Reference" "PC23"
			(at -5.334 5.99567 0)
			(unlocked yes)
			(layer "F.SilkS")
			(effects
				(font
					(size 0.7874 0.5842)
					(thickness 0.1524)
				)
				(justify left)
			)
		)
		(property "Value" ""
			(at 0 0 0)
			(layer "F.Fab")
			(effects
				(font
					(size 1.27 1.27)
				)
			)
		)
		(duplicate_pad_numbers_are_jumpers no)
		(fp_line
			(start -5.249926 -3.979926)
			(end -5.249926 -1.2446)
			(stroke
				(width 0.1524)
				(type default)
			)
			(layer "F.SilkS")
		)
		(fp_line
			(start -5.249926 1.2446)
			(end -5.249926 3.979926)
			(stroke
				(width 0.1524)
				(type default)
			)
			(layer "F.SilkS")
		)
		(fp_line
			(start -5.249926 3.979926)
			(end -3.979926 5.249926)
			(stroke
				(width 0.1524)
				(type default)
			)
			(layer "F.SilkS")
		)
		(fp_line
			(start -3.979926 -5.249926)
			(end -5.249926 -3.979926)
			(stroke
				(width 0.1524)
				(type default)
			)
			(layer "F.SilkS")
		)
		(fp_line
			(start -3.979926 5.249926)
			(end 5.249926 5.249926)
			(stroke
				(width 0.1524)
				(type default)
			)
			(layer "F.SilkS")
		)
		(fp_line
			(start 5.249926 -5.249926)
			(end -3.979926 -5.249926)
			(stroke
				(width 0.1524)
				(type default)
			)
			(layer "F.SilkS")
		)
		(fp_line
			(start 5.249926 -1.2446)
			(end 5.249926 -5.249926)
			(stroke
				(width 0.1524)
				(type default)
			)
			(layer "F.SilkS")
		)
		(fp_line
			(start 5.249926 5.249926)
			(end 5.249926 1.2446)
			(stroke
				(width 0.1524)
				(type default)
			)
			(layer "F.SilkS")
		)
		(fp_line
			(start -5.249926 -5.249926)
			(end -5.249926 5.249926)
			(stroke
				(width 0.1)
				(type default)
			)
			(layer "F.Fab")
		)
		(fp_line
			(start -5.249926 5.249926)
			(end 5.249926 5.249926)
			(stroke
				(width 0.1)
				(type default)
			)
			(layer "F.Fab")
		)
		(fp_line
			(start 5.249926 -5.249926)
			(end -5.249926 -5.249926)
			(stroke
				(width 0.1)
				(type default)
			)
			(layer "F.Fab")
		)
		(fp_line
			(start 5.249926 5.249926)
			(end 5.249926 -5.249926)
			(stroke
				(width 0.1)
				(type default)
			)
			(layer "F.Fab")
		)
		(pad "1" smd rect
			(at -4.45008 0 90)
			(size 2.2098 4.4196)
			(layers "F.Cu" "F.Mask" "F.Paste")
			(net "P52V_FAN_1")
		)
		(pad "2" smd rect
			(at 4.45008 0 90)
			(size 2.2098 4.4196)
			(layers "F.Cu" "F.Mask" "F.Paste")
			(net "GND")
		)
	)
	(footprint ""
		(layer "F.Cu")
		(at 17.018 -24.892 180)
		(property "Reference" "R5540"
			(at 0 0 180)
			(layer "F.SilkS")
			(hide yes)
			(effects
				(font
					(size 1.27 1.27)
				)
			)
		)
		(property "Value" ""
			(at 0 0 180)
			(layer "F.Fab")
			(effects
				(font
					(size 1.27 1.27)
				)
			)
		)
		(duplicate_pad_numbers_are_jumpers no)
		(fp_line
			(start 0.7874 0.4064)
			(end -0.7874 0.4064)
			(stroke
				(width 0.1524)
				(type default)
			)
			(layer "F.SilkS")
		)
		(fp_line
			(start 0.7874 -0.4064)
			(end 0.7874 0.4064)
			(stroke
				(width 0.1524)
				(type default)
			)
			(layer "F.SilkS")
		)
		(fp_line
			(start -0.7874 0.4064)
			(end -0.7874 -0.4064)
			(stroke
				(width 0.1524)
				(type default)
			)
			(layer "F.SilkS")
		)
		(fp_line
			(start -0.7874 -0.4064)
			(end 0.7874 -0.4064)
			(stroke
				(width 0.1524)
				(type default)
			)
			(layer "F.SilkS")
		)
		(fp_line
			(start 0.67945 0.3048)
			(end 0.120396 0.3048)
			(stroke
				(width 0.1)
				(type default)
			)
			(layer "F.Fab")
		)
		(fp_line
			(start 0.67945 -0.3048)
			(end 0.67945 0.3048)
			(stroke
				(width 0.1)
				(type default)
			)
			(layer "F.Fab")
		)
		(fp_line
			(start 0.12065 -0.2794)
			(end 0.12065 -0.3048)
			(stroke
				(width 0.1)
				(type default)
			)
			(layer "F.Fab")
		)
		(fp_line
			(start 0.12065 -0.3048)
			(end 0.67945 -0.3048)
			(stroke
				(width 0.1)
				(type default)
			)
			(layer "F.Fab")
		)
		(fp_line
			(start 0.120396 0.3048)
			(end 0.120396 0.2794)
			(stroke
				(width 0.1)
				(type default)
			)
			(layer "F.Fab")
		)
		(fp_line
			(start 0.120396 0.2794)
			(end -0.12065 0.2794)
			(stroke
				(width 0.1)
				(type default)
			)
			(layer "F.Fab")
		)
		(fp_line
			(start -0.12065 0.3048)
			(end -0.67945 0.3048)
			(stroke
				(width 0.1)
				(type default)
			)
			(layer "F.Fab")
		)
		(fp_line
			(start -0.12065 0.2794)
			(end -0.12065 0.3048)
			(stroke
				(width 0.1)
				(type default)
			)
			(layer "F.Fab")
		)
		(fp_line
			(start -0.12065 -0.2794)
			(end 0.12065 -0.2794)
			(stroke
				(width 0.1)
				(type default)
			)
			(layer "F.Fab")
		)
		(fp_line
			(start -0.12065 -0.305054)
			(end -0.12065 -0.2794)
			(stroke
				(width 0.1)
				(type default)
			)
			(layer "F.Fab")
		)
		(fp_line
			(start -0.67945 0.3048)
			(end -0.67945 -0.305054)
			(stroke
				(width 0.1)
				(type default)
			)
			(layer "F.Fab")
		)
		(fp_line
			(start -0.67945 -0.305054)
			(end -0.12065 -0.305054)
			(stroke
				(width 0.1)
				(type default)
			)
			(layer "F.Fab")
		)
		(pad "1" smd rect
			(at -0.40005 0)
			(size 0.4572 0.508)
			(layers "F.Cu" "F.Mask" "F.Paste")
			(net "P12V_LED_FAN4")
		)
		(pad "2" smd rect
			(at 0.40005 0)
			(size 0.4572 0.508)
			(layers "F.Cu" "F.Mask" "F.Paste")
			(net "FAN_4_OK_LED_R_N")
		)
	)
	(footprint ""
		(layer "F.Cu")
		(at 15.621 -162.814)
		(property "Reference" "C52"
			(at 0 0 0)
			(layer "F.SilkS")
			(hide yes)
			(effects
				(font
					(size 1.27 1.27)
				)
			)
		)
		(property "Value" ""
			(at 0 0 0)
			(layer "F.Fab")
			(effects
				(font
					(size 1.27 1.27)
				)
			)
		)
		(duplicate_pad_numbers_are_jumpers no)
		(fp_line
			(start -0.7874 -0.4064)
			(end 0.7874 -0.4064)
			(stroke
				(width 0.1524)
				(type default)
			)
			(layer "F.SilkS")
		)
		(fp_line
			(start -0.7874 0.4064)
			(end -0.7874 -0.4064)
			(stroke
				(width 0.1524)
				(type default)
			)
			(layer "F.SilkS")
		)
		(fp_line
			(start 0.7874 -0.4064)
			(end 0.7874 0.4064)
			(stroke
				(width 0.1524)
				(type default)
			)
			(layer "F.SilkS")
		)
		(fp_line
			(start 0.7874 0.4064)
			(end -0.7874 0.4064)
			(stroke
				(width 0.1524)
				(type default)
			)
			(layer "F.SilkS")
		)
		(fp_line
			(start -0.67945 -0.305054)
			(end -0.12065 -0.305054)
			(stroke
				(width 0.1)
				(type default)
			)
			(layer "F.Fab")
		)
		(fp_line
			(start -0.67945 0.3048)
			(end -0.67945 -0.305054)
			(stroke
				(width 0.1)
				(type default)
			)
			(layer "F.Fab")
		)
		(fp_line
			(start -0.12065 -0.305054)
			(end -0.12065 -0.2794)
			(stroke
				(width 0.1)
				(type default)
			)
			(layer "F.Fab")
		)
		(fp_line
			(start -0.12065 -0.2794)
			(end 0.12065 -0.2794)
			(stroke
				(width 0.1)
				(type default)
			)
			(layer "F.Fab")
		)
		(fp_line
			(start -0.12065 0.2794)
			(end -0.12065 0.3048)
			(stroke
				(width 0.1)
				(type default)
			)
			(layer "F.Fab")
		)
		(fp_line
			(start -0.12065 0.3048)
			(end -0.67945 0.3048)
			(stroke
				(width 0.1)
				(type default)
			)
			(layer "F.Fab")
		)
		(fp_line
			(start 0.120396 0.2794)
			(end -0.12065 0.2794)
			(stroke
				(width 0.1)
				(type default)
			)
			(layer "F.Fab")
		)
		(fp_line
			(start 0.120396 0.3048)
			(end 0.120396 0.2794)
			(stroke
				(width 0.1)
				(type default)
			)
			(layer "F.Fab")
		)
		(fp_line
			(start 0.12065 -0.3048)
			(end 0.67945 -0.3048)
			(stroke
				(width 0.1)
				(type default)
			)
			(layer "F.Fab")
		)
		(fp_line
			(start 0.12065 -0.2794)
			(end 0.12065 -0.3048)
			(stroke
				(width 0.1)
				(type default)
			)
			(layer "F.Fab")
		)
		(fp_line
			(start 0.67945 -0.3048)
			(end 0.67945 0.3048)
			(stroke
				(width 0.1)
				(type default)
			)
			(layer "F.Fab")
		)
		(fp_line
			(start 0.67945 0.3048)
			(end 0.120396 0.3048)
			(stroke
				(width 0.1)
				(type default)
			)
			(layer "F.Fab")
		)
		(pad "1" smd circle
			(at -0.40005 0)
			(size 0 0)
			(layers "F.Cu" "F.Mask" "F.Paste")
			(net "FAN_0_PRESENT_N")
		)
		(pad "2" smd circle
			(at 0.40005 0)
			(size 0 0)
			(layers "F.Cu" "F.Mask" "F.Paste")
			(net "GND")
		)
	)
	(footprint ""
		(layer "F.Cu")
		(at 14.859 -131.064)
		(property "Reference" "R5616"
			(at 0 0 0)
			(layer "F.SilkS")
			(hide yes)
			(effects
				(font
					(size 1.27 1.27)
				)
			)
		)
		(property "Value" ""
			(at 0 0 0)
			(layer "F.Fab")
			(effects
				(font
					(size 1.27 1.27)
				)
			)
		)
		(duplicate_pad_numbers_are_jumpers no)
		(fp_line
			(start -0.7874 -0.4064)
			(end 0.7874 -0.4064)
			(stroke
				(width 0.1524)
				(type default)
			)
			(layer "F.SilkS")
		)
		(fp_line
			(start -0.7874 0.4064)
			(end -0.7874 -0.4064)
			(stroke
				(width 0.1524)
				(type default)
			)
			(layer "F.SilkS")
		)
		(fp_line
			(start 0.7874 -0.4064)
			(end 0.7874 0.4064)
			(stroke
				(width 0.1524)
				(type default)
			)
			(layer "F.SilkS")
		)
		(fp_line
			(start 0.7874 0.4064)
			(end -0.7874 0.4064)
			(stroke
				(width 0.1524)
				(type default)
			)
			(layer "F.SilkS")
		)
		(fp_line
			(start -0.67945 -0.305054)
			(end -0.12065 -0.305054)
			(stroke
				(width 0.1)
				(type default)
			)
			(layer "F.Fab")
		)
		(fp_line
			(start -0.67945 0.3048)
			(end -0.67945 -0.305054)
			(stroke
				(width 0.1)
				(type default)
			)
			(layer "F.Fab")
		)
		(fp_line
			(start -0.12065 -0.305054)
			(end -0.12065 -0.2794)
			(stroke
				(width 0.1)
				(type default)
			)
			(layer "F.Fab")
		)
		(fp_line
			(start -0.12065 -0.2794)
			(end 0.12065 -0.2794)
			(stroke
				(width 0.1)
				(type default)
			)
			(layer "F.Fab")
		)
		(fp_line
			(start -0.12065 0.2794)
			(end -0.12065 0.3048)
			(stroke
				(width 0.1)
				(type default)
			)
			(layer "F.Fab")
		)
		(fp_line
			(start -0.12065 0.3048)
			(end -0.67945 0.3048)
			(stroke
				(width 0.1)
				(type default)
			)
			(layer "F.Fab")
		)
		(fp_line
			(start 0.120396 0.2794)
			(end -0.12065 0.2794)
			(stroke
				(width 0.1)
				(type default)
			)
			(layer "F.Fab")
		)
		(fp_line
			(start 0.120396 0.3048)
			(end 0.120396 0.2794)
			(stroke
				(width 0.1)
				(type default)
			)
			(layer "F.Fab")
		)
		(fp_line
			(start 0.12065 -0.3048)
			(end 0.67945 -0.3048)
			(stroke
				(width 0.1)
				(type default)
			)
			(layer "F.Fab")
		)
		(fp_line
			(start 0.12065 -0.2794)
			(end 0.12065 -0.3048)
			(stroke
				(width 0.1)
				(type default)
			)
			(layer "F.Fab")
		)
		(fp_line
			(start 0.67945 -0.3048)
			(end 0.67945 0.3048)
			(stroke
				(width 0.1)
				(type default)
			)
			(layer "F.Fab")
		)
		(fp_line
			(start 0.67945 0.3048)
			(end 0.120396 0.3048)
			(stroke
				(width 0.1)
				(type default)
			)
			(layer "F.Fab")
		)
		(pad "1" smd rect
			(at -0.40005 0 180)
			(size 0.4572 0.508)
			(layers "F.Cu" "F.Mask" "F.Paste")
			(net "FAN_6_TACH_IL")
		)
		(pad "2" smd rect
			(at 0.40005 0 180)
			(size 0.4572 0.508)
			(layers "F.Cu" "F.Mask" "F.Paste")
			(net "FAN_6_TACH_IL_R1")
		)
	)
	(footprint ""
		(layer "F.Cu")
		(at 42.291 -137.287 -90)
		(property "Reference" "R5564"
			(at 0 0 270)
			(layer "F.SilkS")
			(hide yes)
			(effects
				(font
					(size 1.27 1.27)
				)
			)
		)
		(property "Value" ""
			(at 0 0 270)
			(layer "F.Fab")
			(effects
				(font
					(size 1.27 1.27)
				)
			)
		)
		(duplicate_pad_numbers_are_jumpers no)
		(fp_line
			(start -0.7874 0.4064)
			(end -0.7874 -0.4064)
			(stroke
				(width 0.1524)
				(type default)
			)
			(layer "F.SilkS")
		)
		(fp_line
			(start 0.7874 0.4064)
			(end -0.7874 0.4064)
			(stroke
				(width 0.1524)
				(type default)
			)
			(layer "F.SilkS")
		)
		(fp_line
			(start -0.7874 -0.4064)
			(end 0.7874 -0.4064)
			(stroke
				(width 0.1524)
				(type default)
			)
			(layer "F.SilkS")
		)
		(fp_line
			(start 0.7874 -0.4064)
			(end 0.7874 0.4064)
			(stroke
				(width 0.1524)
				(type default)
			)
			(layer "F.SilkS")
		)
		(fp_line
			(start -0.67945 0.3048)
			(end -0.67945 -0.305054)
			(stroke
				(width 0.1)
				(type default)
			)
			(layer "F.Fab")
		)
		(fp_line
			(start -0.12065 0.3048)
			(end -0.67945 0.3048)
			(stroke
				(width 0.1)
				(type default)
			)
			(layer "F.Fab")
		)
		(fp_line
			(start 0.120396 0.3048)
			(end 0.120396 0.2794)
			(stroke
				(width 0.1)
				(type default)
			)
			(layer "F.Fab")
		)
		(fp_line
			(start 0.67945 0.3048)
			(end 0.120396 0.3048)
			(stroke
				(width 0.1)
				(type default)
			)
			(layer "F.Fab")
		)
		(fp_line
			(start -0.12065 0.2794)
			(end -0.12065 0.3048)
			(stroke
				(width 0.1)
				(type default)
			)
			(layer "F.Fab")
		)
		(fp_line
			(start 0.120396 0.2794)
			(end -0.12065 0.2794)
			(stroke
				(width 0.1)
				(type default)
			)
			(layer "F.Fab")
		)
		(fp_line
			(start -0.12065 -0.2794)
			(end 0.12065 -0.2794)
			(stroke
				(width 0.1)
				(type default)
			)
			(layer "F.Fab")
		)
		(fp_line
			(start 0.12065 -0.2794)
			(end 0.12065 -0.3048)
			(stroke
				(width 0.1)
				(type default)
			)
			(layer "F.Fab")
		)
		(fp_line
			(start 0.12065 -0.3048)
			(end 0.67945 -0.3048)
			(stroke
				(width 0.1)
				(type default)
			)
			(layer "F.Fab")
		)
		(fp_line
			(start 0.67945 -0.3048)
			(end 0.67945 0.3048)
			(stroke
				(width 0.1)
				(type default)
			)
			(layer "F.Fab")
		)
		(fp_line
			(start -0.67945 -0.305054)
			(end -0.12065 -0.305054)
			(stroke
				(width 0.1)
				(type default)
			)
			(layer "F.Fab")
		)
		(fp_line
			(start -0.12065 -0.305054)
			(end -0.12065 -0.2794)
			(stroke
				(width 0.1)
				(type default)
			)
			(layer "F.Fab")
		)
		(pad "1" smd circle
			(at -0.40005 0 270)
			(size 0 0)
			(layers "F.Cu" "F.Mask" "F.Paste")
			(net "GND")
		)
		(pad "2" smd circle
			(at 0.40005 0 270)
			(size 0 0)
			(layers "F.Cu" "F.Mask" "F.Paste")
			(net "U403_ADD2")
		)
	)
	(footprint ""
		(layer "F.Cu")
		(at 25.527 -124.079 180)
		(property "Reference" "R4953"
			(at 0 0 180)
			(layer "F.SilkS")
			(hide yes)
			(effects
				(font
					(size 1.27 1.27)
				)
			)
		)
		(property "Value" ""
			(at 0 0 180)
			(layer "F.Fab")
			(effects
				(font
					(size 1.27 1.27)
				)
			)
		)
		(duplicate_pad_numbers_are_jumpers no)
		(fp_line
			(start 0.7874 0.4064)
			(end -0.7874 0.4064)
			(stroke
				(width 0.1524)
				(type default)
			)
			(layer "F.SilkS")
		)
		(fp_line
			(start 0.7874 -0.4064)
			(end 0.7874 0.4064)
			(stroke
				(width 0.1524)
				(type default)
			)
			(layer "F.SilkS")
		)
		(fp_line
			(start -0.7874 0.4064)
			(end -0.7874 -0.4064)
			(stroke
				(width 0.1524)
				(type default)
			)
			(layer "F.SilkS")
		)
		(fp_line
			(start -0.7874 -0.4064)
			(end 0.7874 -0.4064)
			(stroke
				(width 0.1524)
				(type default)
			)
			(layer "F.SilkS")
		)
		(fp_line
			(start 0.67945 0.3048)
			(end 0.120396 0.3048)
			(stroke
				(width 0.1)
				(type default)
			)
			(layer "F.Fab")
		)
		(fp_line
			(start 0.67945 -0.3048)
			(end 0.67945 0.3048)
			(stroke
				(width 0.1)
				(type default)
			)
			(layer "F.Fab")
		)
		(fp_line
			(start 0.12065 -0.2794)
			(end 0.12065 -0.3048)
			(stroke
				(width 0.1)
				(type default)
			)
			(layer "F.Fab")
		)
		(fp_line
			(start 0.12065 -0.3048)
			(end 0.67945 -0.3048)
			(stroke
				(width 0.1)
				(type default)
			)
			(layer "F.Fab")
		)
		(fp_line
			(start 0.120396 0.3048)
			(end 0.120396 0.2794)
			(stroke
				(width 0.1)
				(type default)
			)
			(layer "F.Fab")
		)
		(fp_line
			(start 0.120396 0.2794)
			(end -0.12065 0.2794)
			(stroke
				(width 0.1)
				(type default)
			)
			(layer "F.Fab")
		)
		(fp_line
			(start -0.12065 0.3048)
			(end -0.67945 0.3048)
			(stroke
				(width 0.1)
				(type default)
			)
			(layer "F.Fab")
		)
		(fp_line
			(start -0.12065 0.2794)
			(end -0.12065 0.3048)
			(stroke
				(width 0.1)
				(type default)
			)
			(layer "F.Fab")
		)
		(fp_line
			(start -0.12065 -0.2794)
			(end 0.12065 -0.2794)
			(stroke
				(width 0.1)
				(type default)
			)
			(layer "F.Fab")
		)
		(fp_line
			(start -0.12065 -0.305054)
			(end -0.12065 -0.2794)
			(stroke
				(width 0.1)
				(type default)
			)
			(layer "F.Fab")
		)
		(fp_line
			(start -0.67945 0.3048)
			(end -0.67945 -0.305054)
			(stroke
				(width 0.1)
				(type default)
			)
			(layer "F.Fab")
		)
		(fp_line
			(start -0.67945 -0.305054)
			(end -0.12065 -0.305054)
			(stroke
				(width 0.1)
				(type default)
			)
			(layer "F.Fab")
		)
		(pad "1" smd circle
			(at -0.40005 0 180)
			(size 0 0)
			(layers "F.Cu" "F.Mask" "F.Paste")
			(net "GND")
		)
		(pad "2" smd circle
			(at 0.40005 0 180)
			(size 0 0)
			(layers "F.Cu" "F.Mask" "F.Paste")
			(net "MAX31790_U330_PWM_START0")
		)
	)
	(footprint ""
		(layer "F.Cu")
		(at 13.335 -167.64 180)
		(property "Reference" "R5510"
			(at 0 0 180)
			(layer "F.SilkS")
			(hide yes)
			(effects
				(font
					(size 1.27 1.27)
				)
			)
		)
		(property "Value" ""
			(at 0 0 180)
			(layer "F.Fab")
			(effects
				(font
					(size 1.27 1.27)
				)
			)
		)
		(duplicate_pad_numbers_are_jumpers no)
		(fp_line
			(start 0.7874 0.4064)
			(end -0.7874 0.4064)
			(stroke
				(width 0.1524)
				(type default)
			)
			(layer "F.SilkS")
		)
		(fp_line
			(start 0.7874 -0.4064)
			(end 0.7874 0.4064)
			(stroke
				(width 0.1524)
				(type default)
			)
			(layer "F.SilkS")
		)
		(fp_line
			(start -0.7874 0.4064)
			(end -0.7874 -0.4064)
			(stroke
				(width 0.1524)
				(type default)
			)
			(layer "F.SilkS")
		)
		(fp_line
			(start -0.7874 -0.4064)
			(end 0.7874 -0.4064)
			(stroke
				(width 0.1524)
				(type default)
			)
			(layer "F.SilkS")
		)
		(fp_line
			(start 0.67945 0.3048)
			(end 0.120396 0.3048)
			(stroke
				(width 0.1)
				(type default)
			)
			(layer "F.Fab")
		)
		(fp_line
			(start 0.67945 -0.3048)
			(end 0.67945 0.3048)
			(stroke
				(width 0.1)
				(type default)
			)
			(layer "F.Fab")
		)
		(fp_line
			(start 0.12065 -0.2794)
			(end 0.12065 -0.3048)
			(stroke
				(width 0.1)
				(type default)
			)
			(layer "F.Fab")
		)
		(fp_line
			(start 0.12065 -0.3048)
			(end 0.67945 -0.3048)
			(stroke
				(width 0.1)
				(type default)
			)
			(layer "F.Fab")
		)
		(fp_line
			(start 0.120396 0.3048)
			(end 0.120396 0.2794)
			(stroke
				(width 0.1)
				(type default)
			)
			(layer "F.Fab")
		)
		(fp_line
			(start 0.120396 0.2794)
			(end -0.12065 0.2794)
			(stroke
				(width 0.1)
				(type default)
			)
			(layer "F.Fab")
		)
		(fp_line
			(start -0.12065 0.3048)
			(end -0.67945 0.3048)
			(stroke
				(width 0.1)
				(type default)
			)
			(layer "F.Fab")
		)
		(fp_line
			(start -0.12065 0.2794)
			(end -0.12065 0.3048)
			(stroke
				(width 0.1)
				(type default)
			)
			(layer "F.Fab")
		)
		(fp_line
			(start -0.12065 -0.2794)
			(end 0.12065 -0.2794)
			(stroke
				(width 0.1)
				(type default)
			)
			(layer "F.Fab")
		)
		(fp_line
			(start -0.12065 -0.305054)
			(end -0.12065 -0.2794)
			(stroke
				(width 0.1)
				(type default)
			)
			(layer "F.Fab")
		)
		(fp_line
			(start -0.67945 0.3048)
			(end -0.67945 -0.305054)
			(stroke
				(width 0.1)
				(type default)
			)
			(layer "F.Fab")
		)
		(fp_line
			(start -0.67945 -0.305054)
			(end -0.12065 -0.305054)
			(stroke
				(width 0.1)
				(type default)
			)
			(layer "F.Fab")
		)
		(pad "1" smd circle
			(at -0.40005 0 180)
			(size 0 0)
			(layers "F.Cu" "F.Mask" "F.Paste")
			(net "P3V3_AUX")
		)
		(pad "2" smd circle
			(at 0.40005 0 180)
			(size 0 0)
			(layers "F.Cu" "F.Mask" "F.Paste")
			(net "FAN_3_PRESENT_N")
		)
	)
	(footprint ""
		(layer "F.Cu")
		(at 15.24 -120.65 180)
		(property "Reference" "R5315"
			(at 0 0 180)
			(layer "F.SilkS")
			(hide yes)
			(effects
				(font
					(size 1.27 1.27)
				)
			)
		)
		(property "Value" ""
			(at 0 0 180)
			(layer "F.Fab")
			(effects
				(font
					(size 1.27 1.27)
				)
			)
		)
		(duplicate_pad_numbers_are_jumpers no)
		(fp_line
			(start 0.7874 0.4064)
			(end -0.7874 0.4064)
			(stroke
				(width 0.1524)
				(type default)
			)
			(layer "F.SilkS")
		)
		(fp_line
			(start 0.7874 -0.4064)
			(end 0.7874 0.4064)
			(stroke
				(width 0.1524)
				(type default)
			)
			(layer "F.SilkS")
		)
		(fp_line
			(start -0.7874 0.4064)
			(end -0.7874 -0.4064)
			(stroke
				(width 0.1524)
				(type default)
			)
			(layer "F.SilkS")
		)
		(fp_line
			(start -0.7874 -0.4064)
			(end 0.7874 -0.4064)
			(stroke
				(width 0.1524)
				(type default)
			)
			(layer "F.SilkS")
		)
		(fp_line
			(start 0.67945 0.3048)
			(end 0.120396 0.3048)
			(stroke
				(width 0.1)
				(type default)
			)
			(layer "F.Fab")
		)
		(fp_line
			(start 0.67945 -0.3048)
			(end 0.67945 0.3048)
			(stroke
				(width 0.1)
				(type default)
			)
			(layer "F.Fab")
		)
		(fp_line
			(start 0.12065 -0.2794)
			(end 0.12065 -0.3048)
			(stroke
				(width 0.1)
				(type default)
			)
			(layer "F.Fab")
		)
		(fp_line
			(start 0.12065 -0.3048)
			(end 0.67945 -0.3048)
			(stroke
				(width 0.1)
				(type default)
			)
			(layer "F.Fab")
		)
		(fp_line
			(start 0.120396 0.3048)
			(end 0.120396 0.2794)
			(stroke
				(width 0.1)
				(type default)
			)
			(layer "F.Fab")
		)
		(fp_line
			(start 0.120396 0.2794)
			(end -0.12065 0.2794)
			(stroke
				(width 0.1)
				(type default)
			)
			(layer "F.Fab")
		)
		(fp_line
			(start -0.12065 0.3048)
			(end -0.67945 0.3048)
			(stroke
				(width 0.1)
				(type default)
			)
			(layer "F.Fab")
		)
		(fp_line
			(start -0.12065 0.2794)
			(end -0.12065 0.3048)
			(stroke
				(width 0.1)
				(type default)
			)
			(layer "F.Fab")
		)
		(fp_line
			(start -0.12065 -0.2794)
			(end 0.12065 -0.2794)
			(stroke
				(width 0.1)
				(type default)
			)
			(layer "F.Fab")
		)
		(fp_line
			(start -0.12065 -0.305054)
			(end -0.12065 -0.2794)
			(stroke
				(width 0.1)
				(type default)
			)
			(layer "F.Fab")
		)
		(fp_line
			(start -0.67945 0.3048)
			(end -0.67945 -0.305054)
			(stroke
				(width 0.1)
				(type default)
			)
			(layer "F.Fab")
		)
		(fp_line
			(start -0.67945 -0.305054)
			(end -0.12065 -0.305054)
			(stroke
				(width 0.1)
				(type default)
			)
			(layer "F.Fab")
		)
		(pad "1" smd rect
			(at -0.40005 0)
			(size 0.4572 0.508)
			(layers "F.Cu" "F.Mask" "F.Paste")
			(net "FAN_5_TACH_OL_R")
		)
		(pad "2" smd rect
			(at 0.40005 0)
			(size 0.4572 0.508)
			(layers "F.Cu" "F.Mask" "F.Paste")
			(net "FAN_5_TACH_OL")
		)
	)
	(footprint ""
		(layer "F.Cu")
		(at 22.098 -114.427)
		(property "Reference" "R352"
			(at 0 0 0)
			(layer "F.SilkS")
			(hide yes)
			(effects
				(font
					(size 1.27 1.27)
				)
			)
		)
		(property "Value" ""
			(at 0 0 0)
			(layer "F.Fab")
			(effects
				(font
					(size 1.27 1.27)
				)
			)
		)
		(duplicate_pad_numbers_are_jumpers no)
		(fp_line
			(start -0.7874 -0.4064)
			(end 0.7874 -0.4064)
			(stroke
				(width 0.1524)
				(type default)
			)
			(layer "F.SilkS")
		)
		(fp_line
			(start -0.7874 0.4064)
			(end -0.7874 -0.4064)
			(stroke
				(width 0.1524)
				(type default)
			)
			(layer "F.SilkS")
		)
		(fp_line
			(start 0.7874 -0.4064)
			(end 0.7874 0.4064)
			(stroke
				(width 0.1524)
				(type default)
			)
			(layer "F.SilkS")
		)
		(fp_line
			(start 0.7874 0.4064)
			(end -0.7874 0.4064)
			(stroke
				(width 0.1524)
				(type default)
			)
			(layer "F.SilkS")
		)
		(fp_line
			(start -0.67945 -0.305054)
			(end -0.12065 -0.305054)
			(stroke
				(width 0.1)
				(type default)
			)
			(layer "F.Fab")
		)
		(fp_line
			(start -0.67945 0.3048)
			(end -0.67945 -0.305054)
			(stroke
				(width 0.1)
				(type default)
			)
			(layer "F.Fab")
		)
		(fp_line
			(start -0.12065 -0.305054)
			(end -0.12065 -0.2794)
			(stroke
				(width 0.1)
				(type default)
			)
			(layer "F.Fab")
		)
		(fp_line
			(start -0.12065 -0.2794)
			(end 0.12065 -0.2794)
			(stroke
				(width 0.1)
				(type default)
			)
			(layer "F.Fab")
		)
		(fp_line
			(start -0.12065 0.2794)
			(end -0.12065 0.3048)
			(stroke
				(width 0.1)
				(type default)
			)
			(layer "F.Fab")
		)
		(fp_line
			(start -0.12065 0.3048)
			(end -0.67945 0.3048)
			(stroke
				(width 0.1)
				(type default)
			)
			(layer "F.Fab")
		)
		(fp_line
			(start 0.120396 0.2794)
			(end -0.12065 0.2794)
			(stroke
				(width 0.1)
				(type default)
			)
			(layer "F.Fab")
		)
		(fp_line
			(start 0.120396 0.3048)
			(end 0.120396 0.2794)
			(stroke
				(width 0.1)
				(type default)
			)
			(layer "F.Fab")
		)
		(fp_line
			(start 0.12065 -0.3048)
			(end 0.67945 -0.3048)
			(stroke
				(width 0.1)
				(type default)
			)
			(layer "F.Fab")
		)
		(fp_line
			(start 0.12065 -0.2794)
			(end 0.12065 -0.3048)
			(stroke
				(width 0.1)
				(type default)
			)
			(layer "F.Fab")
		)
		(fp_line
			(start 0.67945 -0.3048)
			(end 0.67945 0.3048)
			(stroke
				(width 0.1)
				(type default)
			)
			(layer "F.Fab")
		)
		(fp_line
			(start 0.67945 0.3048)
			(end 0.120396 0.3048)
			(stroke
				(width 0.1)
				(type default)
			)
			(layer "F.Fab")
		)
		(pad "1" smd circle
			(at -0.40005 0)
			(size 0 0)
			(layers "F.Cu" "F.Mask" "F.Paste")
			(net "P3V3_AUX")
		)
		(pad "2" smd circle
			(at 0.40005 0)
			(size 0 0)
			(layers "F.Cu" "F.Mask" "F.Paste")
			(net "FAN_2_PWM")
		)
	)
	(footprint ""
		(layer "F.Cu")
		(at 14.351 -201.323956)
		(property "Reference" "R5225"
			(at 0 0 0)
			(layer "F.SilkS")
			(hide yes)
			(effects
				(font
					(size 1.27 1.27)
				)
			)
		)
		(property "Value" ""
			(at 0 0 0)
			(layer "F.Fab")
			(effects
				(font
					(size 1.27 1.27)
				)
			)
		)
		(duplicate_pad_numbers_are_jumpers no)
		(fp_line
			(start -0.7874 -0.4064)
			(end 0.7874 -0.4064)
			(stroke
				(width 0.1524)
				(type default)
			)
			(layer "F.SilkS")
		)
		(fp_line
			(start -0.7874 0.4064)
			(end -0.7874 -0.4064)
			(stroke
				(width 0.1524)
				(type default)
			)
			(layer "F.SilkS")
		)
		(fp_line
			(start 0.7874 -0.4064)
			(end 0.7874 0.4064)
			(stroke
				(width 0.1524)
				(type default)
			)
			(layer "F.SilkS")
		)
		(fp_line
			(start 0.7874 0.4064)
			(end -0.7874 0.4064)
			(stroke
				(width 0.1524)
				(type default)
			)
			(layer "F.SilkS")
		)
		(fp_line
			(start -0.67945 -0.305054)
			(end -0.12065 -0.305054)
			(stroke
				(width 0.1)
				(type default)
			)
			(layer "F.Fab")
		)
		(fp_line
			(start -0.67945 0.3048)
			(end -0.67945 -0.305054)
			(stroke
				(width 0.1)
				(type default)
			)
			(layer "F.Fab")
		)
		(fp_line
			(start -0.12065 -0.305054)
			(end -0.12065 -0.2794)
			(stroke
				(width 0.1)
				(type default)
			)
			(layer "F.Fab")
		)
		(fp_line
			(start -0.12065 -0.2794)
			(end 0.12065 -0.2794)
			(stroke
				(width 0.1)
				(type default)
			)
			(layer "F.Fab")
		)
		(fp_line
			(start -0.12065 0.2794)
			(end -0.12065 0.3048)
			(stroke
				(width 0.1)
				(type default)
			)
			(layer "F.Fab")
		)
		(fp_line
			(start -0.12065 0.3048)
			(end -0.67945 0.3048)
			(stroke
				(width 0.1)
				(type default)
			)
			(layer "F.Fab")
		)
		(fp_line
			(start 0.120396 0.2794)
			(end -0.12065 0.2794)
			(stroke
				(width 0.1)
				(type default)
			)
			(layer "F.Fab")
		)
		(fp_line
			(start 0.120396 0.3048)
			(end 0.120396 0.2794)
			(stroke
				(width 0.1)
				(type default)
			)
			(layer "F.Fab")
		)
		(fp_line
			(start 0.12065 -0.3048)
			(end 0.67945 -0.3048)
			(stroke
				(width 0.1)
				(type default)
			)
			(layer "F.Fab")
		)
		(fp_line
			(start 0.12065 -0.2794)
			(end 0.12065 -0.3048)
			(stroke
				(width 0.1)
				(type default)
			)
			(layer "F.Fab")
		)
		(fp_line
			(start 0.67945 -0.3048)
			(end 0.67945 0.3048)
			(stroke
				(width 0.1)
				(type default)
			)
			(layer "F.Fab")
		)
		(fp_line
			(start 0.67945 0.3048)
			(end 0.120396 0.3048)
			(stroke
				(width 0.1)
				(type default)
			)
			(layer "F.Fab")
		)
		(pad "1" smd circle
			(at -0.40005 0)
			(size 0 0)
			(layers "F.Cu" "F.Mask" "F.Paste")
			(net "SMB_FAN6_SDA_R")
		)
		(pad "2" smd circle
			(at 0.40005 0)
			(size 0 0)
			(layers "F.Cu" "F.Mask" "F.Paste")
			(net "SMB_FAN6_SDA")
		)
	)
	(footprint ""
		(layer "F.Cu")
		(at 30.353 -180.594)
		(property "Reference" "R510"
			(at 0 0 0)
			(layer "F.SilkS")
			(hide yes)
			(effects
				(font
					(size 1.27 1.27)
				)
			)
		)
		(property "Value" ""
			(at 0 0 0)
			(layer "F.Fab")
			(effects
				(font
					(size 1.27 1.27)
				)
			)
		)
		(duplicate_pad_numbers_are_jumpers no)
		(fp_line
			(start -0.7874 -0.4064)
			(end 0.7874 -0.4064)
			(stroke
				(width 0.1524)
				(type default)
			)
			(layer "F.SilkS")
		)
		(fp_line
			(start -0.7874 0.4064)
			(end -0.7874 -0.4064)
			(stroke
				(width 0.1524)
				(type default)
			)
			(layer "F.SilkS")
		)
		(fp_line
			(start 0.7874 -0.4064)
			(end 0.7874 0.4064)
			(stroke
				(width 0.1524)
				(type default)
			)
			(layer "F.SilkS")
		)
		(fp_line
			(start 0.7874 0.4064)
			(end -0.7874 0.4064)
			(stroke
				(width 0.1524)
				(type default)
			)
			(layer "F.SilkS")
		)
		(fp_line
			(start -0.67945 -0.305054)
			(end -0.12065 -0.305054)
			(stroke
				(width 0.1)
				(type default)
			)
			(layer "F.Fab")
		)
		(fp_line
			(start -0.67945 0.3048)
			(end -0.67945 -0.305054)
			(stroke
				(width 0.1)
				(type default)
			)
			(layer "F.Fab")
		)
		(fp_line
			(start -0.12065 -0.305054)
			(end -0.12065 -0.2794)
			(stroke
				(width 0.1)
				(type default)
			)
			(layer "F.Fab")
		)
		(fp_line
			(start -0.12065 -0.2794)
			(end 0.12065 -0.2794)
			(stroke
				(width 0.1)
				(type default)
			)
			(layer "F.Fab")
		)
		(fp_line
			(start -0.12065 0.2794)
			(end -0.12065 0.3048)
			(stroke
				(width 0.1)
				(type default)
			)
			(layer "F.Fab")
		)
		(fp_line
			(start -0.12065 0.3048)
			(end -0.67945 0.3048)
			(stroke
				(width 0.1)
				(type default)
			)
			(layer "F.Fab")
		)
		(fp_line
			(start 0.120396 0.2794)
			(end -0.12065 0.2794)
			(stroke
				(width 0.1)
				(type default)
			)
			(layer "F.Fab")
		)
		(fp_line
			(start 0.120396 0.3048)
			(end 0.120396 0.2794)
			(stroke
				(width 0.1)
				(type default)
			)
			(layer "F.Fab")
		)
		(fp_line
			(start 0.12065 -0.3048)
			(end 0.67945 -0.3048)
			(stroke
				(width 0.1)
				(type default)
			)
			(layer "F.Fab")
		)
		(fp_line
			(start 0.12065 -0.2794)
			(end 0.12065 -0.3048)
			(stroke
				(width 0.1)
				(type default)
			)
			(layer "F.Fab")
		)
		(fp_line
			(start 0.67945 -0.3048)
			(end 0.67945 0.3048)
			(stroke
				(width 0.1)
				(type default)
			)
			(layer "F.Fab")
		)
		(fp_line
			(start 0.67945 0.3048)
			(end 0.120396 0.3048)
			(stroke
				(width 0.1)
				(type default)
			)
			(layer "F.Fab")
		)
		(pad "1" smd circle
			(at -0.40005 0)
			(size 0 0)
			(layers "F.Cu" "F.Mask" "F.Paste")
			(net "P3V3_AUX")
		)
		(pad "2" smd circle
			(at 0.40005 0)
			(size 0 0)
			(layers "F.Cu" "F.Mask" "F.Paste")
			(net "P52V_FAN_1_BUFF_EN")
		)
	)
	(footprint ""
		(layer "F.Cu")
		(at 16.906494 -71.304912 -90)
		(property "Reference" "C2062"
			(at 0 0 270)
			(layer "F.SilkS")
			(hide yes)
			(effects
				(font
					(size 1.27 1.27)
				)
			)
		)
		(property "Value" ""
			(at 0 0 270)
			(layer "F.Fab")
			(effects
				(font
					(size 1.27 1.27)
				)
			)
		)
		(duplicate_pad_numbers_are_jumpers no)
		(fp_line
			(start -0.7874 0.4064)
			(end -0.7874 -0.4064)
			(stroke
				(width 0.1524)
				(type default)
			)
			(layer "F.SilkS")
		)
		(fp_line
			(start 0.7874 0.4064)
			(end -0.7874 0.4064)
			(stroke
				(width 0.1524)
				(type default)
			)
			(layer "F.SilkS")
		)
		(fp_line
			(start -0.7874 -0.4064)
			(end 0.7874 -0.4064)
			(stroke
				(width 0.1524)
				(type default)
			)
			(layer "F.SilkS")
		)
		(fp_line
			(start 0.7874 -0.4064)
			(end 0.7874 0.4064)
			(stroke
				(width 0.1524)
				(type default)
			)
			(layer "F.SilkS")
		)
		(fp_line
			(start -0.67945 0.3048)
			(end -0.67945 -0.305054)
			(stroke
				(width 0.1)
				(type default)
			)
			(layer "F.Fab")
		)
		(fp_line
			(start -0.12065 0.3048)
			(end -0.67945 0.3048)
			(stroke
				(width 0.1)
				(type default)
			)
			(layer "F.Fab")
		)
		(fp_line
			(start 0.120396 0.3048)
			(end 0.120396 0.2794)
			(stroke
				(width 0.1)
				(type default)
			)
			(layer "F.Fab")
		)
		(fp_line
			(start 0.67945 0.3048)
			(end 0.120396 0.3048)
			(stroke
				(width 0.1)
				(type default)
			)
			(layer "F.Fab")
		)
		(fp_line
			(start -0.12065 0.2794)
			(end -0.12065 0.3048)
			(stroke
				(width 0.1)
				(type default)
			)
			(layer "F.Fab")
		)
		(fp_line
			(start 0.120396 0.2794)
			(end -0.12065 0.2794)
			(stroke
				(width 0.1)
				(type default)
			)
			(layer "F.Fab")
		)
		(fp_line
			(start -0.12065 -0.2794)
			(end 0.12065 -0.2794)
			(stroke
				(width 0.1)
				(type default)
			)
			(layer "F.Fab")
		)
		(fp_line
			(start 0.12065 -0.2794)
			(end 0.12065 -0.3048)
			(stroke
				(width 0.1)
				(type default)
			)
			(layer "F.Fab")
		)
		(fp_line
			(start 0.12065 -0.3048)
			(end 0.67945 -0.3048)
			(stroke
				(width 0.1)
				(type default)
			)
			(layer "F.Fab")
		)
		(fp_line
			(start 0.67945 -0.3048)
			(end 0.67945 0.3048)
			(stroke
				(width 0.1)
				(type default)
			)
			(layer "F.Fab")
		)
		(fp_line
			(start -0.67945 -0.305054)
			(end -0.12065 -0.305054)
			(stroke
				(width 0.1)
				(type default)
			)
			(layer "F.Fab")
		)
		(fp_line
			(start -0.12065 -0.305054)
			(end -0.12065 -0.2794)
			(stroke
				(width 0.1)
				(type default)
			)
			(layer "F.Fab")
		)
		(pad "1" smd circle
			(at -0.40005 0 270)
			(size 0 0)
			(layers "F.Cu" "F.Mask" "F.Paste")
			(net "P3V3_AUX")
		)
		(pad "2" smd circle
			(at 0.40005 0 270)
			(size 0 0)
			(layers "F.Cu" "F.Mask" "F.Paste")
			(net "GND")
		)
	)
	(footprint ""
		(layer "F.Cu")
		(at 16.393922 -101.950012)
		(property "Reference" "C2032"
			(at 0 0 0)
			(layer "F.SilkS")
			(hide yes)
			(effects
				(font
					(size 1.27 1.27)
				)
			)
		)
		(property "Value" ""
			(at 0 0 0)
			(layer "F.Fab")
			(effects
				(font
					(size 1.27 1.27)
				)
			)
		)
		(duplicate_pad_numbers_are_jumpers no)
		(fp_line
			(start -0.7874 -0.4064)
			(end 0.7874 -0.4064)
			(stroke
				(width 0.1524)
				(type default)
			)
			(layer "F.SilkS")
		)
		(fp_line
			(start -0.7874 0.4064)
			(end -0.7874 -0.4064)
			(stroke
				(width 0.1524)
				(type default)
			)
			(layer "F.SilkS")
		)
		(fp_line
			(start 0.7874 -0.4064)
			(end 0.7874 0.4064)
			(stroke
				(width 0.1524)
				(type default)
			)
			(layer "F.SilkS")
		)
		(fp_line
			(start 0.7874 0.4064)
			(end -0.7874 0.4064)
			(stroke
				(width 0.1524)
				(type default)
			)
			(layer "F.SilkS")
		)
		(fp_line
			(start -0.67945 -0.305054)
			(end -0.12065 -0.305054)
			(stroke
				(width 0.1)
				(type default)
			)
			(layer "F.Fab")
		)
		(fp_line
			(start -0.67945 0.3048)
			(end -0.67945 -0.305054)
			(stroke
				(width 0.1)
				(type default)
			)
			(layer "F.Fab")
		)
		(fp_line
			(start -0.12065 -0.305054)
			(end -0.12065 -0.2794)
			(stroke
				(width 0.1)
				(type default)
			)
			(layer "F.Fab")
		)
		(fp_line
			(start -0.12065 -0.2794)
			(end 0.12065 -0.2794)
			(stroke
				(width 0.1)
				(type default)
			)
			(layer "F.Fab")
		)
		(fp_line
			(start -0.12065 0.2794)
			(end -0.12065 0.3048)
			(stroke
				(width 0.1)
				(type default)
			)
			(layer "F.Fab")
		)
		(fp_line
			(start -0.12065 0.3048)
			(end -0.67945 0.3048)
			(stroke
				(width 0.1)
				(type default)
			)
			(layer "F.Fab")
		)
		(fp_line
			(start 0.120396 0.2794)
			(end -0.12065 0.2794)
			(stroke
				(width 0.1)
				(type default)
			)
			(layer "F.Fab")
		)
		(fp_line
			(start 0.120396 0.3048)
			(end 0.120396 0.2794)
			(stroke
				(width 0.1)
				(type default)
			)
			(layer "F.Fab")
		)
		(fp_line
			(start 0.12065 -0.3048)
			(end 0.67945 -0.3048)
			(stroke
				(width 0.1)
				(type default)
			)
			(layer "F.Fab")
		)
		(fp_line
			(start 0.12065 -0.2794)
			(end 0.12065 -0.3048)
			(stroke
				(width 0.1)
				(type default)
			)
			(layer "F.Fab")
		)
		(fp_line
			(start 0.67945 -0.3048)
			(end 0.67945 0.3048)
			(stroke
				(width 0.1)
				(type default)
			)
			(layer "F.Fab")
		)
		(fp_line
			(start 0.67945 0.3048)
			(end 0.120396 0.3048)
			(stroke
				(width 0.1)
				(type default)
			)
			(layer "F.Fab")
		)
		(pad "1" smd circle
			(at -0.40005 0)
			(size 0 0)
			(layers "F.Cu" "F.Mask" "F.Paste")
			(net "FAN_5_PWM_OL_R")
		)
		(pad "2" smd circle
			(at 0.40005 0)
			(size 0 0)
			(layers "F.Cu" "F.Mask" "F.Paste")
			(net "GND")
		)
	)
	(footprint ""
		(layer "F.Cu")
		(at 34.925 -275.608288 180)
		(property "Reference" "PC7"
			(at -3.175 -6.013958 0)
			(unlocked yes)
			(layer "F.SilkS")
			(effects
				(font
					(size 0.7874 0.5842)
					(thickness 0.1524)
				)
				(justify left)
			)
		)
		(property "Value" ""
			(at 0 0 180)
			(layer "F.Fab")
			(effects
				(font
					(size 1.27 1.27)
				)
			)
		)
		(duplicate_pad_numbers_are_jumpers no)
		(fp_line
			(start 5.249926 5.249926)
			(end 5.249926 1.2446)
			(stroke
				(width 0.1524)
				(type default)
			)
			(layer "F.SilkS")
		)
		(fp_line
			(start 5.249926 -1.2446)
			(end 5.249926 -5.249926)
			(stroke
				(width 0.1524)
				(type default)
			)
			(layer "F.SilkS")
		)
		(fp_line
			(start 5.249926 -5.249926)
			(end -3.979926 -5.249926)
			(stroke
				(width 0.1524)
				(type default)
			)
			(layer "F.SilkS")
		)
		(fp_line
			(start -3.979926 5.249926)
			(end 5.249926 5.249926)
			(stroke
				(width 0.1524)
				(type default)
			)
			(layer "F.SilkS")
		)
		(fp_line
			(start -3.979926 -5.249926)
			(end -5.249926 -3.979926)
			(stroke
				(width 0.1524)
				(type default)
			)
			(layer "F.SilkS")
		)
		(fp_line
			(start -5.249926 3.979926)
			(end -3.979926 5.249926)
			(stroke
				(width 0.1524)
				(type default)
			)
			(layer "F.SilkS")
		)
		(fp_line
			(start -5.249926 1.2446)
			(end -5.249926 3.979926)
			(stroke
				(width 0.1524)
				(type default)
			)
			(layer "F.SilkS")
		)
		(fp_line
			(start -5.249926 -3.979926)
			(end -5.249926 -1.2446)
			(stroke
				(width 0.1524)
				(type default)
			)
			(layer "F.SilkS")
		)
		(fp_line
			(start 5.249926 5.249926)
			(end 5.249926 -5.249926)
			(stroke
				(width 0.1)
				(type default)
			)
			(layer "F.Fab")
		)
		(fp_line
			(start 5.249926 -5.249926)
			(end -5.249926 -5.249926)
			(stroke
				(width 0.1)
				(type default)
			)
			(layer "F.Fab")
		)
		(fp_line
			(start -5.249926 5.249926)
			(end 5.249926 5.249926)
			(stroke
				(width 0.1)
				(type default)
			)
			(layer "F.Fab")
		)
		(fp_line
			(start -5.249926 -5.249926)
			(end -5.249926 5.249926)
			(stroke
				(width 0.1)
				(type default)
			)
			(layer "F.Fab")
		)
		(pad "1" smd rect
			(at -4.45008 0 270)
			(size 2.2098 4.4196)
			(layers "F.Cu" "F.Mask" "F.Paste")
			(net "P52V_FAN_0")
		)
		(pad "2" smd rect
			(at 4.45008 0 270)
			(size 2.2098 4.4196)
			(layers "F.Cu" "F.Mask" "F.Paste")
			(net "GND")
		)
	)
	(footprint ""
		(layer "F.Cu")
		(at 10.287 -179.959)
		(property "Reference" "U7"
			(at 0.889 4.72567 0)
			(unlocked yes)
			(layer "F.SilkS")
			(effects
				(font
					(size 0.7874 0.5842)
					(thickness 0.1524)
				)
				(justify left)
			)
		)
		(property "Value" ""
			(at 0 0 0)
			(layer "F.Fab")
			(effects
				(font
					(size 1.27 1.27)
				)
			)
		)
		(duplicate_pad_numbers_are_jumpers no)
		(fp_line
			(start -2.0066 -3.9624)
			(end -0.5842 -3.9624)
			(stroke
				(width 0.1524)
				(type default)
			)
			(layer "F.SilkS")
		)
		(fp_line
			(start -2.0066 3.9624)
			(end -2.0066 -3.9624)
			(stroke
				(width 0.1524)
				(type default)
			)
			(layer "F.SilkS")
		)
		(fp_line
			(start -0.5842 -3.9624)
			(end 0 -3.3782)
			(stroke
				(width 0.1524)
				(type default)
			)
			(layer "F.SilkS")
		)
		(fp_line
			(start 0 -3.3782)
			(end 0.5842 -3.9624)
			(stroke
				(width 0.1524)
				(type default)
			)
			(layer "F.SilkS")
		)
		(fp_line
			(start 0.5842 -3.9624)
			(end 2.0066 -3.9624)
			(stroke
				(width 0.1524)
				(type default)
			)
			(layer "F.SilkS")
		)
		(fp_line
			(start 2.0066 -3.9624)
			(end 2.0066 3.9624)
			(stroke
				(width 0.1524)
				(type default)
			)
			(layer "F.SilkS")
		)
		(fp_line
			(start 2.0066 3.9624)
			(end -2.0066 3.9624)
			(stroke
				(width 0.1524)
				(type default)
			)
			(layer "F.SilkS")
		)
		(fp_poly
			(pts
				(xy -3.8862 -3.570986) (xy -4.6482 -3.189986) (xy -4.6482 -3.951986)
			)
			(stroke
				(width 0)
				(type default)
			)
			(fill yes)
			(layer "F.SilkS")
		)
		(fp_line
			(start -3.724402 -3.80365)
			(end -3.724402 3.80365)
			(stroke
				(width 0.1)
				(type default)
			)
			(layer "F.Fab")
		)
		(fp_line
			(start -3.724402 3.80365)
			(end -2.2479 3.80365)
			(stroke
				(width 0.1)
				(type default)
			)
			(layer "F.Fab")
		)
		(fp_line
			(start -3.7211 -3.34645)
			(end -3.7211 -3.80365)
			(stroke
				(width 0.1)
				(type default)
			)
			(layer "F.Fab")
		)
		(fp_line
			(start -2.2479 -3.974846)
			(end -2.2479 -3.80365)
			(stroke
				(width 0.1)
				(type default)
			)
			(layer "F.Fab")
		)
		(fp_line
			(start -2.2479 -3.80365)
			(end -3.724402 -3.80365)
			(stroke
				(width 0.1)
				(type default)
			)
			(layer "F.Fab")
		)
		(fp_line
			(start -2.2479 3.80365)
			(end -2.2479 3.9624)
			(stroke
				(width 0.1)
				(type default)
			)
			(layer "F.Fab")
		)
		(fp_line
			(start -2.2479 3.9624)
			(end 2.2479 3.9624)
			(stroke
				(width 0.1)
				(type default)
			)
			(layer "F.Fab")
		)
		(fp_line
			(start 2.2479 -3.974846)
			(end -2.2479 -3.974846)
			(stroke
				(width 0.1)
				(type default)
			)
			(layer "F.Fab")
		)
		(fp_line
			(start 2.2479 -3.80365)
			(end 2.2479 -3.974846)
			(stroke
				(width 0.1)
				(type default)
			)
			(layer "F.Fab")
		)
		(fp_line
			(start 2.2479 3.80365)
			(end 3.7211 3.80365)
			(stroke
				(width 0.1)
				(type default)
			)
			(layer "F.Fab")
		)
		(fp_line
			(start 2.2479 3.9624)
			(end 2.2479 3.80365)
			(stroke
				(width 0.1)
				(type default)
			)
			(layer "F.Fab")
		)
		(fp_line
			(start 3.7211 -3.80365)
			(end 2.2479 -3.80365)
			(stroke
				(width 0.1)
				(type default)
			)
			(layer "F.Fab")
		)
		(fp_line
			(start 3.7211 3.80365)
			(end 3.7211 -3.80365)
			(stroke
				(width 0.1)
				(type default)
			)
			(layer "F.Fab")
		)
		(fp_poly
			(pts
				(xy -3.8862 -3.570986) (xy -4.6482 -3.189986) (xy -4.6482 -3.951986)
			)
			(stroke
				(width 0)
				(type default)
			)
			(fill yes)
			(layer "F.Fab")
		)
		(pad "1" smd rect
			(at -2.921 -3.57505 270)
			(size 0.3556 1.4986)
			(layers "F.Cu" "F.Mask" "F.Paste")
			(net "PU_U7_PIN2")
		)
		(pad "2" smd rect
			(at -2.921 -2.925064 270)
			(size 0.3556 1.4986)
			(layers "F.Cu" "F.Mask" "F.Paste")
			(net "PCA9555_MB0_A1")
		)
		(pad "3" smd rect
			(at -2.921 -2.275078 270)
			(size 0.3556 1.4986)
			(layers "F.Cu" "F.Mask" "F.Paste")
			(net "PCA9555_MB0_A2")
		)
		(pad "4" smd rect
			(at -2.921 -1.625092 270)
			(size 0.3556 1.4986)
			(layers "F.Cu" "F.Mask" "F.Paste")
			(net "FAN_0_PRSNT_BUF_N")
		)
		(pad "5" smd rect
			(at -2.921 -0.975106 270)
			(size 0.3556 1.4986)
			(layers "F.Cu" "F.Mask" "F.Paste")
			(net "FAN_1_PRSNT_BUF_N")
		)
		(pad "6" smd rect
			(at -2.921 -0.32512 270)
			(size 0.3556 1.4986)
			(layers "F.Cu" "F.Mask" "F.Paste")
			(net "FAN_2_PRSNT_BUF_N")
		)
		(pad "7" smd rect
			(at -2.921 0.32512 270)
			(size 0.3556 1.4986)
			(layers "F.Cu" "F.Mask" "F.Paste")
			(net "FAN_3_PRSNT_BUF_N")
		)
		(pad "8" smd rect
			(at -2.921 0.975106 270)
			(size 0.3556 1.4986)
			(layers "F.Cu" "F.Mask" "F.Paste")
			(net "FAN_4_PRSNT_BUF_N")
		)
		(pad "9" smd rect
			(at -2.921 1.625092 270)
			(size 0.3556 1.4986)
			(layers "F.Cu" "F.Mask" "F.Paste")
			(net "FAN_5_PRSNT_BUF_N")
		)
		(pad "10" smd rect
			(at -2.921 2.275078 270)
			(size 0.3556 1.4986)
			(layers "F.Cu" "F.Mask" "F.Paste")
			(net "FAN_6_PRSNT_BUF_N")
		)
		(pad "11" smd rect
			(at -2.921 2.925064 270)
			(size 0.3556 1.4986)
			(layers "F.Cu" "F.Mask" "F.Paste")
			(net "FAN_7_PRSNT_BUF_N")
		)
		(pad "12" smd rect
			(at -2.921 3.57505 270)
			(size 0.3556 1.4986)
			(layers "F.Cu" "F.Mask" "F.Paste")
			(net "GND")
		)
		(pad "13" smd rect
			(at 2.921 3.57505 270)
			(size 0.3556 1.4986)
			(layers "F.Cu" "F.Mask" "F.Paste")
			(net "FM_BOARD_SKU_ID0")
		)
		(pad "14" smd rect
			(at 2.921 2.925064 270)
			(size 0.3556 1.4986)
			(layers "F.Cu" "F.Mask" "F.Paste")
			(net "FM_BOARD_SKU_ID1")
		)
		(pad "15" smd rect
			(at 2.921 2.275078 270)
			(size 0.3556 1.4986)
			(layers "F.Cu" "F.Mask" "F.Paste")
			(net "FM_BOARD_SKU_ID2")
		)
		(pad "16" smd rect
			(at 2.921 1.625092 270)
			(size 0.3556 1.4986)
			(layers "F.Cu" "F.Mask" "F.Paste")
			(net "TP_U7_PIN16")
		)
		(pad "17" smd rect
			(at 2.921 0.975106 270)
			(size 0.3556 1.4986)
			(layers "F.Cu" "F.Mask" "F.Paste")
			(net "FM_BOARD_ID0")
		)
		(pad "18" smd rect
			(at 2.921 0.32512 270)
			(size 0.3556 1.4986)
			(layers "F.Cu" "F.Mask" "F.Paste")
			(net "FM_BOARD_ID1")
		)
		(pad "19" smd rect
			(at 2.921 -0.32512 270)
			(size 0.3556 1.4986)
			(layers "F.Cu" "F.Mask" "F.Paste")
			(net "FM_BOARD_ID2")
		)
		(pad "20" smd rect
			(at 2.921 -0.975106 270)
			(size 0.3556 1.4986)
			(layers "F.Cu" "F.Mask" "F.Paste")
			(net "TP_U7_PIN20")
		)
		(pad "21" smd rect
			(at 2.921 -1.625092 270)
			(size 0.3556 1.4986)
			(layers "F.Cu" "F.Mask" "F.Paste")
			(net "PCA9555_MB0_A0")
		)
		(pad "22" smd rect
			(at 2.921 -2.275078 270)
			(size 0.3556 1.4986)
			(layers "F.Cu" "F.Mask" "F.Paste")
			(net "SMB_PDBV_FAN_R_IOX_SCL")
		)
		(pad "23" smd rect
			(at 2.921 -2.925064 270)
			(size 0.3556 1.4986)
			(layers "F.Cu" "F.Mask" "F.Paste")
			(net "SMB_PDBV_FAN_R_IOX_SDA")
		)
		(pad "24" smd rect
			(at 2.921 -3.57505 270)
			(size 0.3556 1.4986)
			(layers "F.Cu" "F.Mask" "F.Paste")
			(net "P3V3_AUX")
		)
	)
	(footprint ""
		(layer "F.Cu")
		(at 14.478 -197.739 180)
		(property "Reference" "D254"
			(at 4.2926 0.05715 0)
			(unlocked yes)
			(layer "F.SilkS")
			(effects
				(font
					(size 0.635 0.4064)
					(thickness 0.1524)
				)
				(justify left)
			)
		)
		(property "Value" ""
			(at 0 0 180)
			(layer "F.Fab")
			(effects
				(font
					(size 1.27 1.27)
				)
			)
		)
		(duplicate_pad_numbers_are_jumpers no)
		(fp_line
			(start 0.94488 0.450088)
			(end 0.94488 -0.450088)
			(stroke
				(width 0.1524)
				(type default)
			)
			(layer "F.SilkS")
		)
		(fp_line
			(start 0.94488 -0.450088)
			(end -0.854964 -0.450088)
			(stroke
				(width 0.1524)
				(type default)
			)
			(layer "F.SilkS")
		)
		(fp_line
			(start 0.870458 -0.2794)
			(end 0.845058 0.4064)
			(stroke
				(width 0.1524)
				(type default)
			)
			(layer "F.SilkS")
		)
		(fp_line
			(start 0.845058 0.4064)
			(end 0.845058 -0.381)
			(stroke
				(width 0.1524)
				(type default)
			)
			(layer "F.SilkS")
		)
		(fp_line
			(start -0.854964 0.450088)
			(end 0.925068 0.450088)
			(stroke
				(width 0.1524)
				(type default)
			)
			(layer "F.SilkS")
		)
		(fp_line
			(start -0.854964 -0.450088)
			(end -0.854964 0.450088)
			(stroke
				(width 0.1524)
				(type default)
			)
			(layer "F.SilkS")
		)
		(fp_line
			(start 0.54991 0.350012)
			(end 0.54991 -0.350012)
			(stroke
				(width 0.1)
				(type default)
			)
			(layer "F.Fab")
		)
		(fp_line
			(start 0.54991 -0.350012)
			(end -0.54991 -0.350012)
			(stroke
				(width 0.1)
				(type default)
			)
			(layer "F.Fab")
		)
		(fp_line
			(start -0.54991 0.350012)
			(end 0.54991 0.350012)
			(stroke
				(width 0.1)
				(type default)
			)
			(layer "F.Fab")
		)
		(fp_line
			(start -0.54991 -0.350012)
			(end -0.54991 0.350012)
			(stroke
				(width 0.1)
				(type default)
			)
			(layer "F.Fab")
		)
		(fp_text user "-"
			(at 2.296922 0.155194 0)
			(unlocked yes)
			(layer "F.SilkS")
			(effects
				(font
					(size 1.905 1.4224)
					(thickness 0.1524)
				)
				(justify left)
			)
		)
		(fp_text user "+"
			(at -0.3048 0.93345 0)
			(unlocked yes)
			(layer "F.SilkS")
			(effects
				(font
					(size 1.905 1.4224)
					(thickness 0.1524)
				)
				(justify left)
			)
		)
		(fp_text user "-"
			(at 2.48539 0.239014 0)
			(unlocked yes)
			(layer "F.Fab")
			(effects
				(font
					(size 1.905 1.4224)
					(thickness 0.1524)
				)
				(justify left)
			)
		)
		(fp_text user "+"
			(at -0.808228 0.239014 0)
			(unlocked yes)
			(layer "F.Fab")
			(effects
				(font
					(size 1.905 1.4224)
					(thickness 0.1524)
				)
				(justify left)
			)
		)
		(pad "A" smd rect
			(at -0.424942 0 180)
			(size 0.5588 0.6096)
			(layers "F.Cu" "F.Mask" "F.Paste")
			(net "GND")
		)
		(pad "C" smd rect
			(at 0.424942 0)
			(size 0.5588 0.6096)
			(layers "F.Cu" "F.Mask" "F.Paste")
			(net "FAN_6_TACH_IL_D")
		)
	)
	(footprint ""
		(layer "F.Cu")
		(at 18.415 -190.881 180)
		(property "Reference" "C93"
			(at 0 0 180)
			(layer "F.SilkS")
			(hide yes)
			(effects
				(font
					(size 1.27 1.27)
				)
			)
		)
		(property "Value" ""
			(at 0 0 180)
			(layer "F.Fab")
			(effects
				(font
					(size 1.27 1.27)
				)
			)
		)
		(duplicate_pad_numbers_are_jumpers no)
		(fp_line
			(start 0.7874 0.4064)
			(end -0.7874 0.4064)
			(stroke
				(width 0.1524)
				(type default)
			)
			(layer "F.SilkS")
		)
		(fp_line
			(start 0.7874 -0.4064)
			(end 0.7874 0.4064)
			(stroke
				(width 0.1524)
				(type default)
			)
			(layer "F.SilkS")
		)
		(fp_line
			(start -0.7874 0.4064)
			(end -0.7874 -0.4064)
			(stroke
				(width 0.1524)
				(type default)
			)
			(layer "F.SilkS")
		)
		(fp_line
			(start -0.7874 -0.4064)
			(end 0.7874 -0.4064)
			(stroke
				(width 0.1524)
				(type default)
			)
			(layer "F.SilkS")
		)
		(fp_line
			(start 0.67945 0.3048)
			(end 0.120396 0.3048)
			(stroke
				(width 0.1)
				(type default)
			)
			(layer "F.Fab")
		)
		(fp_line
			(start 0.67945 -0.3048)
			(end 0.67945 0.3048)
			(stroke
				(width 0.1)
				(type default)
			)
			(layer "F.Fab")
		)
		(fp_line
			(start 0.12065 -0.2794)
			(end 0.12065 -0.3048)
			(stroke
				(width 0.1)
				(type default)
			)
			(layer "F.Fab")
		)
		(fp_line
			(start 0.12065 -0.3048)
			(end 0.67945 -0.3048)
			(stroke
				(width 0.1)
				(type default)
			)
			(layer "F.Fab")
		)
		(fp_line
			(start 0.120396 0.3048)
			(end 0.120396 0.2794)
			(stroke
				(width 0.1)
				(type default)
			)
			(layer "F.Fab")
		)
		(fp_line
			(start 0.120396 0.2794)
			(end -0.12065 0.2794)
			(stroke
				(width 0.1)
				(type default)
			)
			(layer "F.Fab")
		)
		(fp_line
			(start -0.12065 0.3048)
			(end -0.67945 0.3048)
			(stroke
				(width 0.1)
				(type default)
			)
			(layer "F.Fab")
		)
		(fp_line
			(start -0.12065 0.2794)
			(end -0.12065 0.3048)
			(stroke
				(width 0.1)
				(type default)
			)
			(layer "F.Fab")
		)
		(fp_line
			(start -0.12065 -0.2794)
			(end 0.12065 -0.2794)
			(stroke
				(width 0.1)
				(type default)
			)
			(layer "F.Fab")
		)
		(fp_line
			(start -0.12065 -0.305054)
			(end -0.12065 -0.2794)
			(stroke
				(width 0.1)
				(type default)
			)
			(layer "F.Fab")
		)
		(fp_line
			(start -0.67945 0.3048)
			(end -0.67945 -0.305054)
			(stroke
				(width 0.1)
				(type default)
			)
			(layer "F.Fab")
		)
		(fp_line
			(start -0.67945 -0.305054)
			(end -0.12065 -0.305054)
			(stroke
				(width 0.1)
				(type default)
			)
			(layer "F.Fab")
		)
		(pad "1" smd circle
			(at -0.40005 0 180)
			(size 0 0)
			(layers "F.Cu" "F.Mask" "F.Paste")
			(net "GND")
		)
		(pad "2" smd circle
			(at 0.40005 0 180)
			(size 0 0)
			(layers "F.Cu" "F.Mask" "F.Paste")
			(net "P3V3_AUX")
		)
	)
	(footprint ""
		(layer "F.Cu")
		(at 19.431 -294.386 -90)
		(property "Reference" "R5379"
			(at 0 0 270)
			(layer "F.SilkS")
			(hide yes)
			(effects
				(font
					(size 1.27 1.27)
				)
			)
		)
		(property "Value" ""
			(at 0 0 270)
			(layer "F.Fab")
			(effects
				(font
					(size 1.27 1.27)
				)
			)
		)
		(duplicate_pad_numbers_are_jumpers no)
		(fp_line
			(start -0.7874 0.4064)
			(end -0.7874 -0.4064)
			(stroke
				(width 0.1524)
				(type default)
			)
			(layer "F.SilkS")
		)
		(fp_line
			(start 0.7874 0.4064)
			(end -0.7874 0.4064)
			(stroke
				(width 0.1524)
				(type default)
			)
			(layer "F.SilkS")
		)
		(fp_line
			(start -0.7874 -0.4064)
			(end 0.7874 -0.4064)
			(stroke
				(width 0.1524)
				(type default)
			)
			(layer "F.SilkS")
		)
		(fp_line
			(start 0.7874 -0.4064)
			(end 0.7874 0.4064)
			(stroke
				(width 0.1524)
				(type default)
			)
			(layer "F.SilkS")
		)
		(fp_line
			(start -0.67945 0.3048)
			(end -0.67945 -0.305054)
			(stroke
				(width 0.1)
				(type default)
			)
			(layer "F.Fab")
		)
		(fp_line
			(start -0.12065 0.3048)
			(end -0.67945 0.3048)
			(stroke
				(width 0.1)
				(type default)
			)
			(layer "F.Fab")
		)
		(fp_line
			(start 0.120396 0.3048)
			(end 0.120396 0.2794)
			(stroke
				(width 0.1)
				(type default)
			)
			(layer "F.Fab")
		)
		(fp_line
			(start 0.67945 0.3048)
			(end 0.120396 0.3048)
			(stroke
				(width 0.1)
				(type default)
			)
			(layer "F.Fab")
		)
		(fp_line
			(start -0.12065 0.2794)
			(end -0.12065 0.3048)
			(stroke
				(width 0.1)
				(type default)
			)
			(layer "F.Fab")
		)
		(fp_line
			(start 0.120396 0.2794)
			(end -0.12065 0.2794)
			(stroke
				(width 0.1)
				(type default)
			)
			(layer "F.Fab")
		)
		(fp_line
			(start -0.12065 -0.2794)
			(end 0.12065 -0.2794)
			(stroke
				(width 0.1)
				(type default)
			)
			(layer "F.Fab")
		)
		(fp_line
			(start 0.12065 -0.2794)
			(end 0.12065 -0.3048)
			(stroke
				(width 0.1)
				(type default)
			)
			(layer "F.Fab")
		)
		(fp_line
			(start 0.12065 -0.3048)
			(end 0.67945 -0.3048)
			(stroke
				(width 0.1)
				(type default)
			)
			(layer "F.Fab")
		)
		(fp_line
			(start 0.67945 -0.3048)
			(end 0.67945 0.3048)
			(stroke
				(width 0.1)
				(type default)
			)
			(layer "F.Fab")
		)
		(fp_line
			(start -0.67945 -0.305054)
			(end -0.12065 -0.305054)
			(stroke
				(width 0.1)
				(type default)
			)
			(layer "F.Fab")
		)
		(fp_line
			(start -0.12065 -0.305054)
			(end -0.12065 -0.2794)
			(stroke
				(width 0.1)
				(type default)
			)
			(layer "F.Fab")
		)
		(pad "1" smd circle
			(at -0.40005 0 270)
			(size 0 0)
			(layers "F.Cu" "F.Mask" "F.Paste")
			(net "P3V3_AUX")
		)
		(pad "2" smd circle
			(at 0.40005 0 270)
			(size 0 0)
			(layers "F.Cu" "F.Mask" "F.Paste")
			(net "FAN_7_FAIL_R_LED")
		)
	)
	(footprint ""
		(layer "F.Cu")
		(at 33.02 -208.308956 180)
		(property "Reference" "C2030"
			(at 0 0 180)
			(layer "F.SilkS")
			(hide yes)
			(effects
				(font
					(size 1.27 1.27)
				)
			)
		)
		(property "Value" ""
			(at 0 0 180)
			(layer "F.Fab")
			(effects
				(font
					(size 1.27 1.27)
				)
			)
		)
		(duplicate_pad_numbers_are_jumpers no)
		(fp_line
			(start 0.7874 0.4064)
			(end -0.7874 0.4064)
			(stroke
				(width 0.1524)
				(type default)
			)
			(layer "F.SilkS")
		)
		(fp_line
			(start 0.7874 -0.4064)
			(end 0.7874 0.4064)
			(stroke
				(width 0.1524)
				(type default)
			)
			(layer "F.SilkS")
		)
		(fp_line
			(start -0.7874 0.4064)
			(end -0.7874 -0.4064)
			(stroke
				(width 0.1524)
				(type default)
			)
			(layer "F.SilkS")
		)
		(fp_line
			(start -0.7874 -0.4064)
			(end 0.7874 -0.4064)
			(stroke
				(width 0.1524)
				(type default)
			)
			(layer "F.SilkS")
		)
		(fp_line
			(start 0.67945 0.3048)
			(end 0.120396 0.3048)
			(stroke
				(width 0.1)
				(type default)
			)
			(layer "F.Fab")
		)
		(fp_line
			(start 0.67945 -0.3048)
			(end 0.67945 0.3048)
			(stroke
				(width 0.1)
				(type default)
			)
			(layer "F.Fab")
		)
		(fp_line
			(start 0.12065 -0.2794)
			(end 0.12065 -0.3048)
			(stroke
				(width 0.1)
				(type default)
			)
			(layer "F.Fab")
		)
		(fp_line
			(start 0.12065 -0.3048)
			(end 0.67945 -0.3048)
			(stroke
				(width 0.1)
				(type default)
			)
			(layer "F.Fab")
		)
		(fp_line
			(start 0.120396 0.3048)
			(end 0.120396 0.2794)
			(stroke
				(width 0.1)
				(type default)
			)
			(layer "F.Fab")
		)
		(fp_line
			(start 0.120396 0.2794)
			(end -0.12065 0.2794)
			(stroke
				(width 0.1)
				(type default)
			)
			(layer "F.Fab")
		)
		(fp_line
			(start -0.12065 0.3048)
			(end -0.67945 0.3048)
			(stroke
				(width 0.1)
				(type default)
			)
			(layer "F.Fab")
		)
		(fp_line
			(start -0.12065 0.2794)
			(end -0.12065 0.3048)
			(stroke
				(width 0.1)
				(type default)
			)
			(layer "F.Fab")
		)
		(fp_line
			(start -0.12065 -0.2794)
			(end 0.12065 -0.2794)
			(stroke
				(width 0.1)
				(type default)
			)
			(layer "F.Fab")
		)
		(fp_line
			(start -0.12065 -0.305054)
			(end -0.12065 -0.2794)
			(stroke
				(width 0.1)
				(type default)
			)
			(layer "F.Fab")
		)
		(fp_line
			(start -0.67945 0.3048)
			(end -0.67945 -0.305054)
			(stroke
				(width 0.1)
				(type default)
			)
			(layer "F.Fab")
		)
		(fp_line
			(start -0.67945 -0.305054)
			(end -0.12065 -0.305054)
			(stroke
				(width 0.1)
				(type default)
			)
			(layer "F.Fab")
		)
		(pad "1" smd circle
			(at -0.40005 0 180)
			(size 0 0)
			(layers "F.Cu" "F.Mask" "F.Paste")
			(net "FAN_1_TACH_IL_R")
		)
		(pad "2" smd circle
			(at 0.40005 0 180)
			(size 0 0)
			(layers "F.Cu" "F.Mask" "F.Paste")
			(net "GND")
		)
	)
	(footprint ""
		(layer "F.Cu")
		(at 9.906 -170.053 180)
		(property "Reference" "U25"
			(at 2.00533 -1.016 90)
			(unlocked yes)
			(layer "F.SilkS")
			(effects
				(font
					(size 0.7874 0.5842)
					(thickness 0.1524)
				)
				(justify left)
			)
		)
		(property "Value" ""
			(at 0 0 180)
			(layer "F.Fab")
			(effects
				(font
					(size 1.27 1.27)
				)
			)
		)
		(duplicate_pad_numbers_are_jumpers no)
		(fp_line
			(start 1.3462 1.100074)
			(end -1.3462 1.100074)
			(stroke
				(width 0.1524)
				(type default)
			)
			(layer "F.SilkS")
		)
		(fp_line
			(start 1.3462 -1.100074)
			(end 1.3462 1.100074)
			(stroke
				(width 0.1524)
				(type default)
			)
			(layer "F.SilkS")
		)
		(fp_line
			(start 0.670052 -1.100074)
			(end 1.3462 -1.100074)
			(stroke
				(width 0.1524)
				(type default)
			)
			(layer "F.SilkS")
		)
		(fp_line
			(start 0 -0.381)
			(end 0.670052 -1.100074)
			(stroke
				(width 0.1524)
				(type default)
			)
			(layer "F.SilkS")
		)
		(fp_line
			(start -0.670052 -1.100074)
			(end 0 -0.381)
			(stroke
				(width 0.1524)
				(type default)
			)
			(layer "F.SilkS")
		)
		(fp_line
			(start -1.3462 1.100074)
			(end -1.3462 -1.100074)
			(stroke
				(width 0.1524)
				(type default)
			)
			(layer "F.SilkS")
		)
		(fp_line
			(start -1.3462 -1.100074)
			(end -0.670052 -1.100074)
			(stroke
				(width 0.1524)
				(type default)
			)
			(layer "F.SilkS")
		)
		(fp_poly
			(pts
				(xy -1.524 -0.649986) (xy -2.286 -1.030986) (xy -2.286 -0.268986)
			)
			(stroke
				(width 0)
				(type default)
			)
			(fill yes)
			(layer "F.SilkS")
		)
		(fp_line
			(start 1.100074 0.8001)
			(end 0.670052 0.8001)
			(stroke
				(width 0.1)
				(type default)
			)
			(layer "F.Fab")
		)
		(fp_line
			(start 1.100074 -0.8001)
			(end 1.100074 0.8001)
			(stroke
				(width 0.1)
				(type default)
			)
			(layer "F.Fab")
		)
		(fp_line
			(start 0.670052 1.100074)
			(end -0.670052 1.100074)
			(stroke
				(width 0.1)
				(type default)
			)
			(layer "F.Fab")
		)
		(fp_line
			(start 0.670052 0.8001)
			(end 0.670052 1.100074)
			(stroke
				(width 0.1)
				(type default)
			)
			(layer "F.Fab")
		)
		(fp_line
			(start 0.670052 -0.8001)
			(end 1.100074 -0.8001)
			(stroke
				(width 0.1)
				(type default)
			)
			(layer "F.Fab")
		)
		(fp_line
			(start 0.670052 -0.8001)
			(end 0.670052 0.8001)
			(stroke
				(width 0.1)
				(type default)
			)
			(layer "F.Fab")
		)
		(fp_line
			(start 0.670052 -1.100074)
			(end 0.670052 -0.8001)
			(stroke
				(width 0.1)
				(type default)
			)
			(layer "F.Fab")
		)
		(fp_line
			(start -0.670052 1.100074)
			(end -0.670052 0.8001)
			(stroke
				(width 0.1)
				(type default)
			)
			(layer "F.Fab")
		)
		(fp_line
			(start -0.670052 0.8001)
			(end -0.670052 -0.8001)
			(stroke
				(width 0.1)
				(type default)
			)
			(layer "F.Fab")
		)
		(fp_line
			(start -0.670052 0.8001)
			(end -1.100074 0.8001)
			(stroke
				(width 0.1)
				(type default)
			)
			(layer "F.Fab")
		)
		(fp_line
			(start -0.670052 -0.8001)
			(end -0.670052 -1.100074)
			(stroke
				(width 0.1)
				(type default)
			)
			(layer "F.Fab")
		)
		(fp_line
			(start -0.670052 -1.100074)
			(end 0.670052 -1.100074)
			(stroke
				(width 0.1)
				(type default)
			)
			(layer "F.Fab")
		)
		(fp_line
			(start -1.100074 0.8001)
			(end -1.100074 -0.8001)
			(stroke
				(width 0.1)
				(type default)
			)
			(layer "F.Fab")
		)
		(fp_line
			(start -1.100074 -0.8001)
			(end -0.670052 -0.8001)
			(stroke
				(width 0.1)
				(type default)
			)
			(layer "F.Fab")
		)
		(fp_poly
			(pts
				(xy -1.524 -0.649986) (xy -2.286 -1.030986) (xy -2.286 -0.268986)
			)
			(stroke
				(width 0)
				(type default)
			)
			(fill yes)
			(layer "F.Fab")
		)
		(pad "1" smd rect
			(at -0.94996 -0.649986 90)
			(size 0.4064 0.508)
			(layers "F.Cu" "F.Mask" "F.Paste")
			(net "FAN_4_PRESENT_N")
		)
		(pad "2" smd rect
			(at -0.94996 0 90)
			(size 0.4064 0.508)
			(layers "F.Cu" "F.Mask" "F.Paste")
			(net "GND")
		)
		(pad "3" smd rect
			(at -0.94996 0.649986 90)
			(size 0.4064 0.508)
			(layers "F.Cu" "F.Mask" "F.Paste")
			(net "FAN_5_PRESENT_N")
		)
		(pad "4" smd rect
			(at 0.94996 0.649986 90)
			(size 0.4064 0.508)
			(layers "F.Cu" "F.Mask" "F.Paste")
			(net "FAN_5_PRSNT_BUF_R_N")
		)
		(pad "5" smd rect
			(at 0.94996 0 90)
			(size 0.4064 0.508)
			(layers "F.Cu" "F.Mask" "F.Paste")
			(net "P3V3_AUX")
		)
		(pad "6" smd rect
			(at 0.94996 -0.649986 90)
			(size 0.4064 0.508)
			(layers "F.Cu" "F.Mask" "F.Paste")
			(net "FAN_4_PRSNT_BUF_R_N")
		)
	)
	(footprint ""
		(layer "F.Cu")
		(at 16.520922 -106.776012)
		(property "Reference" "C2033"
			(at 0 0 0)
			(layer "F.SilkS")
			(hide yes)
			(effects
				(font
					(size 1.27 1.27)
				)
			)
		)
		(property "Value" ""
			(at 0 0 0)
			(layer "F.Fab")
			(effects
				(font
					(size 1.27 1.27)
				)
			)
		)
		(duplicate_pad_numbers_are_jumpers no)
		(fp_line
			(start -0.7874 -0.4064)
			(end 0.7874 -0.4064)
			(stroke
				(width 0.1524)
				(type default)
			)
			(layer "F.SilkS")
		)
		(fp_line
			(start -0.7874 0.4064)
			(end -0.7874 -0.4064)
			(stroke
				(width 0.1524)
				(type default)
			)
			(layer "F.SilkS")
		)
		(fp_line
			(start 0.7874 -0.4064)
			(end 0.7874 0.4064)
			(stroke
				(width 0.1524)
				(type default)
			)
			(layer "F.SilkS")
		)
		(fp_line
			(start 0.7874 0.4064)
			(end -0.7874 0.4064)
			(stroke
				(width 0.1524)
				(type default)
			)
			(layer "F.SilkS")
		)
		(fp_line
			(start -0.67945 -0.305054)
			(end -0.12065 -0.305054)
			(stroke
				(width 0.1)
				(type default)
			)
			(layer "F.Fab")
		)
		(fp_line
			(start -0.67945 0.3048)
			(end -0.67945 -0.305054)
			(stroke
				(width 0.1)
				(type default)
			)
			(layer "F.Fab")
		)
		(fp_line
			(start -0.12065 -0.305054)
			(end -0.12065 -0.2794)
			(stroke
				(width 0.1)
				(type default)
			)
			(layer "F.Fab")
		)
		(fp_line
			(start -0.12065 -0.2794)
			(end 0.12065 -0.2794)
			(stroke
				(width 0.1)
				(type default)
			)
			(layer "F.Fab")
		)
		(fp_line
			(start -0.12065 0.2794)
			(end -0.12065 0.3048)
			(stroke
				(width 0.1)
				(type default)
			)
			(layer "F.Fab")
		)
		(fp_line
			(start -0.12065 0.3048)
			(end -0.67945 0.3048)
			(stroke
				(width 0.1)
				(type default)
			)
			(layer "F.Fab")
		)
		(fp_line
			(start 0.120396 0.2794)
			(end -0.12065 0.2794)
			(stroke
				(width 0.1)
				(type default)
			)
			(layer "F.Fab")
		)
		(fp_line
			(start 0.120396 0.3048)
			(end 0.120396 0.2794)
			(stroke
				(width 0.1)
				(type default)
			)
			(layer "F.Fab")
		)
		(fp_line
			(start 0.12065 -0.3048)
			(end 0.67945 -0.3048)
			(stroke
				(width 0.1)
				(type default)
			)
			(layer "F.Fab")
		)
		(fp_line
			(start 0.12065 -0.2794)
			(end 0.12065 -0.3048)
			(stroke
				(width 0.1)
				(type default)
			)
			(layer "F.Fab")
		)
		(fp_line
			(start 0.67945 -0.3048)
			(end 0.67945 0.3048)
			(stroke
				(width 0.1)
				(type default)
			)
			(layer "F.Fab")
		)
		(fp_line
			(start 0.67945 0.3048)
			(end 0.120396 0.3048)
			(stroke
				(width 0.1)
				(type default)
			)
			(layer "F.Fab")
		)
		(pad "1" smd circle
			(at -0.40005 0)
			(size 0 0)
			(layers "F.Cu" "F.Mask" "F.Paste")
			(net "FAN_5_PWM_IL_R")
		)
		(pad "2" smd circle
			(at 0.40005 0)
			(size 0 0)
			(layers "F.Cu" "F.Mask" "F.Paste")
			(net "GND")
		)
	)
	(footprint ""
		(layer "F.Cu")
		(at 14.361922 -106.776012)
		(property "Reference" "R5201"
			(at 0 0 0)
			(layer "F.SilkS")
			(hide yes)
			(effects
				(font
					(size 1.27 1.27)
				)
			)
		)
		(property "Value" ""
			(at 0 0 0)
			(layer "F.Fab")
			(effects
				(font
					(size 1.27 1.27)
				)
			)
		)
		(duplicate_pad_numbers_are_jumpers no)
		(fp_line
			(start -0.7874 -0.4064)
			(end 0.7874 -0.4064)
			(stroke
				(width 0.1524)
				(type default)
			)
			(layer "F.SilkS")
		)
		(fp_line
			(start -0.7874 0.4064)
			(end -0.7874 -0.4064)
			(stroke
				(width 0.1524)
				(type default)
			)
			(layer "F.SilkS")
		)
		(fp_line
			(start 0.7874 -0.4064)
			(end 0.7874 0.4064)
			(stroke
				(width 0.1524)
				(type default)
			)
			(layer "F.SilkS")
		)
		(fp_line
			(start 0.7874 0.4064)
			(end -0.7874 0.4064)
			(stroke
				(width 0.1524)
				(type default)
			)
			(layer "F.SilkS")
		)
		(fp_line
			(start -0.67945 -0.305054)
			(end -0.12065 -0.305054)
			(stroke
				(width 0.1)
				(type default)
			)
			(layer "F.Fab")
		)
		(fp_line
			(start -0.67945 0.3048)
			(end -0.67945 -0.305054)
			(stroke
				(width 0.1)
				(type default)
			)
			(layer "F.Fab")
		)
		(fp_line
			(start -0.12065 -0.305054)
			(end -0.12065 -0.2794)
			(stroke
				(width 0.1)
				(type default)
			)
			(layer "F.Fab")
		)
		(fp_line
			(start -0.12065 -0.2794)
			(end 0.12065 -0.2794)
			(stroke
				(width 0.1)
				(type default)
			)
			(layer "F.Fab")
		)
		(fp_line
			(start -0.12065 0.2794)
			(end -0.12065 0.3048)
			(stroke
				(width 0.1)
				(type default)
			)
			(layer "F.Fab")
		)
		(fp_line
			(start -0.12065 0.3048)
			(end -0.67945 0.3048)
			(stroke
				(width 0.1)
				(type default)
			)
			(layer "F.Fab")
		)
		(fp_line
			(start 0.120396 0.2794)
			(end -0.12065 0.2794)
			(stroke
				(width 0.1)
				(type default)
			)
			(layer "F.Fab")
		)
		(fp_line
			(start 0.120396 0.3048)
			(end 0.120396 0.2794)
			(stroke
				(width 0.1)
				(type default)
			)
			(layer "F.Fab")
		)
		(fp_line
			(start 0.12065 -0.3048)
			(end 0.67945 -0.3048)
			(stroke
				(width 0.1)
				(type default)
			)
			(layer "F.Fab")
		)
		(fp_line
			(start 0.12065 -0.2794)
			(end 0.12065 -0.3048)
			(stroke
				(width 0.1)
				(type default)
			)
			(layer "F.Fab")
		)
		(fp_line
			(start 0.67945 -0.3048)
			(end 0.67945 0.3048)
			(stroke
				(width 0.1)
				(type default)
			)
			(layer "F.Fab")
		)
		(fp_line
			(start 0.67945 0.3048)
			(end 0.120396 0.3048)
			(stroke
				(width 0.1)
				(type default)
			)
			(layer "F.Fab")
		)
		(pad "1" smd circle
			(at -0.40005 0)
			(size 0 0)
			(layers "F.Cu" "F.Mask" "F.Paste")
			(net "FAN_5_PWM_IL_R")
		)
		(pad "2" smd circle
			(at 0.40005 0)
			(size 0 0)
			(layers "F.Cu" "F.Mask" "F.Paste")
			(net "FAN_5_PWM_IL")
		)
	)
	(footprint ""
		(layer "F.Cu")
		(at 27.94 -135.382 -90)
		(property "Reference" "R5458"
			(at 0 0 270)
			(layer "F.SilkS")
			(hide yes)
			(effects
				(font
					(size 1.27 1.27)
				)
			)
		)
		(property "Value" ""
			(at 0 0 270)
			(layer "F.Fab")
			(effects
				(font
					(size 1.27 1.27)
				)
			)
		)
		(duplicate_pad_numbers_are_jumpers no)
		(fp_line
			(start -0.7874 0.4064)
			(end -0.7874 -0.4064)
			(stroke
				(width 0.1524)
				(type default)
			)
			(layer "F.SilkS")
		)
		(fp_line
			(start 0.7874 0.4064)
			(end -0.7874 0.4064)
			(stroke
				(width 0.1524)
				(type default)
			)
			(layer "F.SilkS")
		)
		(fp_line
			(start -0.7874 -0.4064)
			(end 0.7874 -0.4064)
			(stroke
				(width 0.1524)
				(type default)
			)
			(layer "F.SilkS")
		)
		(fp_line
			(start 0.7874 -0.4064)
			(end 0.7874 0.4064)
			(stroke
				(width 0.1524)
				(type default)
			)
			(layer "F.SilkS")
		)
		(fp_line
			(start -0.67945 0.3048)
			(end -0.67945 -0.305054)
			(stroke
				(width 0.1)
				(type default)
			)
			(layer "F.Fab")
		)
		(fp_line
			(start -0.12065 0.3048)
			(end -0.67945 0.3048)
			(stroke
				(width 0.1)
				(type default)
			)
			(layer "F.Fab")
		)
		(fp_line
			(start 0.120396 0.3048)
			(end 0.120396 0.2794)
			(stroke
				(width 0.1)
				(type default)
			)
			(layer "F.Fab")
		)
		(fp_line
			(start 0.67945 0.3048)
			(end 0.120396 0.3048)
			(stroke
				(width 0.1)
				(type default)
			)
			(layer "F.Fab")
		)
		(fp_line
			(start -0.12065 0.2794)
			(end -0.12065 0.3048)
			(stroke
				(width 0.1)
				(type default)
			)
			(layer "F.Fab")
		)
		(fp_line
			(start 0.120396 0.2794)
			(end -0.12065 0.2794)
			(stroke
				(width 0.1)
				(type default)
			)
			(layer "F.Fab")
		)
		(fp_line
			(start -0.12065 -0.2794)
			(end 0.12065 -0.2794)
			(stroke
				(width 0.1)
				(type default)
			)
			(layer "F.Fab")
		)
		(fp_line
			(start 0.12065 -0.2794)
			(end 0.12065 -0.3048)
			(stroke
				(width 0.1)
				(type default)
			)
			(layer "F.Fab")
		)
		(fp_line
			(start 0.12065 -0.3048)
			(end 0.67945 -0.3048)
			(stroke
				(width 0.1)
				(type default)
			)
			(layer "F.Fab")
		)
		(fp_line
			(start 0.67945 -0.3048)
			(end 0.67945 0.3048)
			(stroke
				(width 0.1)
				(type default)
			)
			(layer "F.Fab")
		)
		(fp_line
			(start -0.67945 -0.305054)
			(end -0.12065 -0.305054)
			(stroke
				(width 0.1)
				(type default)
			)
			(layer "F.Fab")
		)
		(fp_line
			(start -0.12065 -0.305054)
			(end -0.12065 -0.2794)
			(stroke
				(width 0.1)
				(type default)
			)
			(layer "F.Fab")
		)
		(pad "1" smd circle
			(at -0.40005 0 270)
			(size 0 0)
			(layers "F.Cu" "F.Mask" "F.Paste")
			(net "SMB_PDBV_FAN_SDA")
		)
		(pad "2" smd circle
			(at 0.40005 0 270)
			(size 0 0)
			(layers "F.Cu" "F.Mask" "F.Paste")
			(net "SMB_PDBV_FAN_R_U317_SDA")
		)
	)
	(footprint ""
		(layer "F.Cu")
		(at 29.718 -143.891 -90)
		(property "Reference" "R4787"
			(at 0 0 270)
			(layer "F.SilkS")
			(hide yes)
			(effects
				(font
					(size 1.27 1.27)
				)
			)
		)
		(property "Value" ""
			(at 0 0 270)
			(layer "F.Fab")
			(effects
				(font
					(size 1.27 1.27)
				)
			)
		)
		(duplicate_pad_numbers_are_jumpers no)
		(fp_line
			(start -0.7874 0.4064)
			(end -0.7874 -0.4064)
			(stroke
				(width 0.1524)
				(type default)
			)
			(layer "F.SilkS")
		)
		(fp_line
			(start 0.7874 0.4064)
			(end -0.7874 0.4064)
			(stroke
				(width 0.1524)
				(type default)
			)
			(layer "F.SilkS")
		)
		(fp_line
			(start -0.7874 -0.4064)
			(end 0.7874 -0.4064)
			(stroke
				(width 0.1524)
				(type default)
			)
			(layer "F.SilkS")
		)
		(fp_line
			(start 0.7874 -0.4064)
			(end 0.7874 0.4064)
			(stroke
				(width 0.1524)
				(type default)
			)
			(layer "F.SilkS")
		)
		(fp_line
			(start -0.67945 0.3048)
			(end -0.67945 -0.305054)
			(stroke
				(width 0.1)
				(type default)
			)
			(layer "F.Fab")
		)
		(fp_line
			(start -0.12065 0.3048)
			(end -0.67945 0.3048)
			(stroke
				(width 0.1)
				(type default)
			)
			(layer "F.Fab")
		)
		(fp_line
			(start 0.120396 0.3048)
			(end 0.120396 0.2794)
			(stroke
				(width 0.1)
				(type default)
			)
			(layer "F.Fab")
		)
		(fp_line
			(start 0.67945 0.3048)
			(end 0.120396 0.3048)
			(stroke
				(width 0.1)
				(type default)
			)
			(layer "F.Fab")
		)
		(fp_line
			(start -0.12065 0.2794)
			(end -0.12065 0.3048)
			(stroke
				(width 0.1)
				(type default)
			)
			(layer "F.Fab")
		)
		(fp_line
			(start 0.120396 0.2794)
			(end -0.12065 0.2794)
			(stroke
				(width 0.1)
				(type default)
			)
			(layer "F.Fab")
		)
		(fp_line
			(start -0.12065 -0.2794)
			(end 0.12065 -0.2794)
			(stroke
				(width 0.1)
				(type default)
			)
			(layer "F.Fab")
		)
		(fp_line
			(start 0.12065 -0.2794)
			(end 0.12065 -0.3048)
			(stroke
				(width 0.1)
				(type default)
			)
			(layer "F.Fab")
		)
		(fp_line
			(start 0.12065 -0.3048)
			(end 0.67945 -0.3048)
			(stroke
				(width 0.1)
				(type default)
			)
			(layer "F.Fab")
		)
		(fp_line
			(start 0.67945 -0.3048)
			(end 0.67945 0.3048)
			(stroke
				(width 0.1)
				(type default)
			)
			(layer "F.Fab")
		)
		(fp_line
			(start -0.67945 -0.305054)
			(end -0.12065 -0.305054)
			(stroke
				(width 0.1)
				(type default)
			)
			(layer "F.Fab")
		)
		(fp_line
			(start -0.12065 -0.305054)
			(end -0.12065 -0.2794)
			(stroke
				(width 0.1)
				(type default)
			)
			(layer "F.Fab")
		)
		(pad "1" smd circle
			(at -0.40005 0 270)
			(size 0 0)
			(layers "F.Cu" "F.Mask" "F.Paste")
			(net "SMB_FAN2_R_SDA")
		)
		(pad "2" smd circle
			(at 0.40005 0 270)
			(size 0 0)
			(layers "F.Cu" "F.Mask" "F.Paste")
			(net "SMB_FAN2_SDA")
		)
	)
	(footprint ""
		(layer "F.Cu")
		(at 20.5486 -160.02 -90)
		(property "Reference" "R5470"
			(at 0 0 270)
			(layer "F.SilkS")
			(hide yes)
			(effects
				(font
					(size 1.27 1.27)
				)
			)
		)
		(property "Value" ""
			(at 0 0 270)
			(layer "F.Fab")
			(effects
				(font
					(size 1.27 1.27)
				)
			)
		)
		(duplicate_pad_numbers_are_jumpers no)
		(fp_line
			(start -0.7874 0.4064)
			(end -0.7874 -0.4064)
			(stroke
				(width 0.1524)
				(type default)
			)
			(layer "F.SilkS")
		)
		(fp_line
			(start 0.7874 0.4064)
			(end -0.7874 0.4064)
			(stroke
				(width 0.1524)
				(type default)
			)
			(layer "F.SilkS")
		)
		(fp_line
			(start -0.7874 -0.4064)
			(end 0.7874 -0.4064)
			(stroke
				(width 0.1524)
				(type default)
			)
			(layer "F.SilkS")
		)
		(fp_line
			(start 0.7874 -0.4064)
			(end 0.7874 0.4064)
			(stroke
				(width 0.1524)
				(type default)
			)
			(layer "F.SilkS")
		)
		(fp_line
			(start -0.67945 0.3048)
			(end -0.67945 -0.305054)
			(stroke
				(width 0.1)
				(type default)
			)
			(layer "F.Fab")
		)
		(fp_line
			(start -0.12065 0.3048)
			(end -0.67945 0.3048)
			(stroke
				(width 0.1)
				(type default)
			)
			(layer "F.Fab")
		)
		(fp_line
			(start 0.120396 0.3048)
			(end 0.120396 0.2794)
			(stroke
				(width 0.1)
				(type default)
			)
			(layer "F.Fab")
		)
		(fp_line
			(start 0.67945 0.3048)
			(end 0.120396 0.3048)
			(stroke
				(width 0.1)
				(type default)
			)
			(layer "F.Fab")
		)
		(fp_line
			(start -0.12065 0.2794)
			(end -0.12065 0.3048)
			(stroke
				(width 0.1)
				(type default)
			)
			(layer "F.Fab")
		)
		(fp_line
			(start 0.120396 0.2794)
			(end -0.12065 0.2794)
			(stroke
				(width 0.1)
				(type default)
			)
			(layer "F.Fab")
		)
		(fp_line
			(start -0.12065 -0.2794)
			(end 0.12065 -0.2794)
			(stroke
				(width 0.1)
				(type default)
			)
			(layer "F.Fab")
		)
		(fp_line
			(start 0.12065 -0.2794)
			(end 0.12065 -0.3048)
			(stroke
				(width 0.1)
				(type default)
			)
			(layer "F.Fab")
		)
		(fp_line
			(start 0.12065 -0.3048)
			(end 0.67945 -0.3048)
			(stroke
				(width 0.1)
				(type default)
			)
			(layer "F.Fab")
		)
		(fp_line
			(start 0.67945 -0.3048)
			(end 0.67945 0.3048)
			(stroke
				(width 0.1)
				(type default)
			)
			(layer "F.Fab")
		)
		(fp_line
			(start -0.67945 -0.305054)
			(end -0.12065 -0.305054)
			(stroke
				(width 0.1)
				(type default)
			)
			(layer "F.Fab")
		)
		(fp_line
			(start -0.12065 -0.305054)
			(end -0.12065 -0.2794)
			(stroke
				(width 0.1)
				(type default)
			)
			(layer "F.Fab")
		)
		(pad "1" smd circle
			(at -0.40005 0 270)
			(size 0 0)
			(layers "F.Cu" "F.Mask" "F.Paste")
			(net "PD_TCA9548_SML1_U321_A2")
		)
		(pad "2" smd circle
			(at 0.40005 0 270)
			(size 0 0)
			(layers "F.Cu" "F.Mask" "F.Paste")
			(net "GND")
		)
	)
	(footprint ""
		(layer "F.Cu")
		(at 27.432 -179.451 180)
		(property "Reference" "R5489"
			(at 0 0 180)
			(layer "F.SilkS")
			(hide yes)
			(effects
				(font
					(size 1.27 1.27)
				)
			)
		)
		(property "Value" ""
			(at 0 0 180)
			(layer "F.Fab")
			(effects
				(font
					(size 1.27 1.27)
				)
			)
		)
		(duplicate_pad_numbers_are_jumpers no)
		(fp_line
			(start 0.7874 0.4064)
			(end -0.7874 0.4064)
			(stroke
				(width 0.1524)
				(type default)
			)
			(layer "F.SilkS")
		)
		(fp_line
			(start 0.7874 -0.4064)
			(end 0.7874 0.4064)
			(stroke
				(width 0.1524)
				(type default)
			)
			(layer "F.SilkS")
		)
		(fp_line
			(start -0.7874 0.4064)
			(end -0.7874 -0.4064)
			(stroke
				(width 0.1524)
				(type default)
			)
			(layer "F.SilkS")
		)
		(fp_line
			(start -0.7874 -0.4064)
			(end 0.7874 -0.4064)
			(stroke
				(width 0.1524)
				(type default)
			)
			(layer "F.SilkS")
		)
		(fp_line
			(start 0.67945 0.3048)
			(end 0.120396 0.3048)
			(stroke
				(width 0.1)
				(type default)
			)
			(layer "F.Fab")
		)
		(fp_line
			(start 0.67945 -0.3048)
			(end 0.67945 0.3048)
			(stroke
				(width 0.1)
				(type default)
			)
			(layer "F.Fab")
		)
		(fp_line
			(start 0.12065 -0.2794)
			(end 0.12065 -0.3048)
			(stroke
				(width 0.1)
				(type default)
			)
			(layer "F.Fab")
		)
		(fp_line
			(start 0.12065 -0.3048)
			(end 0.67945 -0.3048)
			(stroke
				(width 0.1)
				(type default)
			)
			(layer "F.Fab")
		)
		(fp_line
			(start 0.120396 0.3048)
			(end 0.120396 0.2794)
			(stroke
				(width 0.1)
				(type default)
			)
			(layer "F.Fab")
		)
		(fp_line
			(start 0.120396 0.2794)
			(end -0.12065 0.2794)
			(stroke
				(width 0.1)
				(type default)
			)
			(layer "F.Fab")
		)
		(fp_line
			(start -0.12065 0.3048)
			(end -0.67945 0.3048)
			(stroke
				(width 0.1)
				(type default)
			)
			(layer "F.Fab")
		)
		(fp_line
			(start -0.12065 0.2794)
			(end -0.12065 0.3048)
			(stroke
				(width 0.1)
				(type default)
			)
			(layer "F.Fab")
		)
		(fp_line
			(start -0.12065 -0.2794)
			(end 0.12065 -0.2794)
			(stroke
				(width 0.1)
				(type default)
			)
			(layer "F.Fab")
		)
		(fp_line
			(start -0.12065 -0.305054)
			(end -0.12065 -0.2794)
			(stroke
				(width 0.1)
				(type default)
			)
			(layer "F.Fab")
		)
		(fp_line
			(start -0.67945 0.3048)
			(end -0.67945 -0.305054)
			(stroke
				(width 0.1)
				(type default)
			)
			(layer "F.Fab")
		)
		(fp_line
			(start -0.67945 -0.305054)
			(end -0.12065 -0.305054)
			(stroke
				(width 0.1)
				(type default)
			)
			(layer "F.Fab")
		)
		(pad "1" smd circle
			(at -0.40005 0 180)
			(size 0 0)
			(layers "F.Cu" "F.Mask" "F.Paste")
			(net "P52V_FAN_2_BUFF_EN")
		)
		(pad "2" smd circle
			(at 0.40005 0 180)
			(size 0 0)
			(layers "F.Cu" "F.Mask" "F.Paste")
			(net "P52V_FAN_2_BUFF_EN_R")
		)
	)
	(footprint ""
		(layer "F.Cu")
		(at 23.495 -162.941 90)
		(property "Reference" "R5275"
			(at 0 0 90)
			(layer "F.SilkS")
			(hide yes)
			(effects
				(font
					(size 1.27 1.27)
				)
			)
		)
		(property "Value" ""
			(at 0 0 90)
			(layer "F.Fab")
			(effects
				(font
					(size 1.27 1.27)
				)
			)
		)
		(duplicate_pad_numbers_are_jumpers no)
		(fp_line
			(start 0.7874 -0.4064)
			(end 0.7874 0.4064)
			(stroke
				(width 0.1524)
				(type default)
			)
			(layer "F.SilkS")
		)
		(fp_line
			(start -0.7874 -0.4064)
			(end 0.7874 -0.4064)
			(stroke
				(width 0.1524)
				(type default)
			)
			(layer "F.SilkS")
		)
		(fp_line
			(start 0.7874 0.4064)
			(end -0.7874 0.4064)
			(stroke
				(width 0.1524)
				(type default)
			)
			(layer "F.SilkS")
		)
		(fp_line
			(start -0.7874 0.4064)
			(end -0.7874 -0.4064)
			(stroke
				(width 0.1524)
				(type default)
			)
			(layer "F.SilkS")
		)
		(fp_line
			(start -0.12065 -0.305054)
			(end -0.12065 -0.2794)
			(stroke
				(width 0.1)
				(type default)
			)
			(layer "F.Fab")
		)
		(fp_line
			(start -0.67945 -0.305054)
			(end -0.12065 -0.305054)
			(stroke
				(width 0.1)
				(type default)
			)
			(layer "F.Fab")
		)
		(fp_line
			(start 0.67945 -0.3048)
			(end 0.67945 0.3048)
			(stroke
				(width 0.1)
				(type default)
			)
			(layer "F.Fab")
		)
		(fp_line
			(start 0.12065 -0.3048)
			(end 0.67945 -0.3048)
			(stroke
				(width 0.1)
				(type default)
			)
			(layer "F.Fab")
		)
		(fp_line
			(start 0.12065 -0.2794)
			(end 0.12065 -0.3048)
			(stroke
				(width 0.1)
				(type default)
			)
			(layer "F.Fab")
		)
		(fp_line
			(start -0.12065 -0.2794)
			(end 0.12065 -0.2794)
			(stroke
				(width 0.1)
				(type default)
			)
			(layer "F.Fab")
		)
		(fp_line
			(start 0.120396 0.2794)
			(end -0.12065 0.2794)
			(stroke
				(width 0.1)
				(type default)
			)
			(layer "F.Fab")
		)
		(fp_line
			(start -0.12065 0.2794)
			(end -0.12065 0.3048)
			(stroke
				(width 0.1)
				(type default)
			)
			(layer "F.Fab")
		)
		(fp_line
			(start 0.67945 0.3048)
			(end 0.120396 0.3048)
			(stroke
				(width 0.1)
				(type default)
			)
			(layer "F.Fab")
		)
		(fp_line
			(start 0.120396 0.3048)
			(end 0.120396 0.2794)
			(stroke
				(width 0.1)
				(type default)
			)
			(layer "F.Fab")
		)
		(fp_line
			(start -0.12065 0.3048)
			(end -0.67945 0.3048)
			(stroke
				(width 0.1)
				(type default)
			)
			(layer "F.Fab")
		)
		(fp_line
			(start -0.67945 0.3048)
			(end -0.67945 -0.305054)
			(stroke
				(width 0.1)
				(type default)
			)
			(layer "F.Fab")
		)
		(pad "1" smd circle
			(at -0.40005 0 90)
			(size 0 0)
			(layers "F.Cu" "F.Mask" "F.Paste")
			(net "SMB_FAN7_R_SDA")
		)
		(pad "2" smd circle
			(at 0.40005 0 90)
			(size 0 0)
			(layers "F.Cu" "F.Mask" "F.Paste")
			(net "P3V3_AUX")
		)
	)
	(footprint ""
		(layer "F.Cu")
		(at 15.24 -216.027 180)
		(property "Reference" "Q15"
			(at 4.445 -1.29667 0)
			(unlocked yes)
			(layer "F.SilkS")
			(effects
				(font
					(size 0.7874 0.5842)
					(thickness 0.1524)
				)
				(justify left)
			)
		)
		(property "Value" ""
			(at 0 0 180)
			(layer "F.Fab")
			(effects
				(font
					(size 1.27 1.27)
				)
			)
		)
		(duplicate_pad_numbers_are_jumpers no)
		(fp_line
			(start 1.905 1.651)
			(end -1.905 1.651)
			(stroke
				(width 0.1524)
				(type default)
			)
			(layer "F.SilkS")
		)
		(fp_line
			(start 1.905 -1.651)
			(end 1.905 1.651)
			(stroke
				(width 0.1524)
				(type default)
			)
			(layer "F.SilkS")
		)
		(fp_line
			(start -1.905 1.651)
			(end -1.905 -1.651)
			(stroke
				(width 0.1524)
				(type default)
			)
			(layer "F.SilkS")
		)
		(fp_line
			(start -1.905 -1.651)
			(end 1.905 -1.651)
			(stroke
				(width 0.1524)
				(type default)
			)
			(layer "F.SilkS")
		)
		(fp_line
			(start 1.249934 0.219964)
			(end 0.6985 0.219964)
			(stroke
				(width 0.1)
				(type default)
			)
			(layer "F.Fab")
		)
		(fp_line
			(start 1.249934 -0.219964)
			(end 1.249934 0.219964)
			(stroke
				(width 0.1)
				(type default)
			)
			(layer "F.Fab")
		)
		(fp_line
			(start 0.6985 1.524)
			(end -0.6985 1.524)
			(stroke
				(width 0.1)
				(type default)
			)
			(layer "F.Fab")
		)
		(fp_line
			(start 0.6985 0.219964)
			(end 0.6985 1.524)
			(stroke
				(width 0.1)
				(type default)
			)
			(layer "F.Fab")
		)
		(fp_line
			(start 0.6985 -0.219964)
			(end 1.249934 -0.219964)
			(stroke
				(width 0.1)
				(type default)
			)
			(layer "F.Fab")
		)
		(fp_line
			(start 0.6985 -1.524)
			(end 0.6985 -0.219964)
			(stroke
				(width 0.1)
				(type default)
			)
			(layer "F.Fab")
		)
		(fp_line
			(start -0.6985 1.524)
			(end -0.6985 1.169924)
			(stroke
				(width 0.1)
				(type default)
			)
			(layer "F.Fab")
		)
		(fp_line
			(start -0.6985 1.169924)
			(end -1.249934 1.169924)
			(stroke
				(width 0.1)
				(type default)
			)
			(layer "F.Fab")
		)
		(fp_line
			(start -0.6985 0.729996)
			(end -0.6985 -0.729996)
			(stroke
				(width 0.1)
				(type default)
			)
			(layer "F.Fab")
		)
		(fp_line
			(start -0.6985 -0.729996)
			(end -1.249934 -0.729996)
			(stroke
				(width 0.1)
				(type default)
			)
			(layer "F.Fab")
		)
		(fp_line
			(start -0.6985 -1.169924)
			(end -0.6985 -1.524)
			(stroke
				(width 0.1)
				(type default)
			)
			(layer "F.Fab")
		)
		(fp_line
			(start -0.6985 -1.524)
			(end 0.6985 -1.524)
			(stroke
				(width 0.1)
				(type default)
			)
			(layer "F.Fab")
		)
		(fp_line
			(start -1.249934 1.169924)
			(end -1.249934 0.729996)
			(stroke
				(width 0.1)
				(type default)
			)
			(layer "F.Fab")
		)
		(fp_line
			(start -1.249934 0.729996)
			(end -0.6985 0.729996)
			(stroke
				(width 0.1)
				(type default)
			)
			(layer "F.Fab")
		)
		(fp_line
			(start -1.249934 -0.729996)
			(end -1.249934 -1.169924)
			(stroke
				(width 0.1)
				(type default)
			)
			(layer "F.Fab")
		)
		(fp_line
			(start -1.249934 -1.169924)
			(end -0.6985 -1.169924)
			(stroke
				(width 0.1)
				(type default)
			)
			(layer "F.Fab")
		)
		(fp_rect
			(start -0.6985 1.524)
			(end 0.6985 -1.524)
			(stroke
				(width 0)
				(type default)
			)
			(fill no)
			(layer "F.Fab")
		)
		(pad "D" smd rect
			(at 1.1176 0 90)
			(size 1.016 1.27)
			(layers "F.Cu" "F.Mask" "F.Paste")
			(net "P12V_LED_FAN6")
		)
		(pad "G" smd rect
			(at -1.1176 -1.016 90)
			(size 1.016 1.27)
			(layers "F.Cu" "F.Mask" "F.Paste")
			(net "U411_D1")
		)
		(pad "S" smd rect
			(at -1.1176 1.016 90)
			(size 1.016 1.27)
			(layers "F.Cu" "F.Mask" "F.Paste")
			(net "P12V_LED")
		)
	)
	(footprint ""
		(layer "F.Cu")
		(at 19.05 -16.002 180)
		(property "Reference" "R5308"
			(at 0 0 180)
			(layer "F.SilkS")
			(hide yes)
			(effects
				(font
					(size 1.27 1.27)
				)
			)
		)
		(property "Value" ""
			(at 0 0 180)
			(layer "F.Fab")
			(effects
				(font
					(size 1.27 1.27)
				)
			)
		)
		(duplicate_pad_numbers_are_jumpers no)
		(fp_line
			(start 1.2954 0.5842)
			(end -1.2954 0.5842)
			(stroke
				(width 0.1524)
				(type default)
			)
			(layer "F.SilkS")
		)
		(fp_line
			(start 1.2954 -0.5842)
			(end 1.2954 0.5842)
			(stroke
				(width 0.1524)
				(type default)
			)
			(layer "F.SilkS")
		)
		(fp_line
			(start -1.2954 0.5842)
			(end -1.2954 -0.5842)
			(stroke
				(width 0.1524)
				(type default)
			)
			(layer "F.SilkS")
		)
		(fp_line
			(start -1.2954 -0.5842)
			(end 1.2954 -0.5842)
			(stroke
				(width 0.1524)
				(type default)
			)
			(layer "F.SilkS")
		)
		(fp_line
			(start 1.1938 0.4064)
			(end 0.8636 0.4064)
			(stroke
				(width 0.1)
				(type default)
			)
			(layer "F.Fab")
		)
		(fp_line
			(start 1.1938 -0.406654)
			(end 1.1938 0.4064)
			(stroke
				(width 0.1)
				(type default)
			)
			(layer "F.Fab")
		)
		(fp_line
			(start 0.8636 0.4572)
			(end -0.8636 0.4572)
			(stroke
				(width 0.1)
				(type default)
			)
			(layer "F.Fab")
		)
		(fp_line
			(start 0.8636 0.4064)
			(end 0.8636 0.4572)
			(stroke
				(width 0.1)
				(type default)
			)
			(layer "F.Fab")
		)
		(fp_line
			(start 0.8636 -0.406654)
			(end 1.1938 -0.406654)
			(stroke
				(width 0.1)
				(type default)
			)
			(layer "F.Fab")
		)
		(fp_line
			(start 0.8636 -0.4572)
			(end 0.8636 -0.406654)
			(stroke
				(width 0.1)
				(type default)
			)
			(layer "F.Fab")
		)
		(fp_line
			(start -0.8636 0.4572)
			(end -0.8636 0.4318)
			(stroke
				(width 0.1)
				(type default)
			)
			(layer "F.Fab")
		)
		(fp_line
			(start -0.8636 0.4318)
			(end -0.8636 0.4064)
			(stroke
				(width 0.1)
				(type default)
			)
			(layer "F.Fab")
		)
		(fp_line
			(start -0.8636 0.4064)
			(end -1.1938 0.4064)
			(stroke
				(width 0.1)
				(type default)
			)
			(layer "F.Fab")
		)
		(fp_line
			(start -0.8636 -0.406654)
			(end -0.8636 -0.4572)
			(stroke
				(width 0.1)
				(type default)
			)
			(layer "F.Fab")
		)
		(fp_line
			(start -0.8636 -0.4572)
			(end 0.8636 -0.4572)
			(stroke
				(width 0.1)
				(type default)
			)
			(layer "F.Fab")
		)
		(fp_line
			(start -1.1938 0.4064)
			(end -1.1938 -0.406654)
			(stroke
				(width 0.1)
				(type default)
			)
			(layer "F.Fab")
		)
		(fp_line
			(start -1.1938 -0.406654)
			(end -0.8636 -0.406654)
			(stroke
				(width 0.1)
				(type default)
			)
			(layer "F.Fab")
		)
		(pad "1" smd rect
			(at -0.7366 0 90)
			(size 0.7112 0.8128)
			(layers "F.Cu" "F.Mask" "F.Paste")
			(net "P52V_FAN_4")
		)
		(pad "2" smd rect
			(at 0.7366 0 90)
			(size 0.7112 0.8128)
			(layers "F.Cu" "F.Mask" "F.Paste")
			(net "FAN_4_TACH_IL_R")
		)
	)
	(footprint ""
		(layer "F.Cu")
		(at 36.703 -107.061 90)
		(property "Reference" "R5404"
			(at 0 0 90)
			(layer "F.SilkS")
			(hide yes)
			(effects
				(font
					(size 1.27 1.27)
				)
			)
		)
		(property "Value" ""
			(at 0 0 90)
			(layer "F.Fab")
			(effects
				(font
					(size 1.27 1.27)
				)
			)
		)
		(duplicate_pad_numbers_are_jumpers no)
		(fp_line
			(start 0.7874 -0.4064)
			(end 0.7874 0.4064)
			(stroke
				(width 0.1524)
				(type default)
			)
			(layer "F.SilkS")
		)
		(fp_line
			(start -0.7874 -0.4064)
			(end 0.7874 -0.4064)
			(stroke
				(width 0.1524)
				(type default)
			)
			(layer "F.SilkS")
		)
		(fp_line
			(start 0.7874 0.4064)
			(end -0.7874 0.4064)
			(stroke
				(width 0.1524)
				(type default)
			)
			(layer "F.SilkS")
		)
		(fp_line
			(start -0.7874 0.4064)
			(end -0.7874 -0.4064)
			(stroke
				(width 0.1524)
				(type default)
			)
			(layer "F.SilkS")
		)
		(fp_line
			(start -0.12065 -0.305054)
			(end -0.12065 -0.2794)
			(stroke
				(width 0.1)
				(type default)
			)
			(layer "F.Fab")
		)
		(fp_line
			(start -0.67945 -0.305054)
			(end -0.12065 -0.305054)
			(stroke
				(width 0.1)
				(type default)
			)
			(layer "F.Fab")
		)
		(fp_line
			(start 0.67945 -0.3048)
			(end 0.67945 0.3048)
			(stroke
				(width 0.1)
				(type default)
			)
			(layer "F.Fab")
		)
		(fp_line
			(start 0.12065 -0.3048)
			(end 0.67945 -0.3048)
			(stroke
				(width 0.1)
				(type default)
			)
			(layer "F.Fab")
		)
		(fp_line
			(start 0.12065 -0.2794)
			(end 0.12065 -0.3048)
			(stroke
				(width 0.1)
				(type default)
			)
			(layer "F.Fab")
		)
		(fp_line
			(start -0.12065 -0.2794)
			(end 0.12065 -0.2794)
			(stroke
				(width 0.1)
				(type default)
			)
			(layer "F.Fab")
		)
		(fp_line
			(start 0.120396 0.2794)
			(end -0.12065 0.2794)
			(stroke
				(width 0.1)
				(type default)
			)
			(layer "F.Fab")
		)
		(fp_line
			(start -0.12065 0.2794)
			(end -0.12065 0.3048)
			(stroke
				(width 0.1)
				(type default)
			)
			(layer "F.Fab")
		)
		(fp_line
			(start 0.67945 0.3048)
			(end 0.120396 0.3048)
			(stroke
				(width 0.1)
				(type default)
			)
			(layer "F.Fab")
		)
		(fp_line
			(start 0.120396 0.3048)
			(end 0.120396 0.2794)
			(stroke
				(width 0.1)
				(type default)
			)
			(layer "F.Fab")
		)
		(fp_line
			(start -0.12065 0.3048)
			(end -0.67945 0.3048)
			(stroke
				(width 0.1)
				(type default)
			)
			(layer "F.Fab")
		)
		(fp_line
			(start -0.67945 0.3048)
			(end -0.67945 -0.305054)
			(stroke
				(width 0.1)
				(type default)
			)
			(layer "F.Fab")
		)
		(pad "1" smd rect
			(at -0.40005 0 270)
			(size 0.4572 0.508)
			(layers "F.Cu" "F.Mask" "F.Paste")
			(net "FAN_2_OK_LED_R_N")
		)
		(pad "2" smd rect
			(at 0.40005 0 270)
			(size 0.4572 0.508)
			(layers "F.Cu" "F.Mask" "F.Paste")
			(net "FAN_2_OK_R_LED_N")
		)
	)
	(footprint ""
		(layer "F.Cu")
		(at 37.338 -204.752956 180)
		(property "Reference" "R5204"
			(at 0 0 180)
			(layer "F.SilkS")
			(hide yes)
			(effects
				(font
					(size 1.27 1.27)
				)
			)
		)
		(property "Value" ""
			(at 0 0 180)
			(layer "F.Fab")
			(effects
				(font
					(size 1.27 1.27)
				)
			)
		)
		(duplicate_pad_numbers_are_jumpers no)
		(fp_line
			(start 0.7874 0.4064)
			(end -0.7874 0.4064)
			(stroke
				(width 0.1524)
				(type default)
			)
			(layer "F.SilkS")
		)
		(fp_line
			(start 0.7874 -0.4064)
			(end 0.7874 0.4064)
			(stroke
				(width 0.1524)
				(type default)
			)
			(layer "F.SilkS")
		)
		(fp_line
			(start -0.7874 0.4064)
			(end -0.7874 -0.4064)
			(stroke
				(width 0.1524)
				(type default)
			)
			(layer "F.SilkS")
		)
		(fp_line
			(start -0.7874 -0.4064)
			(end 0.7874 -0.4064)
			(stroke
				(width 0.1524)
				(type default)
			)
			(layer "F.SilkS")
		)
		(fp_line
			(start 0.67945 0.3048)
			(end 0.120396 0.3048)
			(stroke
				(width 0.1)
				(type default)
			)
			(layer "F.Fab")
		)
		(fp_line
			(start 0.67945 -0.3048)
			(end 0.67945 0.3048)
			(stroke
				(width 0.1)
				(type default)
			)
			(layer "F.Fab")
		)
		(fp_line
			(start 0.12065 -0.2794)
			(end 0.12065 -0.3048)
			(stroke
				(width 0.1)
				(type default)
			)
			(layer "F.Fab")
		)
		(fp_line
			(start 0.12065 -0.3048)
			(end 0.67945 -0.3048)
			(stroke
				(width 0.1)
				(type default)
			)
			(layer "F.Fab")
		)
		(fp_line
			(start 0.120396 0.3048)
			(end 0.120396 0.2794)
			(stroke
				(width 0.1)
				(type default)
			)
			(layer "F.Fab")
		)
		(fp_line
			(start 0.120396 0.2794)
			(end -0.12065 0.2794)
			(stroke
				(width 0.1)
				(type default)
			)
			(layer "F.Fab")
		)
		(fp_line
			(start -0.12065 0.3048)
			(end -0.67945 0.3048)
			(stroke
				(width 0.1)
				(type default)
			)
			(layer "F.Fab")
		)
		(fp_line
			(start -0.12065 0.2794)
			(end -0.12065 0.3048)
			(stroke
				(width 0.1)
				(type default)
			)
			(layer "F.Fab")
		)
		(fp_line
			(start -0.12065 -0.2794)
			(end 0.12065 -0.2794)
			(stroke
				(width 0.1)
				(type default)
			)
			(layer "F.Fab")
		)
		(fp_line
			(start -0.12065 -0.305054)
			(end -0.12065 -0.2794)
			(stroke
				(width 0.1)
				(type default)
			)
			(layer "F.Fab")
		)
		(fp_line
			(start -0.67945 0.3048)
			(end -0.67945 -0.305054)
			(stroke
				(width 0.1)
				(type default)
			)
			(layer "F.Fab")
		)
		(fp_line
			(start -0.67945 -0.305054)
			(end -0.12065 -0.305054)
			(stroke
				(width 0.1)
				(type default)
			)
			(layer "F.Fab")
		)
		(pad "1" smd circle
			(at -0.40005 0 180)
			(size 0 0)
			(layers "F.Cu" "F.Mask" "F.Paste")
			(net "SMB_FAN1_SDA_R")
		)
		(pad "2" smd circle
			(at 0.40005 0 180)
			(size 0 0)
			(layers "F.Cu" "F.Mask" "F.Paste")
			(net "SMB_FAN1_SDA")
		)
	)
	(footprint ""
		(layer "F.Cu")
		(at 30.353 -178.816)
		(property "Reference" "R511"
			(at 0 0 0)
			(layer "F.SilkS")
			(hide yes)
			(effects
				(font
					(size 1.27 1.27)
				)
			)
		)
		(property "Value" ""
			(at 0 0 0)
			(layer "F.Fab")
			(effects
				(font
					(size 1.27 1.27)
				)
			)
		)
		(duplicate_pad_numbers_are_jumpers no)
		(fp_line
			(start -0.7874 -0.4064)
			(end 0.7874 -0.4064)
			(stroke
				(width 0.1524)
				(type default)
			)
			(layer "F.SilkS")
		)
		(fp_line
			(start -0.7874 0.4064)
			(end -0.7874 -0.4064)
			(stroke
				(width 0.1524)
				(type default)
			)
			(layer "F.SilkS")
		)
		(fp_line
			(start 0.7874 -0.4064)
			(end 0.7874 0.4064)
			(stroke
				(width 0.1524)
				(type default)
			)
			(layer "F.SilkS")
		)
		(fp_line
			(start 0.7874 0.4064)
			(end -0.7874 0.4064)
			(stroke
				(width 0.1524)
				(type default)
			)
			(layer "F.SilkS")
		)
		(fp_line
			(start -0.67945 -0.305054)
			(end -0.12065 -0.305054)
			(stroke
				(width 0.1)
				(type default)
			)
			(layer "F.Fab")
		)
		(fp_line
			(start -0.67945 0.3048)
			(end -0.67945 -0.305054)
			(stroke
				(width 0.1)
				(type default)
			)
			(layer "F.Fab")
		)
		(fp_line
			(start -0.12065 -0.305054)
			(end -0.12065 -0.2794)
			(stroke
				(width 0.1)
				(type default)
			)
			(layer "F.Fab")
		)
		(fp_line
			(start -0.12065 -0.2794)
			(end 0.12065 -0.2794)
			(stroke
				(width 0.1)
				(type default)
			)
			(layer "F.Fab")
		)
		(fp_line
			(start -0.12065 0.2794)
			(end -0.12065 0.3048)
			(stroke
				(width 0.1)
				(type default)
			)
			(layer "F.Fab")
		)
		(fp_line
			(start -0.12065 0.3048)
			(end -0.67945 0.3048)
			(stroke
				(width 0.1)
				(type default)
			)
			(layer "F.Fab")
		)
		(fp_line
			(start 0.120396 0.2794)
			(end -0.12065 0.2794)
			(stroke
				(width 0.1)
				(type default)
			)
			(layer "F.Fab")
		)
		(fp_line
			(start 0.120396 0.3048)
			(end 0.120396 0.2794)
			(stroke
				(width 0.1)
				(type default)
			)
			(layer "F.Fab")
		)
		(fp_line
			(start 0.12065 -0.3048)
			(end 0.67945 -0.3048)
			(stroke
				(width 0.1)
				(type default)
			)
			(layer "F.Fab")
		)
		(fp_line
			(start 0.12065 -0.2794)
			(end 0.12065 -0.3048)
			(stroke
				(width 0.1)
				(type default)
			)
			(layer "F.Fab")
		)
		(fp_line
			(start 0.67945 -0.3048)
			(end 0.67945 0.3048)
			(stroke
				(width 0.1)
				(type default)
			)
			(layer "F.Fab")
		)
		(fp_line
			(start 0.67945 0.3048)
			(end 0.120396 0.3048)
			(stroke
				(width 0.1)
				(type default)
			)
			(layer "F.Fab")
		)
		(pad "1" smd circle
			(at -0.40005 0)
			(size 0 0)
			(layers "F.Cu" "F.Mask" "F.Paste")
			(net "P3V3_AUX")
		)
		(pad "2" smd circle
			(at 0.40005 0)
			(size 0 0)
			(layers "F.Cu" "F.Mask" "F.Paste")
			(net "P52V_FAN_2_BUFF_EN")
		)
	)
	(footprint ""
		(layer "F.Cu")
		(at 22.225 -34.163 -90)
		(property "Reference" "R5658"
			(at 0 0 270)
			(layer "F.SilkS")
			(hide yes)
			(effects
				(font
					(size 1.27 1.27)
				)
			)
		)
		(property "Value" ""
			(at 0 0 270)
			(layer "F.Fab")
			(effects
				(font
					(size 1.27 1.27)
				)
			)
		)
		(duplicate_pad_numbers_are_jumpers no)
		(fp_line
			(start -0.7874 0.4064)
			(end -0.7874 -0.4064)
			(stroke
				(width 0.1524)
				(type default)
			)
			(layer "F.SilkS")
		)
		(fp_line
			(start 0.7874 0.4064)
			(end -0.7874 0.4064)
			(stroke
				(width 0.1524)
				(type default)
			)
			(layer "F.SilkS")
		)
		(fp_line
			(start -0.7874 -0.4064)
			(end 0.7874 -0.4064)
			(stroke
				(width 0.1524)
				(type default)
			)
			(layer "F.SilkS")
		)
		(fp_line
			(start 0.7874 -0.4064)
			(end 0.7874 0.4064)
			(stroke
				(width 0.1524)
				(type default)
			)
			(layer "F.SilkS")
		)
		(fp_line
			(start -0.67945 0.3048)
			(end -0.67945 -0.305054)
			(stroke
				(width 0.1)
				(type default)
			)
			(layer "F.Fab")
		)
		(fp_line
			(start -0.12065 0.3048)
			(end -0.67945 0.3048)
			(stroke
				(width 0.1)
				(type default)
			)
			(layer "F.Fab")
		)
		(fp_line
			(start 0.120396 0.3048)
			(end 0.120396 0.2794)
			(stroke
				(width 0.1)
				(type default)
			)
			(layer "F.Fab")
		)
		(fp_line
			(start 0.67945 0.3048)
			(end 0.120396 0.3048)
			(stroke
				(width 0.1)
				(type default)
			)
			(layer "F.Fab")
		)
		(fp_line
			(start -0.12065 0.2794)
			(end -0.12065 0.3048)
			(stroke
				(width 0.1)
				(type default)
			)
			(layer "F.Fab")
		)
		(fp_line
			(start 0.120396 0.2794)
			(end -0.12065 0.2794)
			(stroke
				(width 0.1)
				(type default)
			)
			(layer "F.Fab")
		)
		(fp_line
			(start -0.12065 -0.2794)
			(end 0.12065 -0.2794)
			(stroke
				(width 0.1)
				(type default)
			)
			(layer "F.Fab")
		)
		(fp_line
			(start 0.12065 -0.2794)
			(end 0.12065 -0.3048)
			(stroke
				(width 0.1)
				(type default)
			)
			(layer "F.Fab")
		)
		(fp_line
			(start 0.12065 -0.3048)
			(end 0.67945 -0.3048)
			(stroke
				(width 0.1)
				(type default)
			)
			(layer "F.Fab")
		)
		(fp_line
			(start 0.67945 -0.3048)
			(end 0.67945 0.3048)
			(stroke
				(width 0.1)
				(type default)
			)
			(layer "F.Fab")
		)
		(fp_line
			(start -0.67945 -0.305054)
			(end -0.12065 -0.305054)
			(stroke
				(width 0.1)
				(type default)
			)
			(layer "F.Fab")
		)
		(fp_line
			(start -0.12065 -0.305054)
			(end -0.12065 -0.2794)
			(stroke
				(width 0.1)
				(type default)
			)
			(layer "F.Fab")
		)
		(pad "1" smd rect
			(at -0.40005 0 90)
			(size 0.4572 0.508)
			(layers "F.Cu" "F.Mask" "F.Paste")
			(net "P12V_LED")
		)
		(pad "2" smd rect
			(at 0.40005 0 90)
			(size 0.4572 0.508)
			(layers "F.Cu" "F.Mask" "F.Paste")
			(net "U409_D1")
		)
	)
	(footprint ""
		(layer "F.Cu")
		(at 34.544 -105.791)
		(property "Reference" "U372"
			(at -2.74955 3.17246 90)
			(unlocked yes)
			(layer "F.SilkS")
			(effects
				(font
					(size 0.7874 0.5842)
					(thickness 0.1524)
				)
				(justify left)
			)
		)
		(property "Value" ""
			(at 0 0 0)
			(layer "F.Fab")
			(effects
				(font
					(size 1.27 1.27)
				)
			)
		)
		(duplicate_pad_numbers_are_jumpers no)
		(fp_line
			(start -1.335278 -1.100074)
			(end -1.335278 1.100074)
			(stroke
				(width 0.1524)
				(type default)
			)
			(layer "F.SilkS")
		)
		(fp_line
			(start -1.335278 1.100074)
			(end 1.335278 1.100074)
			(stroke
				(width 0.1524)
				(type default)
			)
			(layer "F.SilkS")
		)
		(fp_line
			(start 1.335278 -1.100074)
			(end -1.335278 -1.100074)
			(stroke
				(width 0.1524)
				(type default)
			)
			(layer "F.SilkS")
		)
		(fp_line
			(start 1.335278 1.100074)
			(end 1.335278 -1.100074)
			(stroke
				(width 0.1524)
				(type default)
			)
			(layer "F.SilkS")
		)
		(fp_line
			(start -0.674878 -1.100074)
			(end -0.674878 1.100074)
			(stroke
				(width 0.1)
				(type default)
			)
			(layer "F.Fab")
		)
		(fp_line
			(start -0.674878 1.100074)
			(end 0.674878 1.100074)
			(stroke
				(width 0.1)
				(type default)
			)
			(layer "F.Fab")
		)
		(fp_line
			(start 0.674878 -1.100074)
			(end -0.674878 -1.100074)
			(stroke
				(width 0.1)
				(type default)
			)
			(layer "F.Fab")
		)
		(fp_line
			(start 0.674878 1.100074)
			(end 0.674878 -1.100074)
			(stroke
				(width 0.1)
				(type default)
			)
			(layer "F.Fab")
		)
		(pad "D" smd rect
			(at 0.8001 0 270)
			(size 0.6096 0.8128)
			(layers "F.Cu" "F.Mask" "F.Paste")
			(net "FAN_2_OK_LED_R_N")
		)
		(pad "G" smd rect
			(at -0.8001 -0.649986 270)
			(size 0.6096 0.8128)
			(layers "F.Cu" "F.Mask" "F.Paste")
			(net "FAN_2_OK_R_LED")
		)
		(pad "S" smd rect
			(at -0.8001 0.649986 270)
			(size 0.6096 0.8128)
			(layers "F.Cu" "F.Mask" "F.Paste")
			(net "GND")
		)
	)
	(footprint ""
		(layer "F.Cu")
		(at 14.351 -300.736 180)
		(property "Reference" "D258"
			(at 4.064 -1.04267 0)
			(unlocked yes)
			(layer "F.SilkS")
			(effects
				(font
					(size 0.7874 0.5842)
					(thickness 0.1524)
				)
				(justify left)
			)
		)
		(property "Value" ""
			(at 0 0 180)
			(layer "F.Fab")
			(effects
				(font
					(size 1.27 1.27)
				)
			)
		)
		(duplicate_pad_numbers_are_jumpers no)
		(fp_line
			(start 0.94488 0.450088)
			(end 0.94488 -0.450088)
			(stroke
				(width 0.1524)
				(type default)
			)
			(layer "F.SilkS")
		)
		(fp_line
			(start 0.94488 -0.450088)
			(end -0.854964 -0.450088)
			(stroke
				(width 0.1524)
				(type default)
			)
			(layer "F.SilkS")
		)
		(fp_line
			(start 0.870458 -0.2794)
			(end 0.845058 0.4064)
			(stroke
				(width 0.1524)
				(type default)
			)
			(layer "F.SilkS")
		)
		(fp_line
			(start 0.845058 0.4064)
			(end 0.845058 -0.381)
			(stroke
				(width 0.1524)
				(type default)
			)
			(layer "F.SilkS")
		)
		(fp_line
			(start -0.854964 0.450088)
			(end 0.925068 0.450088)
			(stroke
				(width 0.1524)
				(type default)
			)
			(layer "F.SilkS")
		)
		(fp_line
			(start -0.854964 -0.450088)
			(end -0.854964 0.450088)
			(stroke
				(width 0.1524)
				(type default)
			)
			(layer "F.SilkS")
		)
		(fp_line
			(start 0.54991 0.350012)
			(end 0.54991 -0.350012)
			(stroke
				(width 0.1)
				(type default)
			)
			(layer "F.Fab")
		)
		(fp_line
			(start 0.54991 -0.350012)
			(end -0.54991 -0.350012)
			(stroke
				(width 0.1)
				(type default)
			)
			(layer "F.Fab")
		)
		(fp_line
			(start -0.54991 0.350012)
			(end 0.54991 0.350012)
			(stroke
				(width 0.1)
				(type default)
			)
			(layer "F.Fab")
		)
		(fp_line
			(start -0.54991 -0.350012)
			(end -0.54991 0.350012)
			(stroke
				(width 0.1)
				(type default)
			)
			(layer "F.Fab")
		)
		(fp_text user "-"
			(at 2.159 0.22225 0)
			(unlocked yes)
			(layer "F.SilkS")
			(effects
				(font
					(size 1.905 1.4224)
					(thickness 0.1524)
				)
				(justify left)
			)
		)
		(fp_text user "+"
			(at -0.66802 -0.50927 0)
			(unlocked yes)
			(layer "F.SilkS")
			(effects
				(font
					(size 1.905 1.4224)
					(thickness 0.1524)
				)
				(justify left)
			)
		)
		(fp_text user "-"
			(at 2.48539 0.239014 0)
			(unlocked yes)
			(layer "F.Fab")
			(effects
				(font
					(size 1.905 1.4224)
					(thickness 0.1524)
				)
				(justify left)
			)
		)
		(fp_text user "+"
			(at -0.808228 0.239014 0)
			(unlocked yes)
			(layer "F.Fab")
			(effects
				(font
					(size 1.905 1.4224)
					(thickness 0.1524)
				)
				(justify left)
			)
		)
		(pad "A" smd rect
			(at -0.424942 0 180)
			(size 0.5588 0.6096)
			(layers "F.Cu" "F.Mask" "F.Paste")
			(net "GND")
		)
		(pad "C" smd rect
			(at 0.424942 0)
			(size 0.5588 0.6096)
			(layers "F.Cu" "F.Mask" "F.Paste")
			(net "FAN_7_OK_R_LED_N")
		)
	)
	(footprint ""
		(layer "F.Cu")
		(at 36.703 -65.278)
		(property "Reference" "PR21"
			(at 0 0 0)
			(layer "F.SilkS")
			(hide yes)
			(effects
				(font
					(size 1.27 1.27)
				)
			)
		)
		(property "Value" ""
			(at 0 0 0)
			(layer "F.Fab")
			(effects
				(font
					(size 1.27 1.27)
				)
			)
		)
		(duplicate_pad_numbers_are_jumpers no)
		(fp_line
			(start -0.7874 -0.4064)
			(end 0.7874 -0.4064)
			(stroke
				(width 0.1524)
				(type default)
			)
			(layer "F.SilkS")
		)
		(fp_line
			(start -0.7874 0.4064)
			(end -0.7874 -0.4064)
			(stroke
				(width 0.1524)
				(type default)
			)
			(layer "F.SilkS")
		)
		(fp_line
			(start 0.7874 -0.4064)
			(end 0.7874 0.4064)
			(stroke
				(width 0.1524)
				(type default)
			)
			(layer "F.SilkS")
		)
		(fp_line
			(start 0.7874 0.4064)
			(end -0.7874 0.4064)
			(stroke
				(width 0.1524)
				(type default)
			)
			(layer "F.SilkS")
		)
		(fp_line
			(start -0.67945 -0.305054)
			(end -0.12065 -0.305054)
			(stroke
				(width 0.1)
				(type default)
			)
			(layer "F.Fab")
		)
		(fp_line
			(start -0.67945 0.3048)
			(end -0.67945 -0.305054)
			(stroke
				(width 0.1)
				(type default)
			)
			(layer "F.Fab")
		)
		(fp_line
			(start -0.12065 -0.305054)
			(end -0.12065 -0.2794)
			(stroke
				(width 0.1)
				(type default)
			)
			(layer "F.Fab")
		)
		(fp_line
			(start -0.12065 -0.2794)
			(end 0.12065 -0.2794)
			(stroke
				(width 0.1)
				(type default)
			)
			(layer "F.Fab")
		)
		(fp_line
			(start -0.12065 0.2794)
			(end -0.12065 0.3048)
			(stroke
				(width 0.1)
				(type default)
			)
			(layer "F.Fab")
		)
		(fp_line
			(start -0.12065 0.3048)
			(end -0.67945 0.3048)
			(stroke
				(width 0.1)
				(type default)
			)
			(layer "F.Fab")
		)
		(fp_line
			(start 0.120396 0.2794)
			(end -0.12065 0.2794)
			(stroke
				(width 0.1)
				(type default)
			)
			(layer "F.Fab")
		)
		(fp_line
			(start 0.120396 0.3048)
			(end 0.120396 0.2794)
			(stroke
				(width 0.1)
				(type default)
			)
			(layer "F.Fab")
		)
		(fp_line
			(start 0.12065 -0.3048)
			(end 0.67945 -0.3048)
			(stroke
				(width 0.1)
				(type default)
			)
			(layer "F.Fab")
		)
		(fp_line
			(start 0.12065 -0.2794)
			(end 0.12065 -0.3048)
			(stroke
				(width 0.1)
				(type default)
			)
			(layer "F.Fab")
		)
		(fp_line
			(start 0.67945 -0.3048)
			(end 0.67945 0.3048)
			(stroke
				(width 0.1)
				(type default)
			)
			(layer "F.Fab")
		)
		(fp_line
			(start 0.67945 0.3048)
			(end 0.120396 0.3048)
			(stroke
				(width 0.1)
				(type default)
			)
			(layer "F.Fab")
		)
		(pad "1" smd circle
			(at -0.40005 0)
			(size 0 0)
			(layers "F.Cu" "F.Mask" "F.Paste")
			(net "FAN_3_FAULT_R")
		)
		(pad "2" smd circle
			(at 0.40005 0)
			(size 0 0)
			(layers "F.Cu" "F.Mask" "F.Paste")
			(net "FAN_3_P3V_R")
		)
	)
	(footprint ""
		(layer "F.Cu")
		(at 14.234922 -101.950012 180)
		(property "Reference" "R5198"
			(at 0 0 180)
			(layer "F.SilkS")
			(hide yes)
			(effects
				(font
					(size 1.27 1.27)
				)
			)
		)
		(property "Value" ""
			(at 0 0 180)
			(layer "F.Fab")
			(effects
				(font
					(size 1.27 1.27)
				)
			)
		)
		(duplicate_pad_numbers_are_jumpers no)
		(fp_line
			(start 0.7874 0.4064)
			(end -0.7874 0.4064)
			(stroke
				(width 0.1524)
				(type default)
			)
			(layer "F.SilkS")
		)
		(fp_line
			(start 0.7874 -0.4064)
			(end 0.7874 0.4064)
			(stroke
				(width 0.1524)
				(type default)
			)
			(layer "F.SilkS")
		)
		(fp_line
			(start -0.7874 0.4064)
			(end -0.7874 -0.4064)
			(stroke
				(width 0.1524)
				(type default)
			)
			(layer "F.SilkS")
		)
		(fp_line
			(start -0.7874 -0.4064)
			(end 0.7874 -0.4064)
			(stroke
				(width 0.1524)
				(type default)
			)
			(layer "F.SilkS")
		)
		(fp_line
			(start 0.67945 0.3048)
			(end 0.120396 0.3048)
			(stroke
				(width 0.1)
				(type default)
			)
			(layer "F.Fab")
		)
		(fp_line
			(start 0.67945 -0.3048)
			(end 0.67945 0.3048)
			(stroke
				(width 0.1)
				(type default)
			)
			(layer "F.Fab")
		)
		(fp_line
			(start 0.12065 -0.2794)
			(end 0.12065 -0.3048)
			(stroke
				(width 0.1)
				(type default)
			)
			(layer "F.Fab")
		)
		(fp_line
			(start 0.12065 -0.3048)
			(end 0.67945 -0.3048)
			(stroke
				(width 0.1)
				(type default)
			)
			(layer "F.Fab")
		)
		(fp_line
			(start 0.120396 0.3048)
			(end 0.120396 0.2794)
			(stroke
				(width 0.1)
				(type default)
			)
			(layer "F.Fab")
		)
		(fp_line
			(start 0.120396 0.2794)
			(end -0.12065 0.2794)
			(stroke
				(width 0.1)
				(type default)
			)
			(layer "F.Fab")
		)
		(fp_line
			(start -0.12065 0.3048)
			(end -0.67945 0.3048)
			(stroke
				(width 0.1)
				(type default)
			)
			(layer "F.Fab")
		)
		(fp_line
			(start -0.12065 0.2794)
			(end -0.12065 0.3048)
			(stroke
				(width 0.1)
				(type default)
			)
			(layer "F.Fab")
		)
		(fp_line
			(start -0.12065 -0.2794)
			(end 0.12065 -0.2794)
			(stroke
				(width 0.1)
				(type default)
			)
			(layer "F.Fab")
		)
		(fp_line
			(start -0.12065 -0.305054)
			(end -0.12065 -0.2794)
			(stroke
				(width 0.1)
				(type default)
			)
			(layer "F.Fab")
		)
		(fp_line
			(start -0.67945 0.3048)
			(end -0.67945 -0.305054)
			(stroke
				(width 0.1)
				(type default)
			)
			(layer "F.Fab")
		)
		(fp_line
			(start -0.67945 -0.305054)
			(end -0.12065 -0.305054)
			(stroke
				(width 0.1)
				(type default)
			)
			(layer "F.Fab")
		)
		(pad "1" smd circle
			(at -0.40005 0 180)
			(size 0 0)
			(layers "F.Cu" "F.Mask" "F.Paste")
			(net "FAN_5_PWM_OL")
		)
		(pad "2" smd circle
			(at 0.40005 0 180)
			(size 0 0)
			(layers "F.Cu" "F.Mask" "F.Paste")
			(net "FAN_5_PWM_OL_R")
		)
	)
	(footprint ""
		(layer "F.Cu")
		(at 33.02 -209.451956 180)
		(property "Reference" "R5306"
			(at 0 0 180)
			(layer "F.SilkS")
			(hide yes)
			(effects
				(font
					(size 1.27 1.27)
				)
			)
		)
		(property "Value" ""
			(at 0 0 180)
			(layer "F.Fab")
			(effects
				(font
					(size 1.27 1.27)
				)
			)
		)
		(duplicate_pad_numbers_are_jumpers no)
		(fp_line
			(start 0.7874 0.4064)
			(end -0.7874 0.4064)
			(stroke
				(width 0.1524)
				(type default)
			)
			(layer "F.SilkS")
		)
		(fp_line
			(start 0.7874 -0.4064)
			(end 0.7874 0.4064)
			(stroke
				(width 0.1524)
				(type default)
			)
			(layer "F.SilkS")
		)
		(fp_line
			(start -0.7874 0.4064)
			(end -0.7874 -0.4064)
			(stroke
				(width 0.1524)
				(type default)
			)
			(layer "F.SilkS")
		)
		(fp_line
			(start -0.7874 -0.4064)
			(end 0.7874 -0.4064)
			(stroke
				(width 0.1524)
				(type default)
			)
			(layer "F.SilkS")
		)
		(fp_line
			(start 0.67945 0.3048)
			(end 0.120396 0.3048)
			(stroke
				(width 0.1)
				(type default)
			)
			(layer "F.Fab")
		)
		(fp_line
			(start 0.67945 -0.3048)
			(end 0.67945 0.3048)
			(stroke
				(width 0.1)
				(type default)
			)
			(layer "F.Fab")
		)
		(fp_line
			(start 0.12065 -0.2794)
			(end 0.12065 -0.3048)
			(stroke
				(width 0.1)
				(type default)
			)
			(layer "F.Fab")
		)
		(fp_line
			(start 0.12065 -0.3048)
			(end 0.67945 -0.3048)
			(stroke
				(width 0.1)
				(type default)
			)
			(layer "F.Fab")
		)
		(fp_line
			(start 0.120396 0.3048)
			(end 0.120396 0.2794)
			(stroke
				(width 0.1)
				(type default)
			)
			(layer "F.Fab")
		)
		(fp_line
			(start 0.120396 0.2794)
			(end -0.12065 0.2794)
			(stroke
				(width 0.1)
				(type default)
			)
			(layer "F.Fab")
		)
		(fp_line
			(start -0.12065 0.3048)
			(end -0.67945 0.3048)
			(stroke
				(width 0.1)
				(type default)
			)
			(layer "F.Fab")
		)
		(fp_line
			(start -0.12065 0.2794)
			(end -0.12065 0.3048)
			(stroke
				(width 0.1)
				(type default)
			)
			(layer "F.Fab")
		)
		(fp_line
			(start -0.12065 -0.2794)
			(end 0.12065 -0.2794)
			(stroke
				(width 0.1)
				(type default)
			)
			(layer "F.Fab")
		)
		(fp_line
			(start -0.12065 -0.305054)
			(end -0.12065 -0.2794)
			(stroke
				(width 0.1)
				(type default)
			)
			(layer "F.Fab")
		)
		(fp_line
			(start -0.67945 0.3048)
			(end -0.67945 -0.305054)
			(stroke
				(width 0.1)
				(type default)
			)
			(layer "F.Fab")
		)
		(fp_line
			(start -0.67945 -0.305054)
			(end -0.12065 -0.305054)
			(stroke
				(width 0.1)
				(type default)
			)
			(layer "F.Fab")
		)
		(pad "1" smd rect
			(at -0.40005 0)
			(size 0.4572 0.508)
			(layers "F.Cu" "F.Mask" "F.Paste")
			(net "FAN_1_TACH_IL_R")
		)
		(pad "2" smd rect
			(at 0.40005 0)
			(size 0.4572 0.508)
			(layers "F.Cu" "F.Mask" "F.Paste")
			(net "FAN_1_TACH_IL")
		)
	)
	(footprint ""
		(layer "F.Cu")
		(at 37.338 -112.452912 180)
		(property "Reference" "R5224"
			(at 0 0 180)
			(layer "F.SilkS")
			(hide yes)
			(effects
				(font
					(size 1.27 1.27)
				)
			)
		)
		(property "Value" ""
			(at 0 0 180)
			(layer "F.Fab")
			(effects
				(font
					(size 1.27 1.27)
				)
			)
		)
		(duplicate_pad_numbers_are_jumpers no)
		(fp_line
			(start 0.7874 0.4064)
			(end -0.7874 0.4064)
			(stroke
				(width 0.1524)
				(type default)
			)
			(layer "F.SilkS")
		)
		(fp_line
			(start 0.7874 -0.4064)
			(end 0.7874 0.4064)
			(stroke
				(width 0.1524)
				(type default)
			)
			(layer "F.SilkS")
		)
		(fp_line
			(start -0.7874 0.4064)
			(end -0.7874 -0.4064)
			(stroke
				(width 0.1524)
				(type default)
			)
			(layer "F.SilkS")
		)
		(fp_line
			(start -0.7874 -0.4064)
			(end 0.7874 -0.4064)
			(stroke
				(width 0.1524)
				(type default)
			)
			(layer "F.SilkS")
		)
		(fp_line
			(start 0.67945 0.3048)
			(end 0.120396 0.3048)
			(stroke
				(width 0.1)
				(type default)
			)
			(layer "F.Fab")
		)
		(fp_line
			(start 0.67945 -0.3048)
			(end 0.67945 0.3048)
			(stroke
				(width 0.1)
				(type default)
			)
			(layer "F.Fab")
		)
		(fp_line
			(start 0.12065 -0.2794)
			(end 0.12065 -0.3048)
			(stroke
				(width 0.1)
				(type default)
			)
			(layer "F.Fab")
		)
		(fp_line
			(start 0.12065 -0.3048)
			(end 0.67945 -0.3048)
			(stroke
				(width 0.1)
				(type default)
			)
			(layer "F.Fab")
		)
		(fp_line
			(start 0.120396 0.3048)
			(end 0.120396 0.2794)
			(stroke
				(width 0.1)
				(type default)
			)
			(layer "F.Fab")
		)
		(fp_line
			(start 0.120396 0.2794)
			(end -0.12065 0.2794)
			(stroke
				(width 0.1)
				(type default)
			)
			(layer "F.Fab")
		)
		(fp_line
			(start -0.12065 0.3048)
			(end -0.67945 0.3048)
			(stroke
				(width 0.1)
				(type default)
			)
			(layer "F.Fab")
		)
		(fp_line
			(start -0.12065 0.2794)
			(end -0.12065 0.3048)
			(stroke
				(width 0.1)
				(type default)
			)
			(layer "F.Fab")
		)
		(fp_line
			(start -0.12065 -0.2794)
			(end 0.12065 -0.2794)
			(stroke
				(width 0.1)
				(type default)
			)
			(layer "F.Fab")
		)
		(fp_line
			(start -0.12065 -0.305054)
			(end -0.12065 -0.2794)
			(stroke
				(width 0.1)
				(type default)
			)
			(layer "F.Fab")
		)
		(fp_line
			(start -0.67945 0.3048)
			(end -0.67945 -0.305054)
			(stroke
				(width 0.1)
				(type default)
			)
			(layer "F.Fab")
		)
		(fp_line
			(start -0.67945 -0.305054)
			(end -0.12065 -0.305054)
			(stroke
				(width 0.1)
				(type default)
			)
			(layer "F.Fab")
		)
		(pad "1" smd circle
			(at -0.40005 0 180)
			(size 0 0)
			(layers "F.Cu" "F.Mask" "F.Paste")
			(net "SMB_FAN2_SDA_R")
		)
		(pad "2" smd circle
			(at 0.40005 0 180)
			(size 0 0)
			(layers "F.Cu" "F.Mask" "F.Paste")
			(net "SMB_FAN2_SDA")
		)
	)
	(footprint ""
		(layer "F.Cu")
		(at 43.561 -135.509 -90)
		(property "Reference" "R5561"
			(at 0 0 270)
			(layer "F.SilkS")
			(hide yes)
			(effects
				(font
					(size 1.27 1.27)
				)
			)
		)
		(property "Value" ""
			(at 0 0 270)
			(layer "F.Fab")
			(effects
				(font
					(size 1.27 1.27)
				)
			)
		)
		(duplicate_pad_numbers_are_jumpers no)
		(fp_line
			(start -0.7874 0.4064)
			(end -0.7874 -0.4064)
			(stroke
				(width 0.1524)
				(type default)
			)
			(layer "F.SilkS")
		)
		(fp_line
			(start 0.7874 0.4064)
			(end -0.7874 0.4064)
			(stroke
				(width 0.1524)
				(type default)
			)
			(layer "F.SilkS")
		)
		(fp_line
			(start -0.7874 -0.4064)
			(end 0.7874 -0.4064)
			(stroke
				(width 0.1524)
				(type default)
			)
			(layer "F.SilkS")
		)
		(fp_line
			(start 0.7874 -0.4064)
			(end 0.7874 0.4064)
			(stroke
				(width 0.1524)
				(type default)
			)
			(layer "F.SilkS")
		)
		(fp_line
			(start -0.67945 0.3048)
			(end -0.67945 -0.305054)
			(stroke
				(width 0.1)
				(type default)
			)
			(layer "F.Fab")
		)
		(fp_line
			(start -0.12065 0.3048)
			(end -0.67945 0.3048)
			(stroke
				(width 0.1)
				(type default)
			)
			(layer "F.Fab")
		)
		(fp_line
			(start 0.120396 0.3048)
			(end 0.120396 0.2794)
			(stroke
				(width 0.1)
				(type default)
			)
			(layer "F.Fab")
		)
		(fp_line
			(start 0.67945 0.3048)
			(end 0.120396 0.3048)
			(stroke
				(width 0.1)
				(type default)
			)
			(layer "F.Fab")
		)
		(fp_line
			(start -0.12065 0.2794)
			(end -0.12065 0.3048)
			(stroke
				(width 0.1)
				(type default)
			)
			(layer "F.Fab")
		)
		(fp_line
			(start 0.120396 0.2794)
			(end -0.12065 0.2794)
			(stroke
				(width 0.1)
				(type default)
			)
			(layer "F.Fab")
		)
		(fp_line
			(start -0.12065 -0.2794)
			(end 0.12065 -0.2794)
			(stroke
				(width 0.1)
				(type default)
			)
			(layer "F.Fab")
		)
		(fp_line
			(start 0.12065 -0.2794)
			(end 0.12065 -0.3048)
			(stroke
				(width 0.1)
				(type default)
			)
			(layer "F.Fab")
		)
		(fp_line
			(start 0.12065 -0.3048)
			(end 0.67945 -0.3048)
			(stroke
				(width 0.1)
				(type default)
			)
			(layer "F.Fab")
		)
		(fp_line
			(start 0.67945 -0.3048)
			(end 0.67945 0.3048)
			(stroke
				(width 0.1)
				(type default)
			)
			(layer "F.Fab")
		)
		(fp_line
			(start -0.67945 -0.305054)
			(end -0.12065 -0.305054)
			(stroke
				(width 0.1)
				(type default)
			)
			(layer "F.Fab")
		)
		(fp_line
			(start -0.12065 -0.305054)
			(end -0.12065 -0.2794)
			(stroke
				(width 0.1)
				(type default)
			)
			(layer "F.Fab")
		)
		(pad "1" smd circle
			(at -0.40005 0 270)
			(size 0 0)
			(layers "F.Cu" "F.Mask" "F.Paste")
			(net "P3V3_AUX")
		)
		(pad "2" smd circle
			(at 0.40005 0 270)
			(size 0 0)
			(layers "F.Cu" "F.Mask" "F.Paste")
			(net "U403_ADD1")
		)
	)
	(footprint ""
		(layer "F.Cu")
		(at 18.415 -17.526 90)
		(property "Reference" "R5310"
			(at 0 0 90)
			(layer "F.SilkS")
			(hide yes)
			(effects
				(font
					(size 1.27 1.27)
				)
			)
		)
		(property "Value" ""
			(at 0 0 90)
			(layer "F.Fab")
			(effects
				(font
					(size 1.27 1.27)
				)
			)
		)
		(duplicate_pad_numbers_are_jumpers no)
		(fp_line
			(start 0.7874 -0.4064)
			(end 0.7874 0.4064)
			(stroke
				(width 0.1524)
				(type default)
			)
			(layer "F.SilkS")
		)
		(fp_line
			(start -0.7874 -0.4064)
			(end 0.7874 -0.4064)
			(stroke
				(width 0.1524)
				(type default)
			)
			(layer "F.SilkS")
		)
		(fp_line
			(start 0.7874 0.4064)
			(end -0.7874 0.4064)
			(stroke
				(width 0.1524)
				(type default)
			)
			(layer "F.SilkS")
		)
		(fp_line
			(start -0.7874 0.4064)
			(end -0.7874 -0.4064)
			(stroke
				(width 0.1524)
				(type default)
			)
			(layer "F.SilkS")
		)
		(fp_line
			(start -0.12065 -0.305054)
			(end -0.12065 -0.2794)
			(stroke
				(width 0.1)
				(type default)
			)
			(layer "F.Fab")
		)
		(fp_line
			(start -0.67945 -0.305054)
			(end -0.12065 -0.305054)
			(stroke
				(width 0.1)
				(type default)
			)
			(layer "F.Fab")
		)
		(fp_line
			(start 0.67945 -0.3048)
			(end 0.67945 0.3048)
			(stroke
				(width 0.1)
				(type default)
			)
			(layer "F.Fab")
		)
		(fp_line
			(start 0.12065 -0.3048)
			(end 0.67945 -0.3048)
			(stroke
				(width 0.1)
				(type default)
			)
			(layer "F.Fab")
		)
		(fp_line
			(start 0.12065 -0.2794)
			(end 0.12065 -0.3048)
			(stroke
				(width 0.1)
				(type default)
			)
			(layer "F.Fab")
		)
		(fp_line
			(start -0.12065 -0.2794)
			(end 0.12065 -0.2794)
			(stroke
				(width 0.1)
				(type default)
			)
			(layer "F.Fab")
		)
		(fp_line
			(start 0.120396 0.2794)
			(end -0.12065 0.2794)
			(stroke
				(width 0.1)
				(type default)
			)
			(layer "F.Fab")
		)
		(fp_line
			(start -0.12065 0.2794)
			(end -0.12065 0.3048)
			(stroke
				(width 0.1)
				(type default)
			)
			(layer "F.Fab")
		)
		(fp_line
			(start 0.67945 0.3048)
			(end 0.120396 0.3048)
			(stroke
				(width 0.1)
				(type default)
			)
			(layer "F.Fab")
		)
		(fp_line
			(start 0.120396 0.3048)
			(end 0.120396 0.2794)
			(stroke
				(width 0.1)
				(type default)
			)
			(layer "F.Fab")
		)
		(fp_line
			(start -0.12065 0.3048)
			(end -0.67945 0.3048)
			(stroke
				(width 0.1)
				(type default)
			)
			(layer "F.Fab")
		)
		(fp_line
			(start -0.67945 0.3048)
			(end -0.67945 -0.305054)
			(stroke
				(width 0.1)
				(type default)
			)
			(layer "F.Fab")
		)
		(pad "1" smd rect
			(at -0.40005 0 270)
			(size 0.4572 0.508)
			(layers "F.Cu" "F.Mask" "F.Paste")
			(net "FAN_4_TACH_IL_R")
		)
		(pad "2" smd rect
			(at 0.40005 0 270)
			(size 0.4572 0.508)
			(layers "F.Cu" "F.Mask" "F.Paste")
			(net "FAN_4_TACH_IL")
		)
	)
	(footprint ""
		(layer "F.Cu")
		(at 26.67 -160.02 90)
		(property "Reference" "R4880"
			(at 0 0 90)
			(layer "F.SilkS")
			(hide yes)
			(effects
				(font
					(size 1.27 1.27)
				)
			)
		)
		(property "Value" ""
			(at 0 0 90)
			(layer "F.Fab")
			(effects
				(font
					(size 1.27 1.27)
				)
			)
		)
		(duplicate_pad_numbers_are_jumpers no)
		(fp_line
			(start 0.7874 -0.4064)
			(end 0.7874 0.4064)
			(stroke
				(width 0.1524)
				(type default)
			)
			(layer "F.SilkS")
		)
		(fp_line
			(start -0.7874 -0.4064)
			(end 0.7874 -0.4064)
			(stroke
				(width 0.1524)
				(type default)
			)
			(layer "F.SilkS")
		)
		(fp_line
			(start 0.7874 0.4064)
			(end -0.7874 0.4064)
			(stroke
				(width 0.1524)
				(type default)
			)
			(layer "F.SilkS")
		)
		(fp_line
			(start -0.7874 0.4064)
			(end -0.7874 -0.4064)
			(stroke
				(width 0.1524)
				(type default)
			)
			(layer "F.SilkS")
		)
		(fp_line
			(start -0.12065 -0.305054)
			(end -0.12065 -0.2794)
			(stroke
				(width 0.1)
				(type default)
			)
			(layer "F.Fab")
		)
		(fp_line
			(start -0.67945 -0.305054)
			(end -0.12065 -0.305054)
			(stroke
				(width 0.1)
				(type default)
			)
			(layer "F.Fab")
		)
		(fp_line
			(start 0.67945 -0.3048)
			(end 0.67945 0.3048)
			(stroke
				(width 0.1)
				(type default)
			)
			(layer "F.Fab")
		)
		(fp_line
			(start 0.12065 -0.3048)
			(end 0.67945 -0.3048)
			(stroke
				(width 0.1)
				(type default)
			)
			(layer "F.Fab")
		)
		(fp_line
			(start 0.12065 -0.2794)
			(end 0.12065 -0.3048)
			(stroke
				(width 0.1)
				(type default)
			)
			(layer "F.Fab")
		)
		(fp_line
			(start -0.12065 -0.2794)
			(end 0.12065 -0.2794)
			(stroke
				(width 0.1)
				(type default)
			)
			(layer "F.Fab")
		)
		(fp_line
			(start 0.120396 0.2794)
			(end -0.12065 0.2794)
			(stroke
				(width 0.1)
				(type default)
			)
			(layer "F.Fab")
		)
		(fp_line
			(start -0.12065 0.2794)
			(end -0.12065 0.3048)
			(stroke
				(width 0.1)
				(type default)
			)
			(layer "F.Fab")
		)
		(fp_line
			(start 0.67945 0.3048)
			(end 0.120396 0.3048)
			(stroke
				(width 0.1)
				(type default)
			)
			(layer "F.Fab")
		)
		(fp_line
			(start 0.120396 0.3048)
			(end 0.120396 0.2794)
			(stroke
				(width 0.1)
				(type default)
			)
			(layer "F.Fab")
		)
		(fp_line
			(start -0.12065 0.3048)
			(end -0.67945 0.3048)
			(stroke
				(width 0.1)
				(type default)
			)
			(layer "F.Fab")
		)
		(fp_line
			(start -0.67945 0.3048)
			(end -0.67945 -0.305054)
			(stroke
				(width 0.1)
				(type default)
			)
			(layer "F.Fab")
		)
		(pad "1" smd circle
			(at -0.40005 0 90)
			(size 0 0)
			(layers "F.Cu" "F.Mask" "F.Paste")
			(net "SMB_FAN6_R_SDA")
		)
		(pad "2" smd circle
			(at 0.40005 0 90)
			(size 0 0)
			(layers "F.Cu" "F.Mask" "F.Paste")
			(net "SMB_FAN6_SDA")
		)
	)
	(footprint ""
		(layer "F.Cu")
		(at 15.377922 -103.855012 180)
		(property "Reference" "D134"
			(at 5.344922 -0.376682 0)
			(unlocked yes)
			(layer "F.SilkS")
			(effects
				(font
					(size 0.7874 0.5842)
					(thickness 0.1524)
				)
				(justify left)
			)
		)
		(property "Value" ""
			(at 0 0 180)
			(layer "F.Fab")
			(effects
				(font
					(size 1.27 1.27)
				)
			)
		)
		(duplicate_pad_numbers_are_jumpers no)
		(fp_line
			(start 2.032 0.7112)
			(end -1.651 0.7112)
			(stroke
				(width 0.1524)
				(type default)
			)
			(layer "F.SilkS")
		)
		(fp_line
			(start 2.032 -0.7112)
			(end 2.032 0.7112)
			(stroke
				(width 0.1524)
				(type default)
			)
			(layer "F.SilkS")
		)
		(fp_line
			(start 1.905 -0.6858)
			(end 1.905 0.6858)
			(stroke
				(width 0.1524)
				(type default)
			)
			(layer "F.SilkS")
		)
		(fp_line
			(start 1.778 0.6858)
			(end 1.778 -0.6858)
			(stroke
				(width 0.1524)
				(type default)
			)
			(layer "F.SilkS")
		)
		(fp_line
			(start 1.651 -0.6858)
			(end 1.651 0.6858)
			(stroke
				(width 0.1524)
				(type default)
			)
			(layer "F.SilkS")
		)
		(fp_line
			(start 0.299974 -0.500126)
			(end 0.299974 0.500126)
			(stroke
				(width 0.1524)
				(type default)
			)
			(layer "F.SilkS")
		)
		(fp_line
			(start 0.199898 0)
			(end -0.299974 -0.500126)
			(stroke
				(width 0.1524)
				(type default)
			)
			(layer "F.SilkS")
		)
		(fp_line
			(start -0.299974 0.500126)
			(end 0.199898 0)
			(stroke
				(width 0.1524)
				(type default)
			)
			(layer "F.SilkS")
		)
		(fp_line
			(start -0.299974 -0.500126)
			(end -0.299974 0.500126)
			(stroke
				(width 0.1524)
				(type default)
			)
			(layer "F.SilkS")
		)
		(fp_line
			(start -1.651 0.7112)
			(end -1.651 -0.7112)
			(stroke
				(width 0.1524)
				(type default)
			)
			(layer "F.SilkS")
		)
		(fp_line
			(start -1.651 -0.7112)
			(end 2.032 -0.7112)
			(stroke
				(width 0.1524)
				(type default)
			)
			(layer "F.SilkS")
		)
		(fp_line
			(start 1.35001 0.175006)
			(end 0.899922 0.175006)
			(stroke
				(width 0.1)
				(type default)
			)
			(layer "F.Fab")
		)
		(fp_line
			(start 1.35001 -0.225044)
			(end 1.35001 0.175006)
			(stroke
				(width 0.1)
				(type default)
			)
			(layer "F.Fab")
		)
		(fp_line
			(start 0.899922 0.700024)
			(end -0.899922 0.700024)
			(stroke
				(width 0.1)
				(type default)
			)
			(layer "F.Fab")
		)
		(fp_line
			(start 0.899922 0.175006)
			(end 0.899922 0.700024)
			(stroke
				(width 0.1)
				(type default)
			)
			(layer "F.Fab")
		)
		(fp_line
			(start 0.899922 -0.225044)
			(end 1.35001 -0.225044)
			(stroke
				(width 0.1)
				(type default)
			)
			(layer "F.Fab")
		)
		(fp_line
			(start 0.899922 -0.700024)
			(end 0.899922 -0.225044)
			(stroke
				(width 0.1)
				(type default)
			)
			(layer "F.Fab")
		)
		(fp_line
			(start 0.299974 -0.500126)
			(end 0.299974 0.500126)
			(stroke
				(width 0.1)
				(type default)
			)
			(layer "F.Fab")
		)
		(fp_line
			(start 0.199898 0)
			(end -0.299974 -0.500126)
			(stroke
				(width 0.1)
				(type default)
			)
			(layer "F.Fab")
		)
		(fp_line
			(start -0.299974 0.500126)
			(end 0.199898 0)
			(stroke
				(width 0.1)
				(type default)
			)
			(layer "F.Fab")
		)
		(fp_line
			(start -0.299974 -0.500126)
			(end -0.299974 0.500126)
			(stroke
				(width 0.1)
				(type default)
			)
			(layer "F.Fab")
		)
		(fp_line
			(start -0.899922 0.700024)
			(end -0.899922 0.175006)
			(stroke
				(width 0.1)
				(type default)
			)
			(layer "F.Fab")
		)
		(fp_line
			(start -0.899922 0.175006)
			(end -1.35001 0.175006)
			(stroke
				(width 0.1)
				(type default)
			)
			(layer "F.Fab")
		)
		(fp_line
			(start -0.899922 -0.225044)
			(end -0.899922 -0.700024)
			(stroke
				(width 0.1)
				(type default)
			)
			(layer "F.Fab")
		)
		(fp_line
			(start -0.899922 -0.700024)
			(end 0.899922 -0.700024)
			(stroke
				(width 0.1)
				(type default)
			)
			(layer "F.Fab")
		)
		(fp_line
			(start -1.35001 0.175006)
			(end -1.35001 -0.225044)
			(stroke
				(width 0.1)
				(type default)
			)
			(layer "F.Fab")
		)
		(fp_line
			(start -1.35001 -0.225044)
			(end -0.899922 -0.225044)
			(stroke
				(width 0.1)
				(type default)
			)
			(layer "F.Fab")
		)
		(fp_text user "-"
			(at 1.153922 -1.207262 180)
			(unlocked yes)
			(layer "F.SilkS")
			(effects
				(font
					(size 1.905 1.4224)
					(thickness 0.1524)
				)
				(justify left)
			)
		)
		(fp_text user "+"
			(at -2.656078 -1.207262 180)
			(unlocked yes)
			(layer "F.SilkS")
			(effects
				(font
					(size 1.905 1.4224)
					(thickness 0.1524)
				)
				(justify left)
			)
		)
		(fp_text user "-"
			(at 1.8288 -0.24765 180)
			(unlocked yes)
			(layer "F.Fab")
			(effects
				(font
					(size 1.905 1.4224)
					(thickness 0.1524)
				)
				(justify left)
			)
		)
		(fp_text user "+"
			(at -2.794 -0.19685 180)
			(unlocked yes)
			(layer "F.Fab")
			(effects
				(font
					(size 1.905 1.4224)
					(thickness 0.1524)
				)
				(justify left)
			)
		)
		(pad "1" smd rect
			(at -1.0922 0)
			(size 0.8128 0.8636)
			(layers "F.Cu" "F.Mask" "F.Paste")
			(net "FAN_5_TACH_IL_R")
		)
		(pad "2" smd rect
			(at 1.0922 0 180)
			(size 0.8128 0.8636)
			(layers "F.Cu" "F.Mask" "F.Paste")
			(net "FAN_5_TACH_IL_D")
		)
	)
	(footprint ""
		(layer "F.Cu")
		(at 14.0589 -125.857 180)
		(property "Reference" "R5588"
			(at 0 0 180)
			(layer "F.SilkS")
			(hide yes)
			(effects
				(font
					(size 1.27 1.27)
				)
			)
		)
		(property "Value" ""
			(at 0 0 180)
			(layer "F.Fab")
			(effects
				(font
					(size 1.27 1.27)
				)
			)
		)
		(duplicate_pad_numbers_are_jumpers no)
		(fp_line
			(start 0.7874 0.4064)
			(end -0.7874 0.4064)
			(stroke
				(width 0.1524)
				(type default)
			)
			(layer "F.SilkS")
		)
		(fp_line
			(start 0.7874 -0.4064)
			(end 0.7874 0.4064)
			(stroke
				(width 0.1524)
				(type default)
			)
			(layer "F.SilkS")
		)
		(fp_line
			(start -0.7874 0.4064)
			(end -0.7874 -0.4064)
			(stroke
				(width 0.1524)
				(type default)
			)
			(layer "F.SilkS")
		)
		(fp_line
			(start -0.7874 -0.4064)
			(end 0.7874 -0.4064)
			(stroke
				(width 0.1524)
				(type default)
			)
			(layer "F.SilkS")
		)
		(fp_line
			(start 0.67945 0.3048)
			(end 0.120396 0.3048)
			(stroke
				(width 0.1)
				(type default)
			)
			(layer "F.Fab")
		)
		(fp_line
			(start 0.67945 -0.3048)
			(end 0.67945 0.3048)
			(stroke
				(width 0.1)
				(type default)
			)
			(layer "F.Fab")
		)
		(fp_line
			(start 0.12065 -0.2794)
			(end 0.12065 -0.3048)
			(stroke
				(width 0.1)
				(type default)
			)
			(layer "F.Fab")
		)
		(fp_line
			(start 0.12065 -0.3048)
			(end 0.67945 -0.3048)
			(stroke
				(width 0.1)
				(type default)
			)
			(layer "F.Fab")
		)
		(fp_line
			(start 0.120396 0.3048)
			(end 0.120396 0.2794)
			(stroke
				(width 0.1)
				(type default)
			)
			(layer "F.Fab")
		)
		(fp_line
			(start 0.120396 0.2794)
			(end -0.12065 0.2794)
			(stroke
				(width 0.1)
				(type default)
			)
			(layer "F.Fab")
		)
		(fp_line
			(start -0.12065 0.3048)
			(end -0.67945 0.3048)
			(stroke
				(width 0.1)
				(type default)
			)
			(layer "F.Fab")
		)
		(fp_line
			(start -0.12065 0.2794)
			(end -0.12065 0.3048)
			(stroke
				(width 0.1)
				(type default)
			)
			(layer "F.Fab")
		)
		(fp_line
			(start -0.12065 -0.2794)
			(end 0.12065 -0.2794)
			(stroke
				(width 0.1)
				(type default)
			)
			(layer "F.Fab")
		)
		(fp_line
			(start -0.12065 -0.305054)
			(end -0.12065 -0.2794)
			(stroke
				(width 0.1)
				(type default)
			)
			(layer "F.Fab")
		)
		(fp_line
			(start -0.67945 0.3048)
			(end -0.67945 -0.305054)
			(stroke
				(width 0.1)
				(type default)
			)
			(layer "F.Fab")
		)
		(fp_line
			(start -0.67945 -0.305054)
			(end -0.12065 -0.305054)
			(stroke
				(width 0.1)
				(type default)
			)
			(layer "F.Fab")
		)
		(pad "1" smd rect
			(at -0.40005 0)
			(size 0.4572 0.508)
			(layers "F.Cu" "F.Mask" "F.Paste")
			(net "FAN_4_TACH_OL")
		)
		(pad "2" smd rect
			(at 0.40005 0)
			(size 0.4572 0.508)
			(layers "F.Cu" "F.Mask" "F.Paste")
			(net "FAN_4_TACH_OL_R2")
		)
	)
	(footprint ""
		(layer "F.Cu")
		(at 14.351 -295.656)
		(property "Reference" "R5245"
			(at 0 0 0)
			(layer "F.SilkS")
			(hide yes)
			(effects
				(font
					(size 1.27 1.27)
				)
			)
		)
		(property "Value" ""
			(at 0 0 0)
			(layer "F.Fab")
			(effects
				(font
					(size 1.27 1.27)
				)
			)
		)
		(duplicate_pad_numbers_are_jumpers no)
		(fp_line
			(start -0.7874 -0.4064)
			(end 0.7874 -0.4064)
			(stroke
				(width 0.1524)
				(type default)
			)
			(layer "F.SilkS")
		)
		(fp_line
			(start -0.7874 0.4064)
			(end -0.7874 -0.4064)
			(stroke
				(width 0.1524)
				(type default)
			)
			(layer "F.SilkS")
		)
		(fp_line
			(start 0.7874 -0.4064)
			(end 0.7874 0.4064)
			(stroke
				(width 0.1524)
				(type default)
			)
			(layer "F.SilkS")
		)
		(fp_line
			(start 0.7874 0.4064)
			(end -0.7874 0.4064)
			(stroke
				(width 0.1524)
				(type default)
			)
			(layer "F.SilkS")
		)
		(fp_line
			(start -0.67945 -0.305054)
			(end -0.12065 -0.305054)
			(stroke
				(width 0.1)
				(type default)
			)
			(layer "F.Fab")
		)
		(fp_line
			(start -0.67945 0.3048)
			(end -0.67945 -0.305054)
			(stroke
				(width 0.1)
				(type default)
			)
			(layer "F.Fab")
		)
		(fp_line
			(start -0.12065 -0.305054)
			(end -0.12065 -0.2794)
			(stroke
				(width 0.1)
				(type default)
			)
			(layer "F.Fab")
		)
		(fp_line
			(start -0.12065 -0.2794)
			(end 0.12065 -0.2794)
			(stroke
				(width 0.1)
				(type default)
			)
			(layer "F.Fab")
		)
		(fp_line
			(start -0.12065 0.2794)
			(end -0.12065 0.3048)
			(stroke
				(width 0.1)
				(type default)
			)
			(layer "F.Fab")
		)
		(fp_line
			(start -0.12065 0.3048)
			(end -0.67945 0.3048)
			(stroke
				(width 0.1)
				(type default)
			)
			(layer "F.Fab")
		)
		(fp_line
			(start 0.120396 0.2794)
			(end -0.12065 0.2794)
			(stroke
				(width 0.1)
				(type default)
			)
			(layer "F.Fab")
		)
		(fp_line
			(start 0.120396 0.3048)
			(end 0.120396 0.2794)
			(stroke
				(width 0.1)
				(type default)
			)
			(layer "F.Fab")
		)
		(fp_line
			(start 0.12065 -0.3048)
			(end 0.67945 -0.3048)
			(stroke
				(width 0.1)
				(type default)
			)
			(layer "F.Fab")
		)
		(fp_line
			(start 0.12065 -0.2794)
			(end 0.12065 -0.3048)
			(stroke
				(width 0.1)
				(type default)
			)
			(layer "F.Fab")
		)
		(fp_line
			(start 0.67945 -0.3048)
			(end 0.67945 0.3048)
			(stroke
				(width 0.1)
				(type default)
			)
			(layer "F.Fab")
		)
		(fp_line
			(start 0.67945 0.3048)
			(end 0.120396 0.3048)
			(stroke
				(width 0.1)
				(type default)
			)
			(layer "F.Fab")
		)
		(pad "1" smd circle
			(at -0.40005 0)
			(size 0 0)
			(layers "F.Cu" "F.Mask" "F.Paste")
			(net "SMB_FAN7_SDA_R")
		)
		(pad "2" smd circle
			(at 0.40005 0)
			(size 0 0)
			(layers "F.Cu" "F.Mask" "F.Paste")
			(net "SMB_FAN7_SDA")
		)
	)
	(footprint ""
		(layer "F.Cu")
		(at 25.527 -125.349)
		(property "Reference" "R4948"
			(at 0 0 0)
			(layer "F.SilkS")
			(hide yes)
			(effects
				(font
					(size 1.27 1.27)
				)
			)
		)
		(property "Value" ""
			(at 0 0 0)
			(layer "F.Fab")
			(effects
				(font
					(size 1.27 1.27)
				)
			)
		)
		(duplicate_pad_numbers_are_jumpers no)
		(fp_line
			(start -0.7874 -0.4064)
			(end 0.7874 -0.4064)
			(stroke
				(width 0.1524)
				(type default)
			)
			(layer "F.SilkS")
		)
		(fp_line
			(start -0.7874 0.4064)
			(end -0.7874 -0.4064)
			(stroke
				(width 0.1524)
				(type default)
			)
			(layer "F.SilkS")
		)
		(fp_line
			(start 0.7874 -0.4064)
			(end 0.7874 0.4064)
			(stroke
				(width 0.1524)
				(type default)
			)
			(layer "F.SilkS")
		)
		(fp_line
			(start 0.7874 0.4064)
			(end -0.7874 0.4064)
			(stroke
				(width 0.1524)
				(type default)
			)
			(layer "F.SilkS")
		)
		(fp_line
			(start -0.67945 -0.305054)
			(end -0.12065 -0.305054)
			(stroke
				(width 0.1)
				(type default)
			)
			(layer "F.Fab")
		)
		(fp_line
			(start -0.67945 0.3048)
			(end -0.67945 -0.305054)
			(stroke
				(width 0.1)
				(type default)
			)
			(layer "F.Fab")
		)
		(fp_line
			(start -0.12065 -0.305054)
			(end -0.12065 -0.2794)
			(stroke
				(width 0.1)
				(type default)
			)
			(layer "F.Fab")
		)
		(fp_line
			(start -0.12065 -0.2794)
			(end 0.12065 -0.2794)
			(stroke
				(width 0.1)
				(type default)
			)
			(layer "F.Fab")
		)
		(fp_line
			(start -0.12065 0.2794)
			(end -0.12065 0.3048)
			(stroke
				(width 0.1)
				(type default)
			)
			(layer "F.Fab")
		)
		(fp_line
			(start -0.12065 0.3048)
			(end -0.67945 0.3048)
			(stroke
				(width 0.1)
				(type default)
			)
			(layer "F.Fab")
		)
		(fp_line
			(start 0.120396 0.2794)
			(end -0.12065 0.2794)
			(stroke
				(width 0.1)
				(type default)
			)
			(layer "F.Fab")
		)
		(fp_line
			(start 0.120396 0.3048)
			(end 0.120396 0.2794)
			(stroke
				(width 0.1)
				(type default)
			)
			(layer "F.Fab")
		)
		(fp_line
			(start 0.12065 -0.3048)
			(end 0.67945 -0.3048)
			(stroke
				(width 0.1)
				(type default)
			)
			(layer "F.Fab")
		)
		(fp_line
			(start 0.12065 -0.2794)
			(end 0.12065 -0.3048)
			(stroke
				(width 0.1)
				(type default)
			)
			(layer "F.Fab")
		)
		(fp_line
			(start 0.67945 -0.3048)
			(end 0.67945 0.3048)
			(stroke
				(width 0.1)
				(type default)
			)
			(layer "F.Fab")
		)
		(fp_line
			(start 0.67945 0.3048)
			(end 0.120396 0.3048)
			(stroke
				(width 0.1)
				(type default)
			)
			(layer "F.Fab")
		)
		(pad "1" smd circle
			(at -0.40005 0)
			(size 0 0)
			(layers "F.Cu" "F.Mask" "F.Paste")
			(net "MAX31790_U330_PWM_START0")
		)
		(pad "2" smd circle
			(at 0.40005 0)
			(size 0 0)
			(layers "F.Cu" "F.Mask" "F.Paste")
			(net "P3V3_AUX")
		)
	)
	(footprint ""
		(layer "F.Cu")
		(at 16.393922 -286.6771)
		(property "Reference" "C2056"
			(at 0 0 0)
			(layer "F.SilkS")
			(hide yes)
			(effects
				(font
					(size 1.27 1.27)
				)
			)
		)
		(property "Value" ""
			(at 0 0 0)
			(layer "F.Fab")
			(effects
				(font
					(size 1.27 1.27)
				)
			)
		)
		(duplicate_pad_numbers_are_jumpers no)
		(fp_line
			(start -0.7874 -0.4064)
			(end 0.7874 -0.4064)
			(stroke
				(width 0.1524)
				(type default)
			)
			(layer "F.SilkS")
		)
		(fp_line
			(start -0.7874 0.4064)
			(end -0.7874 -0.4064)
			(stroke
				(width 0.1524)
				(type default)
			)
			(layer "F.SilkS")
		)
		(fp_line
			(start 0.7874 -0.4064)
			(end 0.7874 0.4064)
			(stroke
				(width 0.1524)
				(type default)
			)
			(layer "F.SilkS")
		)
		(fp_line
			(start 0.7874 0.4064)
			(end -0.7874 0.4064)
			(stroke
				(width 0.1524)
				(type default)
			)
			(layer "F.SilkS")
		)
		(fp_line
			(start -0.67945 -0.305054)
			(end -0.12065 -0.305054)
			(stroke
				(width 0.1)
				(type default)
			)
			(layer "F.Fab")
		)
		(fp_line
			(start -0.67945 0.3048)
			(end -0.67945 -0.305054)
			(stroke
				(width 0.1)
				(type default)
			)
			(layer "F.Fab")
		)
		(fp_line
			(start -0.12065 -0.305054)
			(end -0.12065 -0.2794)
			(stroke
				(width 0.1)
				(type default)
			)
			(layer "F.Fab")
		)
		(fp_line
			(start -0.12065 -0.2794)
			(end 0.12065 -0.2794)
			(stroke
				(width 0.1)
				(type default)
			)
			(layer "F.Fab")
		)
		(fp_line
			(start -0.12065 0.2794)
			(end -0.12065 0.3048)
			(stroke
				(width 0.1)
				(type default)
			)
			(layer "F.Fab")
		)
		(fp_line
			(start -0.12065 0.3048)
			(end -0.67945 0.3048)
			(stroke
				(width 0.1)
				(type default)
			)
			(layer "F.Fab")
		)
		(fp_line
			(start 0.120396 0.2794)
			(end -0.12065 0.2794)
			(stroke
				(width 0.1)
				(type default)
			)
			(layer "F.Fab")
		)
		(fp_line
			(start 0.120396 0.3048)
			(end 0.120396 0.2794)
			(stroke
				(width 0.1)
				(type default)
			)
			(layer "F.Fab")
		)
		(fp_line
			(start 0.12065 -0.3048)
			(end 0.67945 -0.3048)
			(stroke
				(width 0.1)
				(type default)
			)
			(layer "F.Fab")
		)
		(fp_line
			(start 0.12065 -0.2794)
			(end 0.12065 -0.3048)
			(stroke
				(width 0.1)
				(type default)
			)
			(layer "F.Fab")
		)
		(fp_line
			(start 0.67945 -0.3048)
			(end 0.67945 0.3048)
			(stroke
				(width 0.1)
				(type default)
			)
			(layer "F.Fab")
		)
		(fp_line
			(start 0.67945 0.3048)
			(end 0.120396 0.3048)
			(stroke
				(width 0.1)
				(type default)
			)
			(layer "F.Fab")
		)
		(pad "1" smd circle
			(at -0.40005 0)
			(size 0 0)
			(layers "F.Cu" "F.Mask" "F.Paste")
			(net "FAN_7_PWM_OL_R")
		)
		(pad "2" smd circle
			(at 0.40005 0)
			(size 0 0)
			(layers "F.Cu" "F.Mask" "F.Paste")
			(net "GND")
		)
	)
	(footprint ""
		(layer "F.Cu")
		(at -6.938772 -209.296)
		(property "Reference" "J81"
			(at -3.5052 -5.552948 0)
			(unlocked yes)
			(layer "F.SilkS")
			(effects
				(font
					(size 0.7874 0.5842)
					(thickness 0.1524)
				)
				(justify left)
			)
		)
		(property "Value" ""
			(at 0 0 0)
			(layer "F.Fab")
			(effects
				(font
					(size 1.27 1.27)
				)
			)
		)
		(duplicate_pad_numbers_are_jumpers no)
		(fp_line
			(start -3.330702 -4.771136)
			(end 3.330702 -4.771136)
			(stroke
				(width 0.1524)
				(type default)
			)
			(layer "F.SilkS")
		)
		(fp_line
			(start 0 4.011168)
			(end -3.330702 -4.771136)
			(stroke
				(width 0.1524)
				(type default)
			)
			(layer "F.SilkS")
		)
		(fp_line
			(start 3.330702 -4.771136)
			(end 0 4.011168)
			(stroke
				(width 0.1524)
				(type default)
			)
			(layer "F.SilkS")
		)
		(fp_line
			(start -3.330702 -4.771136)
			(end 3.330702 -4.771136)
			(stroke
				(width 0.1)
				(type default)
			)
			(layer "F.Fab")
		)
		(fp_line
			(start 0 4.011168)
			(end -3.330702 -4.771136)
			(stroke
				(width 0.1)
				(type default)
			)
			(layer "F.Fab")
		)
		(fp_line
			(start 3.330702 -4.771136)
			(end 0 4.011168)
			(stroke
				(width 0.1)
				(type default)
			)
			(layer "F.Fab")
		)
		(pad "1" thru_hole circle
			(at 0 0)
			(size 2.159 2.159)
			(drill 1.7018)
			(layers "*.Cu" "*.Mask")
			(remove_unused_layers no)
			(net "GND2")
			(clearance 0.0254)
			(thermal_gap 0.0254)
		)
		(pad "2" thru_hole circle
			(at -1.27 -3.348736)
			(size 2.159 2.159)
			(drill 1.7018)
			(layers "*.Cu" "*.Mask")
			(remove_unused_layers no)
			(net "TDR_SE_50_OHM_TOP")
			(clearance 0.0254)
			(thermal_gap 0.0254)
		)
		(pad "3" thru_hole circle
			(at 1.27 -3.348736)
			(size 2.159 2.159)
			(drill 1.7018)
			(layers "*.Cu" "*.Mask")
			(remove_unused_layers no)
			(net "TDR_SE_50_OHM_TOP")
			(clearance 0.0254)
			(thermal_gap 0.0254)
		)
	)
	(footprint ""
		(layer "F.Cu")
		(at 13.335 -166.116 180)
		(property "Reference" "R5509"
			(at 0 0 180)
			(layer "F.SilkS")
			(hide yes)
			(effects
				(font
					(size 1.27 1.27)
				)
			)
		)
		(property "Value" ""
			(at 0 0 180)
			(layer "F.Fab")
			(effects
				(font
					(size 1.27 1.27)
				)
			)
		)
		(duplicate_pad_numbers_are_jumpers no)
		(fp_line
			(start 0.7874 0.4064)
			(end -0.7874 0.4064)
			(stroke
				(width 0.1524)
				(type default)
			)
			(layer "F.SilkS")
		)
		(fp_line
			(start 0.7874 -0.4064)
			(end 0.7874 0.4064)
			(stroke
				(width 0.1524)
				(type default)
			)
			(layer "F.SilkS")
		)
		(fp_line
			(start -0.7874 0.4064)
			(end -0.7874 -0.4064)
			(stroke
				(width 0.1524)
				(type default)
			)
			(layer "F.SilkS")
		)
		(fp_line
			(start -0.7874 -0.4064)
			(end 0.7874 -0.4064)
			(stroke
				(width 0.1524)
				(type default)
			)
			(layer "F.SilkS")
		)
		(fp_line
			(start 0.67945 0.3048)
			(end 0.120396 0.3048)
			(stroke
				(width 0.1)
				(type default)
			)
			(layer "F.Fab")
		)
		(fp_line
			(start 0.67945 -0.3048)
			(end 0.67945 0.3048)
			(stroke
				(width 0.1)
				(type default)
			)
			(layer "F.Fab")
		)
		(fp_line
			(start 0.12065 -0.2794)
			(end 0.12065 -0.3048)
			(stroke
				(width 0.1)
				(type default)
			)
			(layer "F.Fab")
		)
		(fp_line
			(start 0.12065 -0.3048)
			(end 0.67945 -0.3048)
			(stroke
				(width 0.1)
				(type default)
			)
			(layer "F.Fab")
		)
		(fp_line
			(start 0.120396 0.3048)
			(end 0.120396 0.2794)
			(stroke
				(width 0.1)
				(type default)
			)
			(layer "F.Fab")
		)
		(fp_line
			(start 0.120396 0.2794)
			(end -0.12065 0.2794)
			(stroke
				(width 0.1)
				(type default)
			)
			(layer "F.Fab")
		)
		(fp_line
			(start -0.12065 0.3048)
			(end -0.67945 0.3048)
			(stroke
				(width 0.1)
				(type default)
			)
			(layer "F.Fab")
		)
		(fp_line
			(start -0.12065 0.2794)
			(end -0.12065 0.3048)
			(stroke
				(width 0.1)
				(type default)
			)
			(layer "F.Fab")
		)
		(fp_line
			(start -0.12065 -0.2794)
			(end 0.12065 -0.2794)
			(stroke
				(width 0.1)
				(type default)
			)
			(layer "F.Fab")
		)
		(fp_line
			(start -0.12065 -0.305054)
			(end -0.12065 -0.2794)
			(stroke
				(width 0.1)
				(type default)
			)
			(layer "F.Fab")
		)
		(fp_line
			(start -0.67945 0.3048)
			(end -0.67945 -0.305054)
			(stroke
				(width 0.1)
				(type default)
			)
			(layer "F.Fab")
		)
		(fp_line
			(start -0.67945 -0.305054)
			(end -0.12065 -0.305054)
			(stroke
				(width 0.1)
				(type default)
			)
			(layer "F.Fab")
		)
		(pad "1" smd circle
			(at -0.40005 0 180)
			(size 0 0)
			(layers "F.Cu" "F.Mask" "F.Paste")
			(net "P3V3_AUX")
		)
		(pad "2" smd circle
			(at 0.40005 0 180)
			(size 0 0)
			(layers "F.Cu" "F.Mask" "F.Paste")
			(net "FAN_2_PRESENT_N")
		)
	)
	(footprint ""
		(layer "F.Cu")
		(at 18.679922 -14.310868 180)
		(property "Reference" "D243"
			(at 0.772922 -1.383538 0)
			(unlocked yes)
			(layer "F.SilkS")
			(effects
				(font
					(size 0.7874 0.5842)
					(thickness 0.1524)
				)
				(justify left)
			)
		)
		(property "Value" ""
			(at 0 0 180)
			(layer "F.Fab")
			(effects
				(font
					(size 1.27 1.27)
				)
			)
		)
		(duplicate_pad_numbers_are_jumpers no)
		(fp_line
			(start 0.94488 0.450088)
			(end 0.94488 -0.450088)
			(stroke
				(width 0.1524)
				(type default)
			)
			(layer "F.SilkS")
		)
		(fp_line
			(start 0.94488 -0.450088)
			(end -0.854964 -0.450088)
			(stroke
				(width 0.1524)
				(type default)
			)
			(layer "F.SilkS")
		)
		(fp_line
			(start 0.870458 -0.2794)
			(end 0.845058 0.4064)
			(stroke
				(width 0.1524)
				(type default)
			)
			(layer "F.SilkS")
		)
		(fp_line
			(start 0.845058 0.4064)
			(end 0.845058 -0.381)
			(stroke
				(width 0.1524)
				(type default)
			)
			(layer "F.SilkS")
		)
		(fp_line
			(start -0.854964 0.450088)
			(end 0.925068 0.450088)
			(stroke
				(width 0.1524)
				(type default)
			)
			(layer "F.SilkS")
		)
		(fp_line
			(start -0.854964 -0.450088)
			(end -0.854964 0.450088)
			(stroke
				(width 0.1524)
				(type default)
			)
			(layer "F.SilkS")
		)
		(fp_line
			(start 0.54991 0.350012)
			(end 0.54991 -0.350012)
			(stroke
				(width 0.1)
				(type default)
			)
			(layer "F.Fab")
		)
		(fp_line
			(start 0.54991 -0.350012)
			(end -0.54991 -0.350012)
			(stroke
				(width 0.1)
				(type default)
			)
			(layer "F.Fab")
		)
		(fp_line
			(start -0.54991 0.350012)
			(end 0.54991 0.350012)
			(stroke
				(width 0.1)
				(type default)
			)
			(layer "F.Fab")
		)
		(fp_line
			(start -0.54991 -0.350012)
			(end -0.54991 0.350012)
			(stroke
				(width 0.1)
				(type default)
			)
			(layer "F.Fab")
		)
		(fp_text user "-"
			(at 1.915922 -0.499618 0)
			(unlocked yes)
			(layer "F.SilkS")
			(effects
				(font
					(size 1.905 1.4224)
					(thickness 0.1524)
				)
				(justify left)
			)
		)
		(fp_text user "+"
			(at -0.624078 0.262382 0)
			(unlocked yes)
			(layer "F.SilkS")
			(effects
				(font
					(size 1.905 1.4224)
					(thickness 0.1524)
				)
				(justify left)
			)
		)
		(fp_text user "-"
			(at 2.48539 0.239014 0)
			(unlocked yes)
			(layer "F.Fab")
			(effects
				(font
					(size 1.905 1.4224)
					(thickness 0.1524)
				)
				(justify left)
			)
		)
		(fp_text user "+"
			(at -0.808228 0.239014 0)
			(unlocked yes)
			(layer "F.Fab")
			(effects
				(font
					(size 1.905 1.4224)
					(thickness 0.1524)
				)
				(justify left)
			)
		)
		(pad "A" smd rect
			(at -0.424942 0 180)
			(size 0.5588 0.6096)
			(layers "F.Cu" "F.Mask" "F.Paste")
			(net "GND")
		)
		(pad "C" smd rect
			(at 0.424942 0)
			(size 0.5588 0.6096)
			(layers "F.Cu" "F.Mask" "F.Paste")
			(net "FAN_4_PWM_OL_R")
		)
	)
	(footprint ""
		(layer "F.Cu")
		(at 36.068 -250.444 -90)
		(property "Reference" "PR28"
			(at 0 0 270)
			(layer "F.SilkS")
			(hide yes)
			(effects
				(font
					(size 1.27 1.27)
				)
			)
		)
		(property "Value" ""
			(at 0 0 270)
			(layer "F.Fab")
			(effects
				(font
					(size 1.27 1.27)
				)
			)
		)
		(duplicate_pad_numbers_are_jumpers no)
		(fp_line
			(start -0.7874 0.4064)
			(end -0.7874 -0.4064)
			(stroke
				(width 0.1524)
				(type default)
			)
			(layer "F.SilkS")
		)
		(fp_line
			(start 0.7874 0.4064)
			(end -0.7874 0.4064)
			(stroke
				(width 0.1524)
				(type default)
			)
			(layer "F.SilkS")
		)
		(fp_line
			(start -0.7874 -0.4064)
			(end 0.7874 -0.4064)
			(stroke
				(width 0.1524)
				(type default)
			)
			(layer "F.SilkS")
		)
		(fp_line
			(start 0.7874 -0.4064)
			(end 0.7874 0.4064)
			(stroke
				(width 0.1524)
				(type default)
			)
			(layer "F.SilkS")
		)
		(fp_line
			(start -0.67945 0.3048)
			(end -0.67945 -0.305054)
			(stroke
				(width 0.1)
				(type default)
			)
			(layer "F.Fab")
		)
		(fp_line
			(start -0.12065 0.3048)
			(end -0.67945 0.3048)
			(stroke
				(width 0.1)
				(type default)
			)
			(layer "F.Fab")
		)
		(fp_line
			(start 0.120396 0.3048)
			(end 0.120396 0.2794)
			(stroke
				(width 0.1)
				(type default)
			)
			(layer "F.Fab")
		)
		(fp_line
			(start 0.67945 0.3048)
			(end 0.120396 0.3048)
			(stroke
				(width 0.1)
				(type default)
			)
			(layer "F.Fab")
		)
		(fp_line
			(start -0.12065 0.2794)
			(end -0.12065 0.3048)
			(stroke
				(width 0.1)
				(type default)
			)
			(layer "F.Fab")
		)
		(fp_line
			(start 0.120396 0.2794)
			(end -0.12065 0.2794)
			(stroke
				(width 0.1)
				(type default)
			)
			(layer "F.Fab")
		)
		(fp_line
			(start -0.12065 -0.2794)
			(end 0.12065 -0.2794)
			(stroke
				(width 0.1)
				(type default)
			)
			(layer "F.Fab")
		)
		(fp_line
			(start 0.12065 -0.2794)
			(end 0.12065 -0.3048)
			(stroke
				(width 0.1)
				(type default)
			)
			(layer "F.Fab")
		)
		(fp_line
			(start 0.12065 -0.3048)
			(end 0.67945 -0.3048)
			(stroke
				(width 0.1)
				(type default)
			)
			(layer "F.Fab")
		)
		(fp_line
			(start 0.67945 -0.3048)
			(end 0.67945 0.3048)
			(stroke
				(width 0.1)
				(type default)
			)
			(layer "F.Fab")
		)
		(fp_line
			(start -0.67945 -0.305054)
			(end -0.12065 -0.305054)
			(stroke
				(width 0.1)
				(type default)
			)
			(layer "F.Fab")
		)
		(fp_line
			(start -0.12065 -0.305054)
			(end -0.12065 -0.2794)
			(stroke
				(width 0.1)
				(type default)
			)
			(layer "F.Fab")
		)
		(pad "1" smd rect
			(at -0.40005 0 90)
			(size 0.4572 0.508)
			(layers "F.Cu" "F.Mask" "F.Paste")
			(net "FAN_1_FAULT_R")
		)
		(pad "2" smd rect
			(at 0.40005 0 90)
			(size 0.4572 0.508)
			(layers "F.Cu" "F.Mask" "F.Paste")
			(net "FAN_1_FAULT")
		)
	)
	(footprint ""
		(layer "F.Cu")
		(at 20.828 -170.688)
		(property "Reference" "R5673"
			(at 0 0 0)
			(layer "F.SilkS")
			(hide yes)
			(effects
				(font
					(size 1.27 1.27)
				)
			)
		)
		(property "Value" ""
			(at 0 0 0)
			(layer "F.Fab")
			(effects
				(font
					(size 1.27 1.27)
				)
			)
		)
		(duplicate_pad_numbers_are_jumpers no)
		(fp_line
			(start -0.7874 -0.4064)
			(end 0.7874 -0.4064)
			(stroke
				(width 0.1524)
				(type default)
			)
			(layer "F.SilkS")
		)
		(fp_line
			(start -0.7874 0.4064)
			(end -0.7874 -0.4064)
			(stroke
				(width 0.1524)
				(type default)
			)
			(layer "F.SilkS")
		)
		(fp_line
			(start 0.7874 -0.4064)
			(end 0.7874 0.4064)
			(stroke
				(width 0.1524)
				(type default)
			)
			(layer "F.SilkS")
		)
		(fp_line
			(start 0.7874 0.4064)
			(end -0.7874 0.4064)
			(stroke
				(width 0.1524)
				(type default)
			)
			(layer "F.SilkS")
		)
		(fp_line
			(start -0.67945 -0.305054)
			(end -0.12065 -0.305054)
			(stroke
				(width 0.1)
				(type default)
			)
			(layer "F.Fab")
		)
		(fp_line
			(start -0.67945 0.3048)
			(end -0.67945 -0.305054)
			(stroke
				(width 0.1)
				(type default)
			)
			(layer "F.Fab")
		)
		(fp_line
			(start -0.12065 -0.305054)
			(end -0.12065 -0.2794)
			(stroke
				(width 0.1)
				(type default)
			)
			(layer "F.Fab")
		)
		(fp_line
			(start -0.12065 -0.2794)
			(end 0.12065 -0.2794)
			(stroke
				(width 0.1)
				(type default)
			)
			(layer "F.Fab")
		)
		(fp_line
			(start -0.12065 0.2794)
			(end -0.12065 0.3048)
			(stroke
				(width 0.1)
				(type default)
			)
			(layer "F.Fab")
		)
		(fp_line
			(start -0.12065 0.3048)
			(end -0.67945 0.3048)
			(stroke
				(width 0.1)
				(type default)
			)
			(layer "F.Fab")
		)
		(fp_line
			(start 0.120396 0.2794)
			(end -0.12065 0.2794)
			(stroke
				(width 0.1)
				(type default)
			)
			(layer "F.Fab")
		)
		(fp_line
			(start 0.120396 0.3048)
			(end 0.120396 0.2794)
			(stroke
				(width 0.1)
				(type default)
			)
			(layer "F.Fab")
		)
		(fp_line
			(start 0.12065 -0.3048)
			(end 0.67945 -0.3048)
			(stroke
				(width 0.1)
				(type default)
			)
			(layer "F.Fab")
		)
		(fp_line
			(start 0.12065 -0.2794)
			(end 0.12065 -0.3048)
			(stroke
				(width 0.1)
				(type default)
			)
			(layer "F.Fab")
		)
		(fp_line
			(start 0.67945 -0.3048)
			(end 0.67945 0.3048)
			(stroke
				(width 0.1)
				(type default)
			)
			(layer "F.Fab")
		)
		(fp_line
			(start 0.67945 0.3048)
			(end 0.120396 0.3048)
			(stroke
				(width 0.1)
				(type default)
			)
			(layer "F.Fab")
		)
		(pad "1" smd circle
			(at -0.40005 0)
			(size 0 0)
			(layers "F.Cu" "F.Mask" "F.Paste")
			(net "FM_BOARD_SKU_ID0")
		)
		(pad "2" smd circle
			(at 0.40005 0)
			(size 0 0)
			(layers "F.Cu" "F.Mask" "F.Paste")
			(net "GND")
		)
	)
	(footprint ""
		(layer "F.Cu")
		(at 32.893 -304.292)
		(property "Reference" "D267"
			(at -0.9906 -1.48463 0)
			(unlocked yes)
			(layer "F.SilkS")
			(effects
				(font
					(size 0.7874 0.5842)
					(thickness 0.1524)
				)
				(justify left)
			)
		)
		(property "Value" ""
			(at 0 0 0)
			(layer "F.Fab")
			(effects
				(font
					(size 1.27 1.27)
				)
			)
		)
		(duplicate_pad_numbers_are_jumpers no)
		(fp_line
			(start -0.854964 -0.450088)
			(end -0.854964 0.450088)
			(stroke
				(width 0.1524)
				(type default)
			)
			(layer "F.SilkS")
		)
		(fp_line
			(start -0.854964 0.450088)
			(end 0.925068 0.450088)
			(stroke
				(width 0.1524)
				(type default)
			)
			(layer "F.SilkS")
		)
		(fp_line
			(start 0.845058 0.4064)
			(end 0.845058 -0.381)
			(stroke
				(width 0.1524)
				(type default)
			)
			(layer "F.SilkS")
		)
		(fp_line
			(start 0.870458 -0.2794)
			(end 0.845058 0.4064)
			(stroke
				(width 0.1524)
				(type default)
			)
			(layer "F.SilkS")
		)
		(fp_line
			(start 0.94488 -0.450088)
			(end -0.854964 -0.450088)
			(stroke
				(width 0.1524)
				(type default)
			)
			(layer "F.SilkS")
		)
		(fp_line
			(start 0.94488 0.450088)
			(end 0.94488 -0.450088)
			(stroke
				(width 0.1524)
				(type default)
			)
			(layer "F.SilkS")
		)
		(fp_line
			(start -0.54991 -0.350012)
			(end -0.54991 0.350012)
			(stroke
				(width 0.1)
				(type default)
			)
			(layer "F.Fab")
		)
		(fp_line
			(start -0.54991 0.350012)
			(end 0.54991 0.350012)
			(stroke
				(width 0.1)
				(type default)
			)
			(layer "F.Fab")
		)
		(fp_line
			(start 0.54991 -0.350012)
			(end -0.54991 -0.350012)
			(stroke
				(width 0.1)
				(type default)
			)
			(layer "F.Fab")
		)
		(fp_line
			(start 0.54991 0.350012)
			(end 0.54991 -0.350012)
			(stroke
				(width 0.1)
				(type default)
			)
			(layer "F.Fab")
		)
		(fp_text user "+"
			(at -0.808228 0.239014 180)
			(unlocked yes)
			(layer "F.SilkS")
			(effects
				(font
					(size 1.905 1.4224)
					(thickness 0.1524)
				)
				(justify left)
			)
		)
		(fp_text user "-"
			(at 1.9558 -0.48895 180)
			(unlocked yes)
			(layer "F.SilkS")
			(effects
				(font
					(size 1.905 1.4224)
					(thickness 0.1524)
				)
				(justify left)
			)
		)
		(fp_text user "+"
			(at -0.808228 0.239014 180)
			(unlocked yes)
			(layer "F.Fab")
			(effects
				(font
					(size 1.905 1.4224)
					(thickness 0.1524)
				)
				(justify left)
			)
		)
		(fp_text user "-"
			(at 2.48539 0.239014 180)
			(unlocked yes)
			(layer "F.Fab")
			(effects
				(font
					(size 1.905 1.4224)
					(thickness 0.1524)
				)
				(justify left)
			)
		)
		(pad "A" smd rect
			(at -0.424942 0)
			(size 0.5588 0.6096)
			(layers "F.Cu" "F.Mask" "F.Paste")
			(net "GND")
		)
		(pad "C" smd rect
			(at 0.424942 0 180)
			(size 0.5588 0.6096)
			(layers "F.Cu" "F.Mask" "F.Paste")
			(net "FAN_0_PWM_OL_R")
		)
	)
	(footprint ""
		(layer "F.Cu")
		(at 25.850088 -326.909938)
		(property "Reference" "H11"
			(at -1.085088 -5.713222 0)
			(unlocked yes)
			(layer "F.SilkS")
			(effects
				(font
					(size 0.7874 0.5842)
					(thickness 0.1524)
				)
				(justify left)
			)
		)
		(property "Value" ""
			(at 0 0 0)
			(layer "F.Fab")
			(effects
				(font
					(size 1.27 1.27)
				)
			)
		)
		(duplicate_pad_numbers_are_jumpers no)
		(pad "1" thru_hole circle
			(at 0 0)
			(size 10.16 10.16)
			(drill 6.4008
				(offset 0 0)
			)
			(layers "*.Cu" "*.Mask")
			(remove_unused_layers no)
			(net "GND")
			(clearance -1.6256)
			(padstack
				(mode front_inner_back)
				(layer "Inner"
					(shape circle)
					(size 10.16 10.16)
					(clearance -1.6256)
				)
				(layer "B.Cu"
					(shape oval)
					(size 10.0076 32.004)
					(offset 0 10.9982)
					(clearance -1.5494)
				)
			)
		)
	)
	(footprint ""
		(layer "F.Cu")
		(at 27.432 -185.674 180)
		(property "Reference" "R5493"
			(at 0 0 180)
			(layer "F.SilkS")
			(hide yes)
			(effects
				(font
					(size 1.27 1.27)
				)
			)
		)
		(property "Value" ""
			(at 0 0 180)
			(layer "F.Fab")
			(effects
				(font
					(size 1.27 1.27)
				)
			)
		)
		(duplicate_pad_numbers_are_jumpers no)
		(fp_line
			(start 0.7874 0.4064)
			(end -0.7874 0.4064)
			(stroke
				(width 0.1524)
				(type default)
			)
			(layer "F.SilkS")
		)
		(fp_line
			(start 0.7874 -0.4064)
			(end 0.7874 0.4064)
			(stroke
				(width 0.1524)
				(type default)
			)
			(layer "F.SilkS")
		)
		(fp_line
			(start -0.7874 0.4064)
			(end -0.7874 -0.4064)
			(stroke
				(width 0.1524)
				(type default)
			)
			(layer "F.SilkS")
		)
		(fp_line
			(start -0.7874 -0.4064)
			(end 0.7874 -0.4064)
			(stroke
				(width 0.1524)
				(type default)
			)
			(layer "F.SilkS")
		)
		(fp_line
			(start 0.67945 0.3048)
			(end 0.120396 0.3048)
			(stroke
				(width 0.1)
				(type default)
			)
			(layer "F.Fab")
		)
		(fp_line
			(start 0.67945 -0.3048)
			(end 0.67945 0.3048)
			(stroke
				(width 0.1)
				(type default)
			)
			(layer "F.Fab")
		)
		(fp_line
			(start 0.12065 -0.2794)
			(end 0.12065 -0.3048)
			(stroke
				(width 0.1)
				(type default)
			)
			(layer "F.Fab")
		)
		(fp_line
			(start 0.12065 -0.3048)
			(end 0.67945 -0.3048)
			(stroke
				(width 0.1)
				(type default)
			)
			(layer "F.Fab")
		)
		(fp_line
			(start 0.120396 0.3048)
			(end 0.120396 0.2794)
			(stroke
				(width 0.1)
				(type default)
			)
			(layer "F.Fab")
		)
		(fp_line
			(start 0.120396 0.2794)
			(end -0.12065 0.2794)
			(stroke
				(width 0.1)
				(type default)
			)
			(layer "F.Fab")
		)
		(fp_line
			(start -0.12065 0.3048)
			(end -0.67945 0.3048)
			(stroke
				(width 0.1)
				(type default)
			)
			(layer "F.Fab")
		)
		(fp_line
			(start -0.12065 0.2794)
			(end -0.12065 0.3048)
			(stroke
				(width 0.1)
				(type default)
			)
			(layer "F.Fab")
		)
		(fp_line
			(start -0.12065 -0.2794)
			(end 0.12065 -0.2794)
			(stroke
				(width 0.1)
				(type default)
			)
			(layer "F.Fab")
		)
		(fp_line
			(start -0.12065 -0.305054)
			(end -0.12065 -0.2794)
			(stroke
				(width 0.1)
				(type default)
			)
			(layer "F.Fab")
		)
		(fp_line
			(start -0.67945 0.3048)
			(end -0.67945 -0.305054)
			(stroke
				(width 0.1)
				(type default)
			)
			(layer "F.Fab")
		)
		(fp_line
			(start -0.67945 -0.305054)
			(end -0.12065 -0.305054)
			(stroke
				(width 0.1)
				(type default)
			)
			(layer "F.Fab")
		)
		(pad "1" smd circle
			(at -0.40005 0 180)
			(size 0 0)
			(layers "F.Cu" "F.Mask" "F.Paste")
			(net "P52V_FAN_6_BUFF_EN")
		)
		(pad "2" smd circle
			(at 0.40005 0 180)
			(size 0 0)
			(layers "F.Cu" "F.Mask" "F.Paste")
			(net "P52V_FAN_6_BUFF_EN_R")
		)
	)
	(footprint ""
		(layer "F.Cu")
		(at 34.544 -109.855)
		(property "Reference" "U373"
			(at -1.4478 -1.819148 0)
			(unlocked yes)
			(layer "F.SilkS")
			(effects
				(font
					(size 0.7874 0.5842)
					(thickness 0.1524)
				)
				(justify left)
			)
		)
		(property "Value" ""
			(at 0 0 0)
			(layer "F.Fab")
			(effects
				(font
					(size 1.27 1.27)
				)
			)
		)
		(duplicate_pad_numbers_are_jumpers no)
		(fp_line
			(start -1.335278 -1.100074)
			(end -1.335278 1.100074)
			(stroke
				(width 0.1524)
				(type default)
			)
			(layer "F.SilkS")
		)
		(fp_line
			(start -1.335278 1.100074)
			(end 1.335278 1.100074)
			(stroke
				(width 0.1524)
				(type default)
			)
			(layer "F.SilkS")
		)
		(fp_line
			(start 1.335278 -1.100074)
			(end -1.335278 -1.100074)
			(stroke
				(width 0.1524)
				(type default)
			)
			(layer "F.SilkS")
		)
		(fp_line
			(start 1.335278 1.100074)
			(end 1.335278 -1.100074)
			(stroke
				(width 0.1524)
				(type default)
			)
			(layer "F.SilkS")
		)
		(fp_line
			(start -0.674878 -1.100074)
			(end -0.674878 1.100074)
			(stroke
				(width 0.1)
				(type default)
			)
			(layer "F.Fab")
		)
		(fp_line
			(start -0.674878 1.100074)
			(end 0.674878 1.100074)
			(stroke
				(width 0.1)
				(type default)
			)
			(layer "F.Fab")
		)
		(fp_line
			(start 0.674878 -1.100074)
			(end -0.674878 -1.100074)
			(stroke
				(width 0.1)
				(type default)
			)
			(layer "F.Fab")
		)
		(fp_line
			(start 0.674878 1.100074)
			(end 0.674878 -1.100074)
			(stroke
				(width 0.1)
				(type default)
			)
			(layer "F.Fab")
		)
		(pad "D" smd rect
			(at 0.8001 0 270)
			(size 0.6096 0.8128)
			(layers "F.Cu" "F.Mask" "F.Paste")
			(net "FAN_2_FAIL_LED_R_N")
		)
		(pad "G" smd rect
			(at -0.8001 -0.649986 270)
			(size 0.6096 0.8128)
			(layers "F.Cu" "F.Mask" "F.Paste")
			(net "FAN_2_FAIL_R_LED")
		)
		(pad "S" smd rect
			(at -0.8001 0.649986 270)
			(size 0.6096 0.8128)
			(layers "F.Cu" "F.Mask" "F.Paste")
			(net "GND")
		)
	)
	(footprint ""
		(layer "F.Cu")
		(at 15.621 -169.291)
		(property "Reference" "C1940"
			(at 0 0 0)
			(layer "F.SilkS")
			(hide yes)
			(effects
				(font
					(size 1.27 1.27)
				)
			)
		)
		(property "Value" ""
			(at 0 0 0)
			(layer "F.Fab")
			(effects
				(font
					(size 1.27 1.27)
				)
			)
		)
		(duplicate_pad_numbers_are_jumpers no)
		(fp_line
			(start -0.7874 -0.4064)
			(end 0.7874 -0.4064)
			(stroke
				(width 0.1524)
				(type default)
			)
			(layer "F.SilkS")
		)
		(fp_line
			(start -0.7874 0.4064)
			(end -0.7874 -0.4064)
			(stroke
				(width 0.1524)
				(type default)
			)
			(layer "F.SilkS")
		)
		(fp_line
			(start 0.7874 -0.4064)
			(end 0.7874 0.4064)
			(stroke
				(width 0.1524)
				(type default)
			)
			(layer "F.SilkS")
		)
		(fp_line
			(start 0.7874 0.4064)
			(end -0.7874 0.4064)
			(stroke
				(width 0.1524)
				(type default)
			)
			(layer "F.SilkS")
		)
		(fp_line
			(start -0.67945 -0.305054)
			(end -0.12065 -0.305054)
			(stroke
				(width 0.1)
				(type default)
			)
			(layer "F.Fab")
		)
		(fp_line
			(start -0.67945 0.3048)
			(end -0.67945 -0.305054)
			(stroke
				(width 0.1)
				(type default)
			)
			(layer "F.Fab")
		)
		(fp_line
			(start -0.12065 -0.305054)
			(end -0.12065 -0.2794)
			(stroke
				(width 0.1)
				(type default)
			)
			(layer "F.Fab")
		)
		(fp_line
			(start -0.12065 -0.2794)
			(end 0.12065 -0.2794)
			(stroke
				(width 0.1)
				(type default)
			)
			(layer "F.Fab")
		)
		(fp_line
			(start -0.12065 0.2794)
			(end -0.12065 0.3048)
			(stroke
				(width 0.1)
				(type default)
			)
			(layer "F.Fab")
		)
		(fp_line
			(start -0.12065 0.3048)
			(end -0.67945 0.3048)
			(stroke
				(width 0.1)
				(type default)
			)
			(layer "F.Fab")
		)
		(fp_line
			(start 0.120396 0.2794)
			(end -0.12065 0.2794)
			(stroke
				(width 0.1)
				(type default)
			)
			(layer "F.Fab")
		)
		(fp_line
			(start 0.120396 0.3048)
			(end 0.120396 0.2794)
			(stroke
				(width 0.1)
				(type default)
			)
			(layer "F.Fab")
		)
		(fp_line
			(start 0.12065 -0.3048)
			(end 0.67945 -0.3048)
			(stroke
				(width 0.1)
				(type default)
			)
			(layer "F.Fab")
		)
		(fp_line
			(start 0.12065 -0.2794)
			(end 0.12065 -0.3048)
			(stroke
				(width 0.1)
				(type default)
			)
			(layer "F.Fab")
		)
		(fp_line
			(start 0.67945 -0.3048)
			(end 0.67945 0.3048)
			(stroke
				(width 0.1)
				(type default)
			)
			(layer "F.Fab")
		)
		(fp_line
			(start 0.67945 0.3048)
			(end 0.120396 0.3048)
			(stroke
				(width 0.1)
				(type default)
			)
			(layer "F.Fab")
		)
		(pad "1" smd circle
			(at -0.40005 0)
			(size 0 0)
			(layers "F.Cu" "F.Mask" "F.Paste")
			(net "FAN_4_PRESENT_N")
		)
		(pad "2" smd circle
			(at 0.40005 0)
			(size 0 0)
			(layers "F.Cu" "F.Mask" "F.Paste")
			(net "GND")
		)
	)
	(footprint ""
		(layer "F.Cu")
		(at 32.131 -162.941 90)
		(property "Reference" "R5288"
			(at 0 0 90)
			(layer "F.SilkS")
			(hide yes)
			(effects
				(font
					(size 1.27 1.27)
				)
			)
		)
		(property "Value" ""
			(at 0 0 90)
			(layer "F.Fab")
			(effects
				(font
					(size 1.27 1.27)
				)
			)
		)
		(duplicate_pad_numbers_are_jumpers no)
		(fp_line
			(start 0.7874 -0.4064)
			(end 0.7874 0.4064)
			(stroke
				(width 0.1524)
				(type default)
			)
			(layer "F.SilkS")
		)
		(fp_line
			(start -0.7874 -0.4064)
			(end 0.7874 -0.4064)
			(stroke
				(width 0.1524)
				(type default)
			)
			(layer "F.SilkS")
		)
		(fp_line
			(start 0.7874 0.4064)
			(end -0.7874 0.4064)
			(stroke
				(width 0.1524)
				(type default)
			)
			(layer "F.SilkS")
		)
		(fp_line
			(start -0.7874 0.4064)
			(end -0.7874 -0.4064)
			(stroke
				(width 0.1524)
				(type default)
			)
			(layer "F.SilkS")
		)
		(fp_line
			(start -0.12065 -0.305054)
			(end -0.12065 -0.2794)
			(stroke
				(width 0.1)
				(type default)
			)
			(layer "F.Fab")
		)
		(fp_line
			(start -0.67945 -0.305054)
			(end -0.12065 -0.305054)
			(stroke
				(width 0.1)
				(type default)
			)
			(layer "F.Fab")
		)
		(fp_line
			(start 0.67945 -0.3048)
			(end 0.67945 0.3048)
			(stroke
				(width 0.1)
				(type default)
			)
			(layer "F.Fab")
		)
		(fp_line
			(start 0.12065 -0.3048)
			(end 0.67945 -0.3048)
			(stroke
				(width 0.1)
				(type default)
			)
			(layer "F.Fab")
		)
		(fp_line
			(start 0.12065 -0.2794)
			(end 0.12065 -0.3048)
			(stroke
				(width 0.1)
				(type default)
			)
			(layer "F.Fab")
		)
		(fp_line
			(start -0.12065 -0.2794)
			(end 0.12065 -0.2794)
			(stroke
				(width 0.1)
				(type default)
			)
			(layer "F.Fab")
		)
		(fp_line
			(start 0.120396 0.2794)
			(end -0.12065 0.2794)
			(stroke
				(width 0.1)
				(type default)
			)
			(layer "F.Fab")
		)
		(fp_line
			(start -0.12065 0.2794)
			(end -0.12065 0.3048)
			(stroke
				(width 0.1)
				(type default)
			)
			(layer "F.Fab")
		)
		(fp_line
			(start 0.67945 0.3048)
			(end 0.120396 0.3048)
			(stroke
				(width 0.1)
				(type default)
			)
			(layer "F.Fab")
		)
		(fp_line
			(start 0.120396 0.3048)
			(end 0.120396 0.2794)
			(stroke
				(width 0.1)
				(type default)
			)
			(layer "F.Fab")
		)
		(fp_line
			(start -0.12065 0.3048)
			(end -0.67945 0.3048)
			(stroke
				(width 0.1)
				(type default)
			)
			(layer "F.Fab")
		)
		(fp_line
			(start -0.67945 0.3048)
			(end -0.67945 -0.305054)
			(stroke
				(width 0.1)
				(type default)
			)
			(layer "F.Fab")
		)
		(pad "1" smd circle
			(at -0.40005 0 90)
			(size 0 0)
			(layers "F.Cu" "F.Mask" "F.Paste")
			(net "SMB_FAN4_R_SCL")
		)
		(pad "2" smd circle
			(at 0.40005 0 90)
			(size 0 0)
			(layers "F.Cu" "F.Mask" "F.Paste")
			(net "P3V3_AUX")
		)
	)
	(footprint ""
		(layer "F.Cu")
		(at 24.384 -13.8938 -90)
		(property "Reference" "R4968"
			(at 0 0 270)
			(layer "F.SilkS")
			(hide yes)
			(effects
				(font
					(size 1.27 1.27)
				)
			)
		)
		(property "Value" ""
			(at 0 0 270)
			(layer "F.Fab")
			(effects
				(font
					(size 1.27 1.27)
				)
			)
		)
		(duplicate_pad_numbers_are_jumpers no)
		(fp_line
			(start -0.7874 0.4064)
			(end -0.7874 -0.4064)
			(stroke
				(width 0.1524)
				(type default)
			)
			(layer "F.SilkS")
		)
		(fp_line
			(start 0.7874 0.4064)
			(end -0.7874 0.4064)
			(stroke
				(width 0.1524)
				(type default)
			)
			(layer "F.SilkS")
		)
		(fp_line
			(start -0.7874 -0.4064)
			(end 0.7874 -0.4064)
			(stroke
				(width 0.1524)
				(type default)
			)
			(layer "F.SilkS")
		)
		(fp_line
			(start 0.7874 -0.4064)
			(end 0.7874 0.4064)
			(stroke
				(width 0.1524)
				(type default)
			)
			(layer "F.SilkS")
		)
		(fp_line
			(start -0.67945 0.3048)
			(end -0.67945 -0.305054)
			(stroke
				(width 0.1)
				(type default)
			)
			(layer "F.Fab")
		)
		(fp_line
			(start -0.12065 0.3048)
			(end -0.67945 0.3048)
			(stroke
				(width 0.1)
				(type default)
			)
			(layer "F.Fab")
		)
		(fp_line
			(start 0.120396 0.3048)
			(end 0.120396 0.2794)
			(stroke
				(width 0.1)
				(type default)
			)
			(layer "F.Fab")
		)
		(fp_line
			(start 0.67945 0.3048)
			(end 0.120396 0.3048)
			(stroke
				(width 0.1)
				(type default)
			)
			(layer "F.Fab")
		)
		(fp_line
			(start -0.12065 0.2794)
			(end -0.12065 0.3048)
			(stroke
				(width 0.1)
				(type default)
			)
			(layer "F.Fab")
		)
		(fp_line
			(start 0.120396 0.2794)
			(end -0.12065 0.2794)
			(stroke
				(width 0.1)
				(type default)
			)
			(layer "F.Fab")
		)
		(fp_line
			(start -0.12065 -0.2794)
			(end 0.12065 -0.2794)
			(stroke
				(width 0.1)
				(type default)
			)
			(layer "F.Fab")
		)
		(fp_line
			(start 0.12065 -0.2794)
			(end 0.12065 -0.3048)
			(stroke
				(width 0.1)
				(type default)
			)
			(layer "F.Fab")
		)
		(fp_line
			(start 0.12065 -0.3048)
			(end 0.67945 -0.3048)
			(stroke
				(width 0.1)
				(type default)
			)
			(layer "F.Fab")
		)
		(fp_line
			(start 0.67945 -0.3048)
			(end 0.67945 0.3048)
			(stroke
				(width 0.1)
				(type default)
			)
			(layer "F.Fab")
		)
		(fp_line
			(start -0.67945 -0.305054)
			(end -0.12065 -0.305054)
			(stroke
				(width 0.1)
				(type default)
			)
			(layer "F.Fab")
		)
		(fp_line
			(start -0.12065 -0.305054)
			(end -0.12065 -0.2794)
			(stroke
				(width 0.1)
				(type default)
			)
			(layer "F.Fab")
		)
		(pad "1" smd circle
			(at -0.40005 0 270)
			(size 0 0)
			(layers "F.Cu" "F.Mask" "F.Paste")
			(net "SMB_PDBV_FAN_SCL")
		)
		(pad "2" smd circle
			(at 0.40005 0 270)
			(size 0 0)
			(layers "F.Cu" "F.Mask" "F.Paste")
			(net "SMB_PDBV_FAN_R_SCL")
		)
	)
	(footprint ""
		(layer "F.Cu")
		(at 47.752 -125.984)
		(property "Reference" "C2036"
			(at 0 0 0)
			(layer "F.SilkS")
			(hide yes)
			(effects
				(font
					(size 1.27 1.27)
				)
			)
		)
		(property "Value" ""
			(at 0 0 0)
			(layer "F.Fab")
			(effects
				(font
					(size 1.27 1.27)
				)
			)
		)
		(duplicate_pad_numbers_are_jumpers no)
		(fp_line
			(start -1.524 -0.762)
			(end 1.524 -0.762)
			(stroke
				(width 0.1524)
				(type default)
			)
			(layer "F.SilkS")
		)
		(fp_line
			(start -1.524 0.762)
			(end -1.524 -0.762)
			(stroke
				(width 0.1524)
				(type default)
			)
			(layer "F.SilkS")
		)
		(fp_line
			(start 1.524 -0.762)
			(end 1.524 0.762)
			(stroke
				(width 0.1524)
				(type default)
			)
			(layer "F.SilkS")
		)
		(fp_line
			(start 1.524 0.762)
			(end -1.524 0.762)
			(stroke
				(width 0.1524)
				(type default)
			)
			(layer "F.SilkS")
		)
		(fp_line
			(start -1.1049 -0.724916)
			(end -1.1049 0.724916)
			(stroke
				(width 0.1)
				(type default)
			)
			(layer "F.Fab")
		)
		(fp_line
			(start -1.1049 0.724916)
			(end 1.1049 0.724916)
			(stroke
				(width 0.1)
				(type default)
			)
			(layer "F.Fab")
		)
		(fp_line
			(start 1.1049 -0.724916)
			(end -1.1049 -0.724916)
			(stroke
				(width 0.1)
				(type default)
			)
			(layer "F.Fab")
		)
		(fp_line
			(start 1.1049 0.724916)
			(end 1.1049 -0.724916)
			(stroke
				(width 0.1)
				(type default)
			)
			(layer "F.Fab")
		)
		(pad "1" smd rect
			(at -0.889 0 180)
			(size 1.016 1.27)
			(layers "F.Cu" "F.Mask" "F.Paste")
			(net "P12V_LED_FAN2")
		)
		(pad "2" smd rect
			(at 0.889 0 180)
			(size 1.016 1.27)
			(layers "F.Cu" "F.Mask" "F.Paste")
			(net "GND")
		)
	)
	(footprint ""
		(layer "F.Cu")
		(at 37.338 -20.279868)
		(property "Reference" "D282"
			(at 1.27 -0.648462 0)
			(unlocked yes)
			(layer "F.SilkS")
			(effects
				(font
					(size 0.7874 0.5842)
					(thickness 0.1524)
				)
				(justify left)
			)
		)
		(property "Value" ""
			(at 0 0 0)
			(layer "F.Fab")
			(effects
				(font
					(size 1.27 1.27)
				)
			)
		)
		(duplicate_pad_numbers_are_jumpers no)
		(fp_line
			(start -0.854964 -0.450088)
			(end -0.854964 0.450088)
			(stroke
				(width 0.1524)
				(type default)
			)
			(layer "F.SilkS")
		)
		(fp_line
			(start -0.854964 0.450088)
			(end 0.925068 0.450088)
			(stroke
				(width 0.1524)
				(type default)
			)
			(layer "F.SilkS")
		)
		(fp_line
			(start 0.845058 0.4064)
			(end 0.845058 -0.381)
			(stroke
				(width 0.1524)
				(type default)
			)
			(layer "F.SilkS")
		)
		(fp_line
			(start 0.870458 -0.2794)
			(end 0.845058 0.4064)
			(stroke
				(width 0.1524)
				(type default)
			)
			(layer "F.SilkS")
		)
		(fp_line
			(start 0.94488 -0.450088)
			(end -0.854964 -0.450088)
			(stroke
				(width 0.1524)
				(type default)
			)
			(layer "F.SilkS")
		)
		(fp_line
			(start 0.94488 0.450088)
			(end 0.94488 -0.450088)
			(stroke
				(width 0.1524)
				(type default)
			)
			(layer "F.SilkS")
		)
		(fp_line
			(start -0.54991 -0.350012)
			(end -0.54991 0.350012)
			(stroke
				(width 0.1)
				(type default)
			)
			(layer "F.Fab")
		)
		(fp_line
			(start -0.54991 0.350012)
			(end 0.54991 0.350012)
			(stroke
				(width 0.1)
				(type default)
			)
			(layer "F.Fab")
		)
		(fp_line
			(start 0.54991 -0.350012)
			(end -0.54991 -0.350012)
			(stroke
				(width 0.1)
				(type default)
			)
			(layer "F.Fab")
		)
		(fp_line
			(start 0.54991 0.350012)
			(end 0.54991 -0.350012)
			(stroke
				(width 0.1)
				(type default)
			)
			(layer "F.Fab")
		)
		(fp_text user "+"
			(at -0.635 0.563118 180)
			(unlocked yes)
			(layer "F.SilkS")
			(effects
				(font
					(size 1.905 1.4224)
					(thickness 0.1524)
				)
				(justify left)
			)
		)
		(fp_text user "-"
			(at 2.159 0.563118 180)
			(unlocked yes)
			(layer "F.SilkS")
			(effects
				(font
					(size 1.905 1.4224)
					(thickness 0.1524)
				)
				(justify left)
			)
		)
		(fp_text user "+"
			(at -0.808228 0.239014 180)
			(unlocked yes)
			(layer "F.Fab")
			(effects
				(font
					(size 1.905 1.4224)
					(thickness 0.1524)
				)
				(justify left)
			)
		)
		(fp_text user "-"
			(at 2.48539 0.239014 180)
			(unlocked yes)
			(layer "F.Fab")
			(effects
				(font
					(size 1.905 1.4224)
					(thickness 0.1524)
				)
				(justify left)
			)
		)
		(pad "A" smd rect
			(at -0.424942 0)
			(size 0.5588 0.6096)
			(layers "F.Cu" "F.Mask" "F.Paste")
			(net "GND")
		)
		(pad "C" smd rect
			(at 0.424942 0 180)
			(size 0.5588 0.6096)
			(layers "F.Cu" "F.Mask" "F.Paste")
			(net "FAN_3_OK_R_LED_N")
		)
	)
	(footprint ""
		(layer "F.Cu")
		(at 13.335 -172.466 180)
		(property "Reference" "R5505"
			(at 0 0 180)
			(layer "F.SilkS")
			(hide yes)
			(effects
				(font
					(size 1.27 1.27)
				)
			)
		)
		(property "Value" ""
			(at 0 0 180)
			(layer "F.Fab")
			(effects
				(font
					(size 1.27 1.27)
				)
			)
		)
		(duplicate_pad_numbers_are_jumpers no)
		(fp_line
			(start 0.7874 0.4064)
			(end -0.7874 0.4064)
			(stroke
				(width 0.1524)
				(type default)
			)
			(layer "F.SilkS")
		)
		(fp_line
			(start 0.7874 -0.4064)
			(end 0.7874 0.4064)
			(stroke
				(width 0.1524)
				(type default)
			)
			(layer "F.SilkS")
		)
		(fp_line
			(start -0.7874 0.4064)
			(end -0.7874 -0.4064)
			(stroke
				(width 0.1524)
				(type default)
			)
			(layer "F.SilkS")
		)
		(fp_line
			(start -0.7874 -0.4064)
			(end 0.7874 -0.4064)
			(stroke
				(width 0.1524)
				(type default)
			)
			(layer "F.SilkS")
		)
		(fp_line
			(start 0.67945 0.3048)
			(end 0.120396 0.3048)
			(stroke
				(width 0.1)
				(type default)
			)
			(layer "F.Fab")
		)
		(fp_line
			(start 0.67945 -0.3048)
			(end 0.67945 0.3048)
			(stroke
				(width 0.1)
				(type default)
			)
			(layer "F.Fab")
		)
		(fp_line
			(start 0.12065 -0.2794)
			(end 0.12065 -0.3048)
			(stroke
				(width 0.1)
				(type default)
			)
			(layer "F.Fab")
		)
		(fp_line
			(start 0.12065 -0.3048)
			(end 0.67945 -0.3048)
			(stroke
				(width 0.1)
				(type default)
			)
			(layer "F.Fab")
		)
		(fp_line
			(start 0.120396 0.3048)
			(end 0.120396 0.2794)
			(stroke
				(width 0.1)
				(type default)
			)
			(layer "F.Fab")
		)
		(fp_line
			(start 0.120396 0.2794)
			(end -0.12065 0.2794)
			(stroke
				(width 0.1)
				(type default)
			)
			(layer "F.Fab")
		)
		(fp_line
			(start -0.12065 0.3048)
			(end -0.67945 0.3048)
			(stroke
				(width 0.1)
				(type default)
			)
			(layer "F.Fab")
		)
		(fp_line
			(start -0.12065 0.2794)
			(end -0.12065 0.3048)
			(stroke
				(width 0.1)
				(type default)
			)
			(layer "F.Fab")
		)
		(fp_line
			(start -0.12065 -0.2794)
			(end 0.12065 -0.2794)
			(stroke
				(width 0.1)
				(type default)
			)
			(layer "F.Fab")
		)
		(fp_line
			(start -0.12065 -0.305054)
			(end -0.12065 -0.2794)
			(stroke
				(width 0.1)
				(type default)
			)
			(layer "F.Fab")
		)
		(fp_line
			(start -0.67945 0.3048)
			(end -0.67945 -0.305054)
			(stroke
				(width 0.1)
				(type default)
			)
			(layer "F.Fab")
		)
		(fp_line
			(start -0.67945 -0.305054)
			(end -0.12065 -0.305054)
			(stroke
				(width 0.1)
				(type default)
			)
			(layer "F.Fab")
		)
		(pad "1" smd circle
			(at -0.40005 0 180)
			(size 0 0)
			(layers "F.Cu" "F.Mask" "F.Paste")
			(net "P3V3_AUX")
		)
		(pad "2" smd circle
			(at 0.40005 0 180)
			(size 0 0)
			(layers "F.Cu" "F.Mask" "F.Paste")
			(net "FAN_6_PRESENT_N")
		)
	)
	(footprint ""
		(layer "F.Cu")
		(at 43.942 -311.277 -90)
		(property "Reference" "Q9"
			(at 2.77495 0.7874 0)
			(unlocked yes)
			(layer "F.SilkS")
			(effects
				(font
					(size 0.7874 0.5842)
					(thickness 0.1524)
				)
				(justify left)
			)
		)
		(property "Value" ""
			(at 0 0 270)
			(layer "F.Fab")
			(effects
				(font
					(size 1.27 1.27)
				)
			)
		)
		(duplicate_pad_numbers_are_jumpers no)
		(fp_line
			(start -1.905 1.651)
			(end -1.905 -1.651)
			(stroke
				(width 0.1524)
				(type default)
			)
			(layer "F.SilkS")
		)
		(fp_line
			(start 1.905 1.651)
			(end -1.905 1.651)
			(stroke
				(width 0.1524)
				(type default)
			)
			(layer "F.SilkS")
		)
		(fp_line
			(start -1.905 -1.651)
			(end 1.905 -1.651)
			(stroke
				(width 0.1524)
				(type default)
			)
			(layer "F.SilkS")
		)
		(fp_line
			(start 1.905 -1.651)
			(end 1.905 1.651)
			(stroke
				(width 0.1524)
				(type default)
			)
			(layer "F.SilkS")
		)
		(fp_line
			(start -0.6985 1.524)
			(end -0.6985 1.169924)
			(stroke
				(width 0.1)
				(type default)
			)
			(layer "F.Fab")
		)
		(fp_line
			(start 0.6985 1.524)
			(end -0.6985 1.524)
			(stroke
				(width 0.1)
				(type default)
			)
			(layer "F.Fab")
		)
		(fp_line
			(start -1.249934 1.169924)
			(end -1.249934 0.729996)
			(stroke
				(width 0.1)
				(type default)
			)
			(layer "F.Fab")
		)
		(fp_line
			(start -0.6985 1.169924)
			(end -1.249934 1.169924)
			(stroke
				(width 0.1)
				(type default)
			)
			(layer "F.Fab")
		)
		(fp_line
			(start -1.249934 0.729996)
			(end -0.6985 0.729996)
			(stroke
				(width 0.1)
				(type default)
			)
			(layer "F.Fab")
		)
		(fp_line
			(start -0.6985 0.729996)
			(end -0.6985 -0.729996)
			(stroke
				(width 0.1)
				(type default)
			)
			(layer "F.Fab")
		)
		(fp_line
			(start 0.6985 0.219964)
			(end 0.6985 1.524)
			(stroke
				(width 0.1)
				(type default)
			)
			(layer "F.Fab")
		)
		(fp_line
			(start 1.249934 0.219964)
			(end 0.6985 0.219964)
			(stroke
				(width 0.1)
				(type default)
			)
			(layer "F.Fab")
		)
		(fp_line
			(start 0.6985 -0.219964)
			(end 1.249934 -0.219964)
			(stroke
				(width 0.1)
				(type default)
			)
			(layer "F.Fab")
		)
		(fp_line
			(start 1.249934 -0.219964)
			(end 1.249934 0.219964)
			(stroke
				(width 0.1)
				(type default)
			)
			(layer "F.Fab")
		)
		(fp_line
			(start -1.249934 -0.729996)
			(end -1.249934 -1.169924)
			(stroke
				(width 0.1)
				(type default)
			)
			(layer "F.Fab")
		)
		(fp_line
			(start -0.6985 -0.729996)
			(end -1.249934 -0.729996)
			(stroke
				(width 0.1)
				(type default)
			)
			(layer "F.Fab")
		)
		(fp_line
			(start -1.249934 -1.169924)
			(end -0.6985 -1.169924)
			(stroke
				(width 0.1)
				(type default)
			)
			(layer "F.Fab")
		)
		(fp_line
			(start -0.6985 -1.169924)
			(end -0.6985 -1.524)
			(stroke
				(width 0.1)
				(type default)
			)
			(layer "F.Fab")
		)
		(fp_line
			(start -0.6985 -1.524)
			(end 0.6985 -1.524)
			(stroke
				(width 0.1)
				(type default)
			)
			(layer "F.Fab")
		)
		(fp_line
			(start 0.6985 -1.524)
			(end 0.6985 -0.219964)
			(stroke
				(width 0.1)
				(type default)
			)
			(layer "F.Fab")
		)
		(fp_rect
			(start -0.6985 1.524)
			(end 0.6985 -1.524)
			(stroke
				(width 0)
				(type default)
			)
			(fill no)
			(layer "F.Fab")
		)
		(pad "D" smd rect
			(at 1.1176 0 180)
			(size 1.016 1.27)
			(layers "F.Cu" "F.Mask" "F.Paste")
			(net "P12V_LED_FAN0")
		)
		(pad "G" smd rect
			(at -1.1176 -1.016 180)
			(size 1.016 1.27)
			(layers "F.Cu" "F.Mask" "F.Paste")
			(net "U405_D1")
		)
		(pad "S" smd rect
			(at -1.1176 1.016 180)
			(size 1.016 1.27)
			(layers "F.Cu" "F.Mask" "F.Paste")
			(net "P12V_LED")
		)
	)
	(footprint ""
		(layer "F.Cu")
		(at 38.6461 -132.588)
		(property "Reference" "R5577"
			(at 0 0 0)
			(layer "F.SilkS")
			(hide yes)
			(effects
				(font
					(size 1.27 1.27)
				)
			)
		)
		(property "Value" ""
			(at 0 0 0)
			(layer "F.Fab")
			(effects
				(font
					(size 1.27 1.27)
				)
			)
		)
		(duplicate_pad_numbers_are_jumpers no)
		(fp_line
			(start -0.7874 -0.4064)
			(end 0.7874 -0.4064)
			(stroke
				(width 0.1524)
				(type default)
			)
			(layer "F.SilkS")
		)
		(fp_line
			(start -0.7874 0.4064)
			(end -0.7874 -0.4064)
			(stroke
				(width 0.1524)
				(type default)
			)
			(layer "F.SilkS")
		)
		(fp_line
			(start 0.7874 -0.4064)
			(end 0.7874 0.4064)
			(stroke
				(width 0.1524)
				(type default)
			)
			(layer "F.SilkS")
		)
		(fp_line
			(start 0.7874 0.4064)
			(end -0.7874 0.4064)
			(stroke
				(width 0.1524)
				(type default)
			)
			(layer "F.SilkS")
		)
		(fp_line
			(start -0.67945 -0.305054)
			(end -0.12065 -0.305054)
			(stroke
				(width 0.1)
				(type default)
			)
			(layer "F.Fab")
		)
		(fp_line
			(start -0.67945 0.3048)
			(end -0.67945 -0.305054)
			(stroke
				(width 0.1)
				(type default)
			)
			(layer "F.Fab")
		)
		(fp_line
			(start -0.12065 -0.305054)
			(end -0.12065 -0.2794)
			(stroke
				(width 0.1)
				(type default)
			)
			(layer "F.Fab")
		)
		(fp_line
			(start -0.12065 -0.2794)
			(end 0.12065 -0.2794)
			(stroke
				(width 0.1)
				(type default)
			)
			(layer "F.Fab")
		)
		(fp_line
			(start -0.12065 0.2794)
			(end -0.12065 0.3048)
			(stroke
				(width 0.1)
				(type default)
			)
			(layer "F.Fab")
		)
		(fp_line
			(start -0.12065 0.3048)
			(end -0.67945 0.3048)
			(stroke
				(width 0.1)
				(type default)
			)
			(layer "F.Fab")
		)
		(fp_line
			(start 0.120396 0.2794)
			(end -0.12065 0.2794)
			(stroke
				(width 0.1)
				(type default)
			)
			(layer "F.Fab")
		)
		(fp_line
			(start 0.120396 0.3048)
			(end 0.120396 0.2794)
			(stroke
				(width 0.1)
				(type default)
			)
			(layer "F.Fab")
		)
		(fp_line
			(start 0.12065 -0.3048)
			(end 0.67945 -0.3048)
			(stroke
				(width 0.1)
				(type default)
			)
			(layer "F.Fab")
		)
		(fp_line
			(start 0.12065 -0.2794)
			(end 0.12065 -0.3048)
			(stroke
				(width 0.1)
				(type default)
			)
			(layer "F.Fab")
		)
		(fp_line
			(start 0.67945 -0.3048)
			(end 0.67945 0.3048)
			(stroke
				(width 0.1)
				(type default)
			)
			(layer "F.Fab")
		)
		(fp_line
			(start 0.67945 0.3048)
			(end 0.120396 0.3048)
			(stroke
				(width 0.1)
				(type default)
			)
			(layer "F.Fab")
		)
		(pad "1" smd rect
			(at -0.40005 0 180)
			(size 0.4572 0.508)
			(layers "F.Cu" "F.Mask" "F.Paste")
			(net "FAN_1_PWM")
		)
		(pad "2" smd rect
			(at 0.40005 0 180)
			(size 0.4572 0.508)
			(layers "F.Cu" "F.Mask" "F.Paste")
			(net "FAN_1_PWM_R2")
		)
	)
	(footprint ""
		(layer "F.Cu")
		(at 23.622 -133.985 90)
		(property "Reference" "R4947"
			(at 0 0 90)
			(layer "F.SilkS")
			(hide yes)
			(effects
				(font
					(size 1.27 1.27)
				)
			)
		)
		(property "Value" ""
			(at 0 0 90)
			(layer "F.Fab")
			(effects
				(font
					(size 1.27 1.27)
				)
			)
		)
		(duplicate_pad_numbers_are_jumpers no)
		(fp_line
			(start 0.7874 -0.4064)
			(end 0.7874 0.4064)
			(stroke
				(width 0.1524)
				(type default)
			)
			(layer "F.SilkS")
		)
		(fp_line
			(start -0.7874 -0.4064)
			(end 0.7874 -0.4064)
			(stroke
				(width 0.1524)
				(type default)
			)
			(layer "F.SilkS")
		)
		(fp_line
			(start 0.7874 0.4064)
			(end -0.7874 0.4064)
			(stroke
				(width 0.1524)
				(type default)
			)
			(layer "F.SilkS")
		)
		(fp_line
			(start -0.7874 0.4064)
			(end -0.7874 -0.4064)
			(stroke
				(width 0.1524)
				(type default)
			)
			(layer "F.SilkS")
		)
		(fp_line
			(start -0.12065 -0.305054)
			(end -0.12065 -0.2794)
			(stroke
				(width 0.1)
				(type default)
			)
			(layer "F.Fab")
		)
		(fp_line
			(start -0.67945 -0.305054)
			(end -0.12065 -0.305054)
			(stroke
				(width 0.1)
				(type default)
			)
			(layer "F.Fab")
		)
		(fp_line
			(start 0.67945 -0.3048)
			(end 0.67945 0.3048)
			(stroke
				(width 0.1)
				(type default)
			)
			(layer "F.Fab")
		)
		(fp_line
			(start 0.12065 -0.3048)
			(end 0.67945 -0.3048)
			(stroke
				(width 0.1)
				(type default)
			)
			(layer "F.Fab")
		)
		(fp_line
			(start 0.12065 -0.2794)
			(end 0.12065 -0.3048)
			(stroke
				(width 0.1)
				(type default)
			)
			(layer "F.Fab")
		)
		(fp_line
			(start -0.12065 -0.2794)
			(end 0.12065 -0.2794)
			(stroke
				(width 0.1)
				(type default)
			)
			(layer "F.Fab")
		)
		(fp_line
			(start 0.120396 0.2794)
			(end -0.12065 0.2794)
			(stroke
				(width 0.1)
				(type default)
			)
			(layer "F.Fab")
		)
		(fp_line
			(start -0.12065 0.2794)
			(end -0.12065 0.3048)
			(stroke
				(width 0.1)
				(type default)
			)
			(layer "F.Fab")
		)
		(fp_line
			(start 0.67945 0.3048)
			(end 0.120396 0.3048)
			(stroke
				(width 0.1)
				(type default)
			)
			(layer "F.Fab")
		)
		(fp_line
			(start 0.120396 0.3048)
			(end 0.120396 0.2794)
			(stroke
				(width 0.1)
				(type default)
			)
			(layer "F.Fab")
		)
		(fp_line
			(start -0.12065 0.3048)
			(end -0.67945 0.3048)
			(stroke
				(width 0.1)
				(type default)
			)
			(layer "F.Fab")
		)
		(fp_line
			(start -0.67945 0.3048)
			(end -0.67945 -0.305054)
			(stroke
				(width 0.1)
				(type default)
			)
			(layer "F.Fab")
		)
		(pad "1" smd circle
			(at -0.40005 0 90)
			(size 0 0)
			(layers "F.Cu" "F.Mask" "F.Paste")
			(net "MAX31790_U330_FREQ_START")
		)
		(pad "2" smd circle
			(at 0.40005 0 90)
			(size 0 0)
			(layers "F.Cu" "F.Mask" "F.Paste")
			(net "P3V3_AUX")
		)
	)
	(footprint ""
		(layer "F.Cu")
		(at 3.937 -312.674 -90)
		(property "Reference" "U412"
			(at 1.32588 2.00787 90)
			(unlocked yes)
			(layer "F.SilkS")
			(effects
				(font
					(size 0.7874 0.5842)
					(thickness 0.1524)
				)
				(justify left)
			)
		)
		(property "Value" ""
			(at 0 0 270)
			(layer "F.Fab")
			(effects
				(font
					(size 1.27 1.27)
				)
			)
		)
		(duplicate_pad_numbers_are_jumpers no)
		(fp_line
			(start -1.335278 1.100074)
			(end 1.335278 1.100074)
			(stroke
				(width 0.1524)
				(type default)
			)
			(layer "F.SilkS")
		)
		(fp_line
			(start 1.335278 1.100074)
			(end 1.335278 -1.100074)
			(stroke
				(width 0.1524)
				(type default)
			)
			(layer "F.SilkS")
		)
		(fp_line
			(start -1.335278 -1.100074)
			(end -1.335278 1.100074)
			(stroke
				(width 0.1524)
				(type default)
			)
			(layer "F.SilkS")
		)
		(fp_line
			(start 1.335278 -1.100074)
			(end -1.335278 -1.100074)
			(stroke
				(width 0.1524)
				(type default)
			)
			(layer "F.SilkS")
		)
		(fp_line
			(start -0.674878 1.100074)
			(end 0.674878 1.100074)
			(stroke
				(width 0.1)
				(type default)
			)
			(layer "F.Fab")
		)
		(fp_line
			(start 0.674878 1.100074)
			(end 0.674878 -1.100074)
			(stroke
				(width 0.1)
				(type default)
			)
			(layer "F.Fab")
		)
		(fp_line
			(start -0.674878 -1.100074)
			(end -0.674878 1.100074)
			(stroke
				(width 0.1)
				(type default)
			)
			(layer "F.Fab")
		)
		(fp_line
			(start 0.674878 -1.100074)
			(end -0.674878 -1.100074)
			(stroke
				(width 0.1)
				(type default)
			)
			(layer "F.Fab")
		)
		(pad "D" smd rect
			(at 0.8001 0 180)
			(size 0.6096 0.8128)
			(layers "F.Cu" "F.Mask" "F.Paste")
			(net "U412_D1")
		)
		(pad "G" smd rect
			(at -0.8001 -0.649986 180)
			(size 0.6096 0.8128)
			(layers "F.Cu" "F.Mask" "F.Paste")
			(net "FAN_7_PRESENT")
		)
		(pad "S" smd rect
			(at -0.8001 0.649986 180)
			(size 0.6096 0.8128)
			(layers "F.Cu" "F.Mask" "F.Paste")
			(net "GND")
		)
	)
	(footprint ""
		(layer "F.Cu")
		(at 38.6461 -136.398)
		(property "Reference" "R5574"
			(at 0 0 0)
			(layer "F.SilkS")
			(hide yes)
			(effects
				(font
					(size 1.27 1.27)
				)
			)
		)
		(property "Value" ""
			(at 0 0 0)
			(layer "F.Fab")
			(effects
				(font
					(size 1.27 1.27)
				)
			)
		)
		(duplicate_pad_numbers_are_jumpers no)
		(fp_line
			(start -0.7874 -0.4064)
			(end 0.7874 -0.4064)
			(stroke
				(width 0.1524)
				(type default)
			)
			(layer "F.SilkS")
		)
		(fp_line
			(start -0.7874 0.4064)
			(end -0.7874 -0.4064)
			(stroke
				(width 0.1524)
				(type default)
			)
			(layer "F.SilkS")
		)
		(fp_line
			(start 0.7874 -0.4064)
			(end 0.7874 0.4064)
			(stroke
				(width 0.1524)
				(type default)
			)
			(layer "F.SilkS")
		)
		(fp_line
			(start 0.7874 0.4064)
			(end -0.7874 0.4064)
			(stroke
				(width 0.1524)
				(type default)
			)
			(layer "F.SilkS")
		)
		(fp_line
			(start -0.67945 -0.305054)
			(end -0.12065 -0.305054)
			(stroke
				(width 0.1)
				(type default)
			)
			(layer "F.Fab")
		)
		(fp_line
			(start -0.67945 0.3048)
			(end -0.67945 -0.305054)
			(stroke
				(width 0.1)
				(type default)
			)
			(layer "F.Fab")
		)
		(fp_line
			(start -0.12065 -0.305054)
			(end -0.12065 -0.2794)
			(stroke
				(width 0.1)
				(type default)
			)
			(layer "F.Fab")
		)
		(fp_line
			(start -0.12065 -0.2794)
			(end 0.12065 -0.2794)
			(stroke
				(width 0.1)
				(type default)
			)
			(layer "F.Fab")
		)
		(fp_line
			(start -0.12065 0.2794)
			(end -0.12065 0.3048)
			(stroke
				(width 0.1)
				(type default)
			)
			(layer "F.Fab")
		)
		(fp_line
			(start -0.12065 0.3048)
			(end -0.67945 0.3048)
			(stroke
				(width 0.1)
				(type default)
			)
			(layer "F.Fab")
		)
		(fp_line
			(start 0.120396 0.2794)
			(end -0.12065 0.2794)
			(stroke
				(width 0.1)
				(type default)
			)
			(layer "F.Fab")
		)
		(fp_line
			(start 0.120396 0.3048)
			(end 0.120396 0.2794)
			(stroke
				(width 0.1)
				(type default)
			)
			(layer "F.Fab")
		)
		(fp_line
			(start 0.12065 -0.3048)
			(end 0.67945 -0.3048)
			(stroke
				(width 0.1)
				(type default)
			)
			(layer "F.Fab")
		)
		(fp_line
			(start 0.12065 -0.2794)
			(end 0.12065 -0.3048)
			(stroke
				(width 0.1)
				(type default)
			)
			(layer "F.Fab")
		)
		(fp_line
			(start 0.67945 -0.3048)
			(end 0.67945 0.3048)
			(stroke
				(width 0.1)
				(type default)
			)
			(layer "F.Fab")
		)
		(fp_line
			(start 0.67945 0.3048)
			(end 0.120396 0.3048)
			(stroke
				(width 0.1)
				(type default)
			)
			(layer "F.Fab")
		)
		(pad "1" smd rect
			(at -0.40005 0 180)
			(size 0.4572 0.508)
			(layers "F.Cu" "F.Mask" "F.Paste")
			(net "FAN_0_TACH_IL")
		)
		(pad "2" smd rect
			(at 0.40005 0 180)
			(size 0.4572 0.508)
			(layers "F.Cu" "F.Mask" "F.Paste")
			(net "FAN_0_TACH_IL_R2")
		)
	)
	(footprint ""
		(layer "F.Cu")
		(at 30.226 -124.206 -90)
		(property "Reference" "R4938"
			(at 0 0 270)
			(layer "F.SilkS")
			(hide yes)
			(effects
				(font
					(size 1.27 1.27)
				)
			)
		)
		(property "Value" ""
			(at 0 0 270)
			(layer "F.Fab")
			(effects
				(font
					(size 1.27 1.27)
				)
			)
		)
		(duplicate_pad_numbers_are_jumpers no)
		(fp_line
			(start -0.7874 0.4064)
			(end -0.7874 -0.4064)
			(stroke
				(width 0.1524)
				(type default)
			)
			(layer "F.SilkS")
		)
		(fp_line
			(start 0.7874 0.4064)
			(end -0.7874 0.4064)
			(stroke
				(width 0.1524)
				(type default)
			)
			(layer "F.SilkS")
		)
		(fp_line
			(start -0.7874 -0.4064)
			(end 0.7874 -0.4064)
			(stroke
				(width 0.1524)
				(type default)
			)
			(layer "F.SilkS")
		)
		(fp_line
			(start 0.7874 -0.4064)
			(end 0.7874 0.4064)
			(stroke
				(width 0.1524)
				(type default)
			)
			(layer "F.SilkS")
		)
		(fp_line
			(start -0.67945 0.3048)
			(end -0.67945 -0.305054)
			(stroke
				(width 0.1)
				(type default)
			)
			(layer "F.Fab")
		)
		(fp_line
			(start -0.12065 0.3048)
			(end -0.67945 0.3048)
			(stroke
				(width 0.1)
				(type default)
			)
			(layer "F.Fab")
		)
		(fp_line
			(start 0.120396 0.3048)
			(end 0.120396 0.2794)
			(stroke
				(width 0.1)
				(type default)
			)
			(layer "F.Fab")
		)
		(fp_line
			(start 0.67945 0.3048)
			(end 0.120396 0.3048)
			(stroke
				(width 0.1)
				(type default)
			)
			(layer "F.Fab")
		)
		(fp_line
			(start -0.12065 0.2794)
			(end -0.12065 0.3048)
			(stroke
				(width 0.1)
				(type default)
			)
			(layer "F.Fab")
		)
		(fp_line
			(start 0.120396 0.2794)
			(end -0.12065 0.2794)
			(stroke
				(width 0.1)
				(type default)
			)
			(layer "F.Fab")
		)
		(fp_line
			(start -0.12065 -0.2794)
			(end 0.12065 -0.2794)
			(stroke
				(width 0.1)
				(type default)
			)
			(layer "F.Fab")
		)
		(fp_line
			(start 0.12065 -0.2794)
			(end 0.12065 -0.3048)
			(stroke
				(width 0.1)
				(type default)
			)
			(layer "F.Fab")
		)
		(fp_line
			(start 0.12065 -0.3048)
			(end 0.67945 -0.3048)
			(stroke
				(width 0.1)
				(type default)
			)
			(layer "F.Fab")
		)
		(fp_line
			(start 0.67945 -0.3048)
			(end 0.67945 0.3048)
			(stroke
				(width 0.1)
				(type default)
			)
			(layer "F.Fab")
		)
		(fp_line
			(start -0.67945 -0.305054)
			(end -0.12065 -0.305054)
			(stroke
				(width 0.1)
				(type default)
			)
			(layer "F.Fab")
		)
		(fp_line
			(start -0.12065 -0.305054)
			(end -0.12065 -0.2794)
			(stroke
				(width 0.1)
				(type default)
			)
			(layer "F.Fab")
		)
		(pad "1" smd circle
			(at -0.40005 0 270)
			(size 0 0)
			(layers "F.Cu" "F.Mask" "F.Paste")
			(net "MAX31790_U317_SPIN_START")
		)
		(pad "2" smd circle
			(at 0.40005 0 270)
			(size 0 0)
			(layers "F.Cu" "F.Mask" "F.Paste")
			(net "P3V3_AUX")
		)
	)
	(footprint ""
		(layer "F.Cu")
		(at 25.527 -179.451 180)
		(property "Reference" "C2081"
			(at 0 0 180)
			(layer "F.SilkS")
			(hide yes)
			(effects
				(font
					(size 1.27 1.27)
				)
			)
		)
		(property "Value" ""
			(at 0 0 180)
			(layer "F.Fab")
			(effects
				(font
					(size 1.27 1.27)
				)
			)
		)
		(duplicate_pad_numbers_are_jumpers no)
		(fp_line
			(start 0.7874 0.4064)
			(end -0.7874 0.4064)
			(stroke
				(width 0.1524)
				(type default)
			)
			(layer "F.SilkS")
		)
		(fp_line
			(start 0.7874 -0.4064)
			(end 0.7874 0.4064)
			(stroke
				(width 0.1524)
				(type default)
			)
			(layer "F.SilkS")
		)
		(fp_line
			(start -0.7874 0.4064)
			(end -0.7874 -0.4064)
			(stroke
				(width 0.1524)
				(type default)
			)
			(layer "F.SilkS")
		)
		(fp_line
			(start -0.7874 -0.4064)
			(end 0.7874 -0.4064)
			(stroke
				(width 0.1524)
				(type default)
			)
			(layer "F.SilkS")
		)
		(fp_line
			(start 0.67945 0.3048)
			(end 0.120396 0.3048)
			(stroke
				(width 0.1)
				(type default)
			)
			(layer "F.Fab")
		)
		(fp_line
			(start 0.67945 -0.3048)
			(end 0.67945 0.3048)
			(stroke
				(width 0.1)
				(type default)
			)
			(layer "F.Fab")
		)
		(fp_line
			(start 0.12065 -0.2794)
			(end 0.12065 -0.3048)
			(stroke
				(width 0.1)
				(type default)
			)
			(layer "F.Fab")
		)
		(fp_line
			(start 0.12065 -0.3048)
			(end 0.67945 -0.3048)
			(stroke
				(width 0.1)
				(type default)
			)
			(layer "F.Fab")
		)
		(fp_line
			(start 0.120396 0.3048)
			(end 0.120396 0.2794)
			(stroke
				(width 0.1)
				(type default)
			)
			(layer "F.Fab")
		)
		(fp_line
			(start 0.120396 0.2794)
			(end -0.12065 0.2794)
			(stroke
				(width 0.1)
				(type default)
			)
			(layer "F.Fab")
		)
		(fp_line
			(start -0.12065 0.3048)
			(end -0.67945 0.3048)
			(stroke
				(width 0.1)
				(type default)
			)
			(layer "F.Fab")
		)
		(fp_line
			(start -0.12065 0.2794)
			(end -0.12065 0.3048)
			(stroke
				(width 0.1)
				(type default)
			)
			(layer "F.Fab")
		)
		(fp_line
			(start -0.12065 -0.2794)
			(end 0.12065 -0.2794)
			(stroke
				(width 0.1)
				(type default)
			)
			(layer "F.Fab")
		)
		(fp_line
			(start -0.12065 -0.305054)
			(end -0.12065 -0.2794)
			(stroke
				(width 0.1)
				(type default)
			)
			(layer "F.Fab")
		)
		(fp_line
			(start -0.67945 0.3048)
			(end -0.67945 -0.305054)
			(stroke
				(width 0.1)
				(type default)
			)
			(layer "F.Fab")
		)
		(fp_line
			(start -0.67945 -0.305054)
			(end -0.12065 -0.305054)
			(stroke
				(width 0.1)
				(type default)
			)
			(layer "F.Fab")
		)
		(pad "1" smd circle
			(at -0.40005 0 180)
			(size 0 0)
			(layers "F.Cu" "F.Mask" "F.Paste")
			(net "P52V_FAN_2_BUFF_EN_R")
		)
		(pad "2" smd circle
			(at 0.40005 0 180)
			(size 0 0)
			(layers "F.Cu" "F.Mask" "F.Paste")
			(net "GND")
		)
	)
	(footprint ""
		(layer "F.Cu")
		(at 37.338 -289.941)
		(property "Reference" "D264"
			(at 1.905 0.02667 0)
			(unlocked yes)
			(layer "F.SilkS")
			(effects
				(font
					(size 0.7874 0.5842)
					(thickness 0.1524)
				)
				(justify left)
			)
		)
		(property "Value" ""
			(at 0 0 0)
			(layer "F.Fab")
			(effects
				(font
					(size 1.27 1.27)
				)
			)
		)
		(duplicate_pad_numbers_are_jumpers no)
		(fp_line
			(start -0.854964 -0.450088)
			(end -0.854964 0.450088)
			(stroke
				(width 0.1524)
				(type default)
			)
			(layer "F.SilkS")
		)
		(fp_line
			(start -0.854964 0.450088)
			(end 0.925068 0.450088)
			(stroke
				(width 0.1524)
				(type default)
			)
			(layer "F.SilkS")
		)
		(fp_line
			(start 0.845058 0.4064)
			(end 0.845058 -0.381)
			(stroke
				(width 0.1524)
				(type default)
			)
			(layer "F.SilkS")
		)
		(fp_line
			(start 0.870458 -0.2794)
			(end 0.845058 0.4064)
			(stroke
				(width 0.1524)
				(type default)
			)
			(layer "F.SilkS")
		)
		(fp_line
			(start 0.94488 -0.450088)
			(end -0.854964 -0.450088)
			(stroke
				(width 0.1524)
				(type default)
			)
			(layer "F.SilkS")
		)
		(fp_line
			(start 0.94488 0.450088)
			(end 0.94488 -0.450088)
			(stroke
				(width 0.1524)
				(type default)
			)
			(layer "F.SilkS")
		)
		(fp_line
			(start -0.54991 -0.350012)
			(end -0.54991 0.350012)
			(stroke
				(width 0.1)
				(type default)
			)
			(layer "F.Fab")
		)
		(fp_line
			(start -0.54991 0.350012)
			(end 0.54991 0.350012)
			(stroke
				(width 0.1)
				(type default)
			)
			(layer "F.Fab")
		)
		(fp_line
			(start 0.54991 -0.350012)
			(end -0.54991 -0.350012)
			(stroke
				(width 0.1)
				(type default)
			)
			(layer "F.Fab")
		)
		(fp_line
			(start 0.54991 0.350012)
			(end 0.54991 -0.350012)
			(stroke
				(width 0.1)
				(type default)
			)
			(layer "F.Fab")
		)
		(fp_text user "+"
			(at -2.00025 1.143 90)
			(unlocked yes)
			(layer "F.SilkS")
			(effects
				(font
					(size 1.905 1.4224)
					(thickness 0.1524)
				)
				(justify left)
			)
		)
		(fp_text user "-"
			(at 2.159 0.22225 180)
			(unlocked yes)
			(layer "F.SilkS")
			(effects
				(font
					(size 1.905 1.4224)
					(thickness 0.1524)
				)
				(justify left)
			)
		)
		(fp_text user "+"
			(at -0.808228 0.239014 180)
			(unlocked yes)
			(layer "F.Fab")
			(effects
				(font
					(size 1.905 1.4224)
					(thickness 0.1524)
				)
				(justify left)
			)
		)
		(fp_text user "-"
			(at 2.48539 0.239014 180)
			(unlocked yes)
			(layer "F.Fab")
			(effects
				(font
					(size 1.905 1.4224)
					(thickness 0.1524)
				)
				(justify left)
			)
		)
		(pad "A" smd rect
			(at -0.424942 0)
			(size 0.5588 0.6096)
			(layers "F.Cu" "F.Mask" "F.Paste")
			(net "GND")
		)
		(pad "C" smd rect
			(at 0.424942 0 180)
			(size 0.5588 0.6096)
			(layers "F.Cu" "F.Mask" "F.Paste")
			(net "FAN_0_OK_R_LED_N")
		)
	)
	(footprint ""
		(layer "F.Cu")
		(at 47.879 -124.46 180)
		(property "Reference" "C2037"
			(at 0 0 180)
			(layer "F.SilkS")
			(hide yes)
			(effects
				(font
					(size 1.27 1.27)
				)
			)
		)
		(property "Value" ""
			(at 0 0 180)
			(layer "F.Fab")
			(effects
				(font
					(size 1.27 1.27)
				)
			)
		)
		(duplicate_pad_numbers_are_jumpers no)
		(fp_line
			(start 0.7874 0.4064)
			(end -0.7874 0.4064)
			(stroke
				(width 0.1524)
				(type default)
			)
			(layer "F.SilkS")
		)
		(fp_line
			(start 0.7874 -0.4064)
			(end 0.7874 0.4064)
			(stroke
				(width 0.1524)
				(type default)
			)
			(layer "F.SilkS")
		)
		(fp_line
			(start -0.7874 0.4064)
			(end -0.7874 -0.4064)
			(stroke
				(width 0.1524)
				(type default)
			)
			(layer "F.SilkS")
		)
		(fp_line
			(start -0.7874 -0.4064)
			(end 0.7874 -0.4064)
			(stroke
				(width 0.1524)
				(type default)
			)
			(layer "F.SilkS")
		)
		(fp_line
			(start 0.6858 0.3048)
			(end 0.1016 0.3048)
			(stroke
				(width 0.1)
				(type default)
			)
			(layer "F.Fab")
		)
		(fp_line
			(start 0.6858 -0.3048)
			(end 0.6858 0.3048)
			(stroke
				(width 0.1)
				(type default)
			)
			(layer "F.Fab")
		)
		(fp_line
			(start 0.1016 0.3048)
			(end 0.1016 0.2794)
			(stroke
				(width 0.1)
				(type default)
			)
			(layer "F.Fab")
		)
		(fp_line
			(start 0.1016 0.2794)
			(end -0.1016 0.2794)
			(stroke
				(width 0.1)
				(type default)
			)
			(layer "F.Fab")
		)
		(fp_line
			(start 0.1016 -0.2794)
			(end 0.1016 -0.3048)
			(stroke
				(width 0.1)
				(type default)
			)
			(layer "F.Fab")
		)
		(fp_line
			(start 0.1016 -0.3048)
			(end 0.6858 -0.3048)
			(stroke
				(width 0.1)
				(type default)
			)
			(layer "F.Fab")
		)
		(fp_line
			(start -0.1016 0.3048)
			(end -0.6858 0.3048)
			(stroke
				(width 0.1)
				(type default)
			)
			(layer "F.Fab")
		)
		(fp_line
			(start -0.1016 0.2794)
			(end -0.1016 0.3048)
			(stroke
				(width 0.1)
				(type default)
			)
			(layer "F.Fab")
		)
		(fp_line
			(start -0.1016 -0.2794)
			(end 0.1016 -0.2794)
			(stroke
				(width 0.1)
				(type default)
			)
			(layer "F.Fab")
		)
		(fp_line
			(start -0.1016 -0.3048)
			(end -0.1016 -0.2794)
			(stroke
				(width 0.1)
				(type default)
			)
			(layer "F.Fab")
		)
		(fp_line
			(start -0.6858 0.3048)
			(end -0.6858 -0.3048)
			(stroke
				(width 0.1)
				(type default)
			)
			(layer "F.Fab")
		)
		(fp_line
			(start -0.6858 -0.3048)
			(end -0.1016 -0.3048)
			(stroke
				(width 0.1)
				(type default)
			)
			(layer "F.Fab")
		)
		(pad "1" smd rect
			(at -0.40005 0)
			(size 0.4572 0.508)
			(layers "F.Cu" "F.Mask" "F.Paste")
			(net "GND")
		)
		(pad "2" smd rect
			(at 0.40005 0)
			(size 0.4572 0.508)
			(layers "F.Cu" "F.Mask" "F.Paste")
			(net "P12V_LED_FAN2")
		)
	)
	(footprint ""
		(layer "F.Cu")
		(at 14.732 -260.096 180)
		(property "Reference" "PR75"
			(at 0 0 180)
			(layer "F.SilkS")
			(hide yes)
			(effects
				(font
					(size 1.27 1.27)
				)
			)
		)
		(property "Value" ""
			(at 0 0 180)
			(layer "F.Fab")
			(effects
				(font
					(size 1.27 1.27)
				)
			)
		)
		(duplicate_pad_numbers_are_jumpers no)
		(fp_line
			(start 0.7874 0.4064)
			(end -0.7874 0.4064)
			(stroke
				(width 0.1524)
				(type default)
			)
			(layer "F.SilkS")
		)
		(fp_line
			(start 0.7874 -0.4064)
			(end 0.7874 0.4064)
			(stroke
				(width 0.1524)
				(type default)
			)
			(layer "F.SilkS")
		)
		(fp_line
			(start -0.7874 0.4064)
			(end -0.7874 -0.4064)
			(stroke
				(width 0.1524)
				(type default)
			)
			(layer "F.SilkS")
		)
		(fp_line
			(start -0.7874 -0.4064)
			(end 0.7874 -0.4064)
			(stroke
				(width 0.1524)
				(type default)
			)
			(layer "F.SilkS")
		)
		(fp_line
			(start 0.67945 0.3048)
			(end 0.120396 0.3048)
			(stroke
				(width 0.1)
				(type default)
			)
			(layer "F.Fab")
		)
		(fp_line
			(start 0.67945 -0.3048)
			(end 0.67945 0.3048)
			(stroke
				(width 0.1)
				(type default)
			)
			(layer "F.Fab")
		)
		(fp_line
			(start 0.12065 -0.2794)
			(end 0.12065 -0.3048)
			(stroke
				(width 0.1)
				(type default)
			)
			(layer "F.Fab")
		)
		(fp_line
			(start 0.12065 -0.3048)
			(end 0.67945 -0.3048)
			(stroke
				(width 0.1)
				(type default)
			)
			(layer "F.Fab")
		)
		(fp_line
			(start 0.120396 0.3048)
			(end 0.120396 0.2794)
			(stroke
				(width 0.1)
				(type default)
			)
			(layer "F.Fab")
		)
		(fp_line
			(start 0.120396 0.2794)
			(end -0.12065 0.2794)
			(stroke
				(width 0.1)
				(type default)
			)
			(layer "F.Fab")
		)
		(fp_line
			(start -0.12065 0.3048)
			(end -0.67945 0.3048)
			(stroke
				(width 0.1)
				(type default)
			)
			(layer "F.Fab")
		)
		(fp_line
			(start -0.12065 0.2794)
			(end -0.12065 0.3048)
			(stroke
				(width 0.1)
				(type default)
			)
			(layer "F.Fab")
		)
		(fp_line
			(start -0.12065 -0.2794)
			(end 0.12065 -0.2794)
			(stroke
				(width 0.1)
				(type default)
			)
			(layer "F.Fab")
		)
		(fp_line
			(start -0.12065 -0.305054)
			(end -0.12065 -0.2794)
			(stroke
				(width 0.1)
				(type default)
			)
			(layer "F.Fab")
		)
		(fp_line
			(start -0.67945 0.3048)
			(end -0.67945 -0.305054)
			(stroke
				(width 0.1)
				(type default)
			)
			(layer "F.Fab")
		)
		(fp_line
			(start -0.67945 -0.305054)
			(end -0.12065 -0.305054)
			(stroke
				(width 0.1)
				(type default)
			)
			(layer "F.Fab")
		)
		(pad "1" smd circle
			(at -0.40005 0 180)
			(size 0 0)
			(layers "F.Cu" "F.Mask" "F.Paste")
			(net "FAN_7_MODE")
		)
		(pad "2" smd circle
			(at 0.40005 0 180)
			(size 0 0)
			(layers "F.Cu" "F.Mask" "F.Paste")
			(net "GND")
		)
	)
	(footprint ""
		(layer "F.Cu")
		(at 45.085 -182.88 180)
		(property "Reference" "R521"
			(at 0 0 180)
			(layer "F.SilkS")
			(hide yes)
			(effects
				(font
					(size 1.27 1.27)
				)
			)
		)
		(property "Value" ""
			(at 0 0 180)
			(layer "F.Fab")
			(effects
				(font
					(size 1.27 1.27)
				)
			)
		)
		(duplicate_pad_numbers_are_jumpers no)
		(fp_line
			(start 0.7874 0.4064)
			(end -0.7874 0.4064)
			(stroke
				(width 0.1524)
				(type default)
			)
			(layer "F.SilkS")
		)
		(fp_line
			(start 0.7874 -0.4064)
			(end 0.7874 0.4064)
			(stroke
				(width 0.1524)
				(type default)
			)
			(layer "F.SilkS")
		)
		(fp_line
			(start -0.7874 0.4064)
			(end -0.7874 -0.4064)
			(stroke
				(width 0.1524)
				(type default)
			)
			(layer "F.SilkS")
		)
		(fp_line
			(start -0.7874 -0.4064)
			(end 0.7874 -0.4064)
			(stroke
				(width 0.1524)
				(type default)
			)
			(layer "F.SilkS")
		)
		(fp_line
			(start 0.67945 0.3048)
			(end 0.120396 0.3048)
			(stroke
				(width 0.1)
				(type default)
			)
			(layer "F.Fab")
		)
		(fp_line
			(start 0.67945 -0.3048)
			(end 0.67945 0.3048)
			(stroke
				(width 0.1)
				(type default)
			)
			(layer "F.Fab")
		)
		(fp_line
			(start 0.12065 -0.2794)
			(end 0.12065 -0.3048)
			(stroke
				(width 0.1)
				(type default)
			)
			(layer "F.Fab")
		)
		(fp_line
			(start 0.12065 -0.3048)
			(end 0.67945 -0.3048)
			(stroke
				(width 0.1)
				(type default)
			)
			(layer "F.Fab")
		)
		(fp_line
			(start 0.120396 0.3048)
			(end 0.120396 0.2794)
			(stroke
				(width 0.1)
				(type default)
			)
			(layer "F.Fab")
		)
		(fp_line
			(start 0.120396 0.2794)
			(end -0.12065 0.2794)
			(stroke
				(width 0.1)
				(type default)
			)
			(layer "F.Fab")
		)
		(fp_line
			(start -0.12065 0.3048)
			(end -0.67945 0.3048)
			(stroke
				(width 0.1)
				(type default)
			)
			(layer "F.Fab")
		)
		(fp_line
			(start -0.12065 0.2794)
			(end -0.12065 0.3048)
			(stroke
				(width 0.1)
				(type default)
			)
			(layer "F.Fab")
		)
		(fp_line
			(start -0.12065 -0.2794)
			(end 0.12065 -0.2794)
			(stroke
				(width 0.1)
				(type default)
			)
			(layer "F.Fab")
		)
		(fp_line
			(start -0.12065 -0.305054)
			(end -0.12065 -0.2794)
			(stroke
				(width 0.1)
				(type default)
			)
			(layer "F.Fab")
		)
		(fp_line
			(start -0.67945 0.3048)
			(end -0.67945 -0.305054)
			(stroke
				(width 0.1)
				(type default)
			)
			(layer "F.Fab")
		)
		(fp_line
			(start -0.67945 -0.305054)
			(end -0.12065 -0.305054)
			(stroke
				(width 0.1)
				(type default)
			)
			(layer "F.Fab")
		)
		(pad "1" smd circle
			(at -0.40005 0 180)
			(size 0 0)
			(layers "F.Cu" "F.Mask" "F.Paste")
			(net "GND")
		)
		(pad "2" smd circle
			(at 0.40005 0 180)
			(size 0 0)
			(layers "F.Cu" "F.Mask" "F.Paste")
			(net "PD_FAN_BUFF_INPUT_U336F")
		)
	)
	(footprint ""
		(layer "F.Cu")
		(at 17.399 -114.681 180)
		(property "Reference" "U362"
			(at -1.651 -1.55067 0)
			(unlocked yes)
			(layer "F.SilkS")
			(effects
				(font
					(size 0.7874 0.5842)
					(thickness 0.1524)
				)
				(justify left)
			)
		)
		(property "Value" ""
			(at 0 0 180)
			(layer "F.Fab")
			(effects
				(font
					(size 1.27 1.27)
				)
			)
		)
		(duplicate_pad_numbers_are_jumpers no)
		(fp_line
			(start 1.335278 1.100074)
			(end 1.335278 -1.100074)
			(stroke
				(width 0.1524)
				(type default)
			)
			(layer "F.SilkS")
		)
		(fp_line
			(start 1.335278 -1.100074)
			(end -1.335278 -1.100074)
			(stroke
				(width 0.1524)
				(type default)
			)
			(layer "F.SilkS")
		)
		(fp_line
			(start -1.335278 1.100074)
			(end 1.335278 1.100074)
			(stroke
				(width 0.1524)
				(type default)
			)
			(layer "F.SilkS")
		)
		(fp_line
			(start -1.335278 -1.100074)
			(end -1.335278 1.100074)
			(stroke
				(width 0.1524)
				(type default)
			)
			(layer "F.SilkS")
		)
		(fp_line
			(start 0.674878 1.100074)
			(end 0.674878 -1.100074)
			(stroke
				(width 0.1)
				(type default)
			)
			(layer "F.Fab")
		)
		(fp_line
			(start 0.674878 -1.100074)
			(end -0.674878 -1.100074)
			(stroke
				(width 0.1)
				(type default)
			)
			(layer "F.Fab")
		)
		(fp_line
			(start -0.674878 1.100074)
			(end 0.674878 1.100074)
			(stroke
				(width 0.1)
				(type default)
			)
			(layer "F.Fab")
		)
		(fp_line
			(start -0.674878 -1.100074)
			(end -0.674878 1.100074)
			(stroke
				(width 0.1)
				(type default)
			)
			(layer "F.Fab")
		)
		(pad "D" smd rect
			(at 0.8001 0 90)
			(size 0.6096 0.8128)
			(layers "F.Cu" "F.Mask" "F.Paste")
			(net "FAN_5_OK_LED_R_N")
		)
		(pad "G" smd rect
			(at -0.8001 -0.649986 90)
			(size 0.6096 0.8128)
			(layers "F.Cu" "F.Mask" "F.Paste")
			(net "FAN_5_OK_R_LED")
		)
		(pad "S" smd rect
			(at -0.8001 0.649986 90)
			(size 0.6096 0.8128)
			(layers "F.Cu" "F.Mask" "F.Paste")
			(net "GND")
		)
	)
	(footprint ""
		(layer "F.Cu")
		(at 43.561 -171.831)
		(property "Reference" "R5096"
			(at 0 0 0)
			(layer "F.SilkS")
			(hide yes)
			(effects
				(font
					(size 1.27 1.27)
				)
			)
		)
		(property "Value" ""
			(at 0 0 0)
			(layer "F.Fab")
			(effects
				(font
					(size 1.27 1.27)
				)
			)
		)
		(duplicate_pad_numbers_are_jumpers no)
		(fp_line
			(start -0.7874 -0.4064)
			(end 0.7874 -0.4064)
			(stroke
				(width 0.1524)
				(type default)
			)
			(layer "F.SilkS")
		)
		(fp_line
			(start -0.7874 0.4064)
			(end -0.7874 -0.4064)
			(stroke
				(width 0.1524)
				(type default)
			)
			(layer "F.SilkS")
		)
		(fp_line
			(start 0.7874 -0.4064)
			(end 0.7874 0.4064)
			(stroke
				(width 0.1524)
				(type default)
			)
			(layer "F.SilkS")
		)
		(fp_line
			(start 0.7874 0.4064)
			(end -0.7874 0.4064)
			(stroke
				(width 0.1524)
				(type default)
			)
			(layer "F.SilkS")
		)
		(fp_line
			(start -0.67945 -0.305054)
			(end -0.12065 -0.305054)
			(stroke
				(width 0.1)
				(type default)
			)
			(layer "F.Fab")
		)
		(fp_line
			(start -0.67945 0.3048)
			(end -0.67945 -0.305054)
			(stroke
				(width 0.1)
				(type default)
			)
			(layer "F.Fab")
		)
		(fp_line
			(start -0.12065 -0.305054)
			(end -0.12065 -0.2794)
			(stroke
				(width 0.1)
				(type default)
			)
			(layer "F.Fab")
		)
		(fp_line
			(start -0.12065 -0.2794)
			(end 0.12065 -0.2794)
			(stroke
				(width 0.1)
				(type default)
			)
			(layer "F.Fab")
		)
		(fp_line
			(start -0.12065 0.2794)
			(end -0.12065 0.3048)
			(stroke
				(width 0.1)
				(type default)
			)
			(layer "F.Fab")
		)
		(fp_line
			(start -0.12065 0.3048)
			(end -0.67945 0.3048)
			(stroke
				(width 0.1)
				(type default)
			)
			(layer "F.Fab")
		)
		(fp_line
			(start 0.120396 0.2794)
			(end -0.12065 0.2794)
			(stroke
				(width 0.1)
				(type default)
			)
			(layer "F.Fab")
		)
		(fp_line
			(start 0.120396 0.3048)
			(end 0.120396 0.2794)
			(stroke
				(width 0.1)
				(type default)
			)
			(layer "F.Fab")
		)
		(fp_line
			(start 0.12065 -0.3048)
			(end 0.67945 -0.3048)
			(stroke
				(width 0.1)
				(type default)
			)
			(layer "F.Fab")
		)
		(fp_line
			(start 0.12065 -0.2794)
			(end 0.12065 -0.3048)
			(stroke
				(width 0.1)
				(type default)
			)
			(layer "F.Fab")
		)
		(fp_line
			(start 0.67945 -0.3048)
			(end 0.67945 0.3048)
			(stroke
				(width 0.1)
				(type default)
			)
			(layer "F.Fab")
		)
		(fp_line
			(start 0.67945 0.3048)
			(end 0.120396 0.3048)
			(stroke
				(width 0.1)
				(type default)
			)
			(layer "F.Fab")
		)
		(pad "1" smd circle
			(at -0.40005 0)
			(size 0 0)
			(layers "F.Cu" "F.Mask" "F.Paste")
			(net "FAN_1_OK_LED")
		)
		(pad "2" smd circle
			(at 0.40005 0)
			(size 0 0)
			(layers "F.Cu" "F.Mask" "F.Paste")
			(net "FAN_1_OK_R_LED")
		)
	)
	(footprint ""
		(layer "F.Cu")
		(at 34.798 -193.548)
		(property "Reference" "C2031"
			(at 0 0 0)
			(layer "F.SilkS")
			(hide yes)
			(effects
				(font
					(size 1.27 1.27)
				)
			)
		)
		(property "Value" ""
			(at 0 0 0)
			(layer "F.Fab")
			(effects
				(font
					(size 1.27 1.27)
				)
			)
		)
		(duplicate_pad_numbers_are_jumpers no)
		(fp_line
			(start -0.7874 -0.4064)
			(end 0.7874 -0.4064)
			(stroke
				(width 0.1524)
				(type default)
			)
			(layer "F.SilkS")
		)
		(fp_line
			(start -0.7874 0.4064)
			(end -0.7874 -0.4064)
			(stroke
				(width 0.1524)
				(type default)
			)
			(layer "F.SilkS")
		)
		(fp_line
			(start 0.7874 -0.4064)
			(end 0.7874 0.4064)
			(stroke
				(width 0.1524)
				(type default)
			)
			(layer "F.SilkS")
		)
		(fp_line
			(start 0.7874 0.4064)
			(end -0.7874 0.4064)
			(stroke
				(width 0.1524)
				(type default)
			)
			(layer "F.SilkS")
		)
		(fp_line
			(start -0.67945 -0.305054)
			(end -0.12065 -0.305054)
			(stroke
				(width 0.1)
				(type default)
			)
			(layer "F.Fab")
		)
		(fp_line
			(start -0.67945 0.3048)
			(end -0.67945 -0.305054)
			(stroke
				(width 0.1)
				(type default)
			)
			(layer "F.Fab")
		)
		(fp_line
			(start -0.12065 -0.305054)
			(end -0.12065 -0.2794)
			(stroke
				(width 0.1)
				(type default)
			)
			(layer "F.Fab")
		)
		(fp_line
			(start -0.12065 -0.2794)
			(end 0.12065 -0.2794)
			(stroke
				(width 0.1)
				(type default)
			)
			(layer "F.Fab")
		)
		(fp_line
			(start -0.12065 0.2794)
			(end -0.12065 0.3048)
			(stroke
				(width 0.1)
				(type default)
			)
			(layer "F.Fab")
		)
		(fp_line
			(start -0.12065 0.3048)
			(end -0.67945 0.3048)
			(stroke
				(width 0.1)
				(type default)
			)
			(layer "F.Fab")
		)
		(fp_line
			(start 0.120396 0.2794)
			(end -0.12065 0.2794)
			(stroke
				(width 0.1)
				(type default)
			)
			(layer "F.Fab")
		)
		(fp_line
			(start 0.120396 0.3048)
			(end 0.120396 0.2794)
			(stroke
				(width 0.1)
				(type default)
			)
			(layer "F.Fab")
		)
		(fp_line
			(start 0.12065 -0.3048)
			(end 0.67945 -0.3048)
			(stroke
				(width 0.1)
				(type default)
			)
			(layer "F.Fab")
		)
		(fp_line
			(start 0.12065 -0.2794)
			(end 0.12065 -0.3048)
			(stroke
				(width 0.1)
				(type default)
			)
			(layer "F.Fab")
		)
		(fp_line
			(start 0.67945 -0.3048)
			(end 0.67945 0.3048)
			(stroke
				(width 0.1)
				(type default)
			)
			(layer "F.Fab")
		)
		(fp_line
			(start 0.67945 0.3048)
			(end 0.120396 0.3048)
			(stroke
				(width 0.1)
				(type default)
			)
			(layer "F.Fab")
		)
		(pad "1" smd circle
			(at -0.40005 0)
			(size 0 0)
			(layers "F.Cu" "F.Mask" "F.Paste")
			(net "FAN_1_TACH_OL_R")
		)
		(pad "2" smd circle
			(at 0.40005 0)
			(size 0 0)
			(layers "F.Cu" "F.Mask" "F.Paste")
			(net "GND")
		)
	)
	(footprint ""
		(layer "F.Cu")
		(at 27.432 -187.452 180)
		(property "Reference" "R5492"
			(at 0 0 180)
			(layer "F.SilkS")
			(hide yes)
			(effects
				(font
					(size 1.27 1.27)
				)
			)
		)
		(property "Value" ""
			(at 0 0 180)
			(layer "F.Fab")
			(effects
				(font
					(size 1.27 1.27)
				)
			)
		)
		(duplicate_pad_numbers_are_jumpers no)
		(fp_line
			(start 0.7874 0.4064)
			(end -0.7874 0.4064)
			(stroke
				(width 0.1524)
				(type default)
			)
			(layer "F.SilkS")
		)
		(fp_line
			(start 0.7874 -0.4064)
			(end 0.7874 0.4064)
			(stroke
				(width 0.1524)
				(type default)
			)
			(layer "F.SilkS")
		)
		(fp_line
			(start -0.7874 0.4064)
			(end -0.7874 -0.4064)
			(stroke
				(width 0.1524)
				(type default)
			)
			(layer "F.SilkS")
		)
		(fp_line
			(start -0.7874 -0.4064)
			(end 0.7874 -0.4064)
			(stroke
				(width 0.1524)
				(type default)
			)
			(layer "F.SilkS")
		)
		(fp_line
			(start 0.67945 0.3048)
			(end 0.120396 0.3048)
			(stroke
				(width 0.1)
				(type default)
			)
			(layer "F.Fab")
		)
		(fp_line
			(start 0.67945 -0.3048)
			(end 0.67945 0.3048)
			(stroke
				(width 0.1)
				(type default)
			)
			(layer "F.Fab")
		)
		(fp_line
			(start 0.12065 -0.2794)
			(end 0.12065 -0.3048)
			(stroke
				(width 0.1)
				(type default)
			)
			(layer "F.Fab")
		)
		(fp_line
			(start 0.12065 -0.3048)
			(end 0.67945 -0.3048)
			(stroke
				(width 0.1)
				(type default)
			)
			(layer "F.Fab")
		)
		(fp_line
			(start 0.120396 0.3048)
			(end 0.120396 0.2794)
			(stroke
				(width 0.1)
				(type default)
			)
			(layer "F.Fab")
		)
		(fp_line
			(start 0.120396 0.2794)
			(end -0.12065 0.2794)
			(stroke
				(width 0.1)
				(type default)
			)
			(layer "F.Fab")
		)
		(fp_line
			(start -0.12065 0.3048)
			(end -0.67945 0.3048)
			(stroke
				(width 0.1)
				(type default)
			)
			(layer "F.Fab")
		)
		(fp_line
			(start -0.12065 0.2794)
			(end -0.12065 0.3048)
			(stroke
				(width 0.1)
				(type default)
			)
			(layer "F.Fab")
		)
		(fp_line
			(start -0.12065 -0.2794)
			(end 0.12065 -0.2794)
			(stroke
				(width 0.1)
				(type default)
			)
			(layer "F.Fab")
		)
		(fp_line
			(start -0.12065 -0.305054)
			(end -0.12065 -0.2794)
			(stroke
				(width 0.1)
				(type default)
			)
			(layer "F.Fab")
		)
		(fp_line
			(start -0.67945 0.3048)
			(end -0.67945 -0.305054)
			(stroke
				(width 0.1)
				(type default)
			)
			(layer "F.Fab")
		)
		(fp_line
			(start -0.67945 -0.305054)
			(end -0.12065 -0.305054)
			(stroke
				(width 0.1)
				(type default)
			)
			(layer "F.Fab")
		)
		(pad "1" smd circle
			(at -0.40005 0 180)
			(size 0 0)
			(layers "F.Cu" "F.Mask" "F.Paste")
			(net "P52V_FAN_5_BUFF_EN")
		)
		(pad "2" smd circle
			(at 0.40005 0 180)
			(size 0 0)
			(layers "F.Cu" "F.Mask" "F.Paste")
			(net "P52V_FAN_5_BUFF_EN_R")
		)
	)
	(footprint ""
		(layer "F.Cu")
		(at 3.81 -130.937)
		(property "Reference" "R5571"
			(at 0 0 0)
			(layer "F.SilkS")
			(hide yes)
			(effects
				(font
					(size 1.27 1.27)
				)
			)
		)
		(property "Value" ""
			(at 0 0 0)
			(layer "F.Fab")
			(effects
				(font
					(size 1.27 1.27)
				)
			)
		)
		(duplicate_pad_numbers_are_jumpers no)
		(fp_line
			(start -0.7874 -0.4064)
			(end 0.7874 -0.4064)
			(stroke
				(width 0.1524)
				(type default)
			)
			(layer "F.SilkS")
		)
		(fp_line
			(start -0.7874 0.4064)
			(end -0.7874 -0.4064)
			(stroke
				(width 0.1524)
				(type default)
			)
			(layer "F.SilkS")
		)
		(fp_line
			(start 0.7874 -0.4064)
			(end 0.7874 0.4064)
			(stroke
				(width 0.1524)
				(type default)
			)
			(layer "F.SilkS")
		)
		(fp_line
			(start 0.7874 0.4064)
			(end -0.7874 0.4064)
			(stroke
				(width 0.1524)
				(type default)
			)
			(layer "F.SilkS")
		)
		(fp_line
			(start -0.67945 -0.305054)
			(end -0.12065 -0.305054)
			(stroke
				(width 0.1)
				(type default)
			)
			(layer "F.Fab")
		)
		(fp_line
			(start -0.67945 0.3048)
			(end -0.67945 -0.305054)
			(stroke
				(width 0.1)
				(type default)
			)
			(layer "F.Fab")
		)
		(fp_line
			(start -0.12065 -0.305054)
			(end -0.12065 -0.2794)
			(stroke
				(width 0.1)
				(type default)
			)
			(layer "F.Fab")
		)
		(fp_line
			(start -0.12065 -0.2794)
			(end 0.12065 -0.2794)
			(stroke
				(width 0.1)
				(type default)
			)
			(layer "F.Fab")
		)
		(fp_line
			(start -0.12065 0.2794)
			(end -0.12065 0.3048)
			(stroke
				(width 0.1)
				(type default)
			)
			(layer "F.Fab")
		)
		(fp_line
			(start -0.12065 0.3048)
			(end -0.67945 0.3048)
			(stroke
				(width 0.1)
				(type default)
			)
			(layer "F.Fab")
		)
		(fp_line
			(start 0.120396 0.2794)
			(end -0.12065 0.2794)
			(stroke
				(width 0.1)
				(type default)
			)
			(layer "F.Fab")
		)
		(fp_line
			(start 0.120396 0.3048)
			(end 0.120396 0.2794)
			(stroke
				(width 0.1)
				(type default)
			)
			(layer "F.Fab")
		)
		(fp_line
			(start 0.12065 -0.3048)
			(end 0.67945 -0.3048)
			(stroke
				(width 0.1)
				(type default)
			)
			(layer "F.Fab")
		)
		(fp_line
			(start 0.12065 -0.2794)
			(end 0.12065 -0.3048)
			(stroke
				(width 0.1)
				(type default)
			)
			(layer "F.Fab")
		)
		(fp_line
			(start 0.67945 -0.3048)
			(end 0.67945 0.3048)
			(stroke
				(width 0.1)
				(type default)
			)
			(layer "F.Fab")
		)
		(fp_line
			(start 0.67945 0.3048)
			(end 0.120396 0.3048)
			(stroke
				(width 0.1)
				(type default)
			)
			(layer "F.Fab")
		)
		(pad "1" smd circle
			(at -0.40005 0)
			(size 0 0)
			(layers "F.Cu" "F.Mask" "F.Paste")
			(net "GND")
		)
		(pad "2" smd circle
			(at 0.40005 0)
			(size 0 0)
			(layers "F.Cu" "F.Mask" "F.Paste")
			(net "U404_ADD1")
		)
	)
	(footprint ""
		(layer "F.Cu")
		(at 16.51 -197.739 180)
		(property "Reference" "C2046"
			(at 0 0 180)
			(layer "F.SilkS")
			(hide yes)
			(effects
				(font
					(size 1.27 1.27)
				)
			)
		)
		(property "Value" ""
			(at 0 0 180)
			(layer "F.Fab")
			(effects
				(font
					(size 1.27 1.27)
				)
			)
		)
		(duplicate_pad_numbers_are_jumpers no)
		(fp_line
			(start 0.7874 0.4064)
			(end -0.7874 0.4064)
			(stroke
				(width 0.1524)
				(type default)
			)
			(layer "F.SilkS")
		)
		(fp_line
			(start 0.7874 -0.4064)
			(end 0.7874 0.4064)
			(stroke
				(width 0.1524)
				(type default)
			)
			(layer "F.SilkS")
		)
		(fp_line
			(start -0.7874 0.4064)
			(end -0.7874 -0.4064)
			(stroke
				(width 0.1524)
				(type default)
			)
			(layer "F.SilkS")
		)
		(fp_line
			(start -0.7874 -0.4064)
			(end 0.7874 -0.4064)
			(stroke
				(width 0.1524)
				(type default)
			)
			(layer "F.SilkS")
		)
		(fp_line
			(start 0.67945 0.3048)
			(end 0.120396 0.3048)
			(stroke
				(width 0.1)
				(type default)
			)
			(layer "F.Fab")
		)
		(fp_line
			(start 0.67945 -0.3048)
			(end 0.67945 0.3048)
			(stroke
				(width 0.1)
				(type default)
			)
			(layer "F.Fab")
		)
		(fp_line
			(start 0.12065 -0.2794)
			(end 0.12065 -0.3048)
			(stroke
				(width 0.1)
				(type default)
			)
			(layer "F.Fab")
		)
		(fp_line
			(start 0.12065 -0.3048)
			(end 0.67945 -0.3048)
			(stroke
				(width 0.1)
				(type default)
			)
			(layer "F.Fab")
		)
		(fp_line
			(start 0.120396 0.3048)
			(end 0.120396 0.2794)
			(stroke
				(width 0.1)
				(type default)
			)
			(layer "F.Fab")
		)
		(fp_line
			(start 0.120396 0.2794)
			(end -0.12065 0.2794)
			(stroke
				(width 0.1)
				(type default)
			)
			(layer "F.Fab")
		)
		(fp_line
			(start -0.12065 0.3048)
			(end -0.67945 0.3048)
			(stroke
				(width 0.1)
				(type default)
			)
			(layer "F.Fab")
		)
		(fp_line
			(start -0.12065 0.2794)
			(end -0.12065 0.3048)
			(stroke
				(width 0.1)
				(type default)
			)
			(layer "F.Fab")
		)
		(fp_line
			(start -0.12065 -0.2794)
			(end 0.12065 -0.2794)
			(stroke
				(width 0.1)
				(type default)
			)
			(layer "F.Fab")
		)
		(fp_line
			(start -0.12065 -0.305054)
			(end -0.12065 -0.2794)
			(stroke
				(width 0.1)
				(type default)
			)
			(layer "F.Fab")
		)
		(fp_line
			(start -0.67945 0.3048)
			(end -0.67945 -0.305054)
			(stroke
				(width 0.1)
				(type default)
			)
			(layer "F.Fab")
		)
		(fp_line
			(start -0.67945 -0.305054)
			(end -0.12065 -0.305054)
			(stroke
				(width 0.1)
				(type default)
			)
			(layer "F.Fab")
		)
		(pad "1" smd circle
			(at -0.40005 0 180)
			(size 0 0)
			(layers "F.Cu" "F.Mask" "F.Paste")
			(net "FAN_6_TACH_IL_R")
		)
		(pad "2" smd circle
			(at 0.40005 0 180)
			(size 0 0)
			(layers "F.Cu" "F.Mask" "F.Paste")
			(net "GND")
		)
	)
	(footprint ""
		(layer "F.Cu")
		(at 19.304 -34.925 180)
		(property "Reference" "Q13"
			(at 1.39446 2.44221 0)
			(unlocked yes)
			(layer "F.SilkS")
			(effects
				(font
					(size 0.7874 0.5842)
					(thickness 0.1524)
				)
				(justify left)
			)
		)
		(property "Value" ""
			(at 0 0 180)
			(layer "F.Fab")
			(effects
				(font
					(size 1.27 1.27)
				)
			)
		)
		(duplicate_pad_numbers_are_jumpers no)
		(fp_line
			(start 1.905 1.651)
			(end -1.905 1.651)
			(stroke
				(width 0.1524)
				(type default)
			)
			(layer "F.SilkS")
		)
		(fp_line
			(start 1.905 -1.651)
			(end 1.905 1.651)
			(stroke
				(width 0.1524)
				(type default)
			)
			(layer "F.SilkS")
		)
		(fp_line
			(start -1.905 1.651)
			(end -1.905 -1.651)
			(stroke
				(width 0.1524)
				(type default)
			)
			(layer "F.SilkS")
		)
		(fp_line
			(start -1.905 -1.651)
			(end 1.905 -1.651)
			(stroke
				(width 0.1524)
				(type default)
			)
			(layer "F.SilkS")
		)
		(fp_line
			(start 1.249934 0.219964)
			(end 0.6985 0.219964)
			(stroke
				(width 0.1)
				(type default)
			)
			(layer "F.Fab")
		)
		(fp_line
			(start 1.249934 -0.219964)
			(end 1.249934 0.219964)
			(stroke
				(width 0.1)
				(type default)
			)
			(layer "F.Fab")
		)
		(fp_line
			(start 0.6985 1.524)
			(end -0.6985 1.524)
			(stroke
				(width 0.1)
				(type default)
			)
			(layer "F.Fab")
		)
		(fp_line
			(start 0.6985 0.219964)
			(end 0.6985 1.524)
			(stroke
				(width 0.1)
				(type default)
			)
			(layer "F.Fab")
		)
		(fp_line
			(start 0.6985 -0.219964)
			(end 1.249934 -0.219964)
			(stroke
				(width 0.1)
				(type default)
			)
			(layer "F.Fab")
		)
		(fp_line
			(start 0.6985 -1.524)
			(end 0.6985 -0.219964)
			(stroke
				(width 0.1)
				(type default)
			)
			(layer "F.Fab")
		)
		(fp_line
			(start -0.6985 1.524)
			(end -0.6985 1.169924)
			(stroke
				(width 0.1)
				(type default)
			)
			(layer "F.Fab")
		)
		(fp_line
			(start -0.6985 1.169924)
			(end -1.249934 1.169924)
			(stroke
				(width 0.1)
				(type default)
			)
			(layer "F.Fab")
		)
		(fp_line
			(start -0.6985 0.729996)
			(end -0.6985 -0.729996)
			(stroke
				(width 0.1)
				(type default)
			)
			(layer "F.Fab")
		)
		(fp_line
			(start -0.6985 -0.729996)
			(end -1.249934 -0.729996)
			(stroke
				(width 0.1)
				(type default)
			)
			(layer "F.Fab")
		)
		(fp_line
			(start -0.6985 -1.169924)
			(end -0.6985 -1.524)
			(stroke
				(width 0.1)
				(type default)
			)
			(layer "F.Fab")
		)
		(fp_line
			(start -0.6985 -1.524)
			(end 0.6985 -1.524)
			(stroke
				(width 0.1)
				(type default)
			)
			(layer "F.Fab")
		)
		(fp_line
			(start -1.249934 1.169924)
			(end -1.249934 0.729996)
			(stroke
				(width 0.1)
				(type default)
			)
			(layer "F.Fab")
		)
		(fp_line
			(start -1.249934 0.729996)
			(end -0.6985 0.729996)
			(stroke
				(width 0.1)
				(type default)
			)
			(layer "F.Fab")
		)
		(fp_line
			(start -1.249934 -0.729996)
			(end -1.249934 -1.169924)
			(stroke
				(width 0.1)
				(type default)
			)
			(layer "F.Fab")
		)
		(fp_line
			(start -1.249934 -1.169924)
			(end -0.6985 -1.169924)
			(stroke
				(width 0.1)
				(type default)
			)
			(layer "F.Fab")
		)
		(fp_rect
			(start 0.6985 -1.524)
			(end -0.6985 1.524)
			(stroke
				(width 0)
				(type default)
			)
			(fill no)
			(layer "F.Fab")
		)
		(pad "D" smd rect
			(at 1.1176 0 90)
			(size 1.016 1.27)
			(layers "F.Cu" "F.Mask" "F.Paste")
			(net "P12V_LED_FAN4")
		)
		(pad "G" smd rect
			(at -1.1176 -1.016 90)
			(size 1.016 1.27)
			(layers "F.Cu" "F.Mask" "F.Paste")
			(net "U409_D1")
		)
		(pad "S" smd rect
			(at -1.1176 1.016 90)
			(size 1.016 1.27)
			(layers "F.Cu" "F.Mask" "F.Paste")
			(net "P12V_LED")
		)
	)
	(footprint ""
		(layer "F.Cu")
		(at 25.654 -141.605 -90)
		(property "Reference" "R5279"
			(at 0 0 270)
			(layer "F.SilkS")
			(hide yes)
			(effects
				(font
					(size 1.27 1.27)
				)
			)
		)
		(property "Value" ""
			(at 0 0 270)
			(layer "F.Fab")
			(effects
				(font
					(size 1.27 1.27)
				)
			)
		)
		(duplicate_pad_numbers_are_jumpers no)
		(fp_line
			(start -0.7874 0.4064)
			(end -0.7874 -0.4064)
			(stroke
				(width 0.1524)
				(type default)
			)
			(layer "F.SilkS")
		)
		(fp_line
			(start 0.7874 0.4064)
			(end -0.7874 0.4064)
			(stroke
				(width 0.1524)
				(type default)
			)
			(layer "F.SilkS")
		)
		(fp_line
			(start -0.7874 -0.4064)
			(end 0.7874 -0.4064)
			(stroke
				(width 0.1524)
				(type default)
			)
			(layer "F.SilkS")
		)
		(fp_line
			(start 0.7874 -0.4064)
			(end 0.7874 0.4064)
			(stroke
				(width 0.1524)
				(type default)
			)
			(layer "F.SilkS")
		)
		(fp_line
			(start -0.67945 0.3048)
			(end -0.67945 -0.305054)
			(stroke
				(width 0.1)
				(type default)
			)
			(layer "F.Fab")
		)
		(fp_line
			(start -0.12065 0.3048)
			(end -0.67945 0.3048)
			(stroke
				(width 0.1)
				(type default)
			)
			(layer "F.Fab")
		)
		(fp_line
			(start 0.120396 0.3048)
			(end 0.120396 0.2794)
			(stroke
				(width 0.1)
				(type default)
			)
			(layer "F.Fab")
		)
		(fp_line
			(start 0.67945 0.3048)
			(end 0.120396 0.3048)
			(stroke
				(width 0.1)
				(type default)
			)
			(layer "F.Fab")
		)
		(fp_line
			(start -0.12065 0.2794)
			(end -0.12065 0.3048)
			(stroke
				(width 0.1)
				(type default)
			)
			(layer "F.Fab")
		)
		(fp_line
			(start 0.120396 0.2794)
			(end -0.12065 0.2794)
			(stroke
				(width 0.1)
				(type default)
			)
			(layer "F.Fab")
		)
		(fp_line
			(start -0.12065 -0.2794)
			(end 0.12065 -0.2794)
			(stroke
				(width 0.1)
				(type default)
			)
			(layer "F.Fab")
		)
		(fp_line
			(start 0.12065 -0.2794)
			(end 0.12065 -0.3048)
			(stroke
				(width 0.1)
				(type default)
			)
			(layer "F.Fab")
		)
		(fp_line
			(start 0.12065 -0.3048)
			(end 0.67945 -0.3048)
			(stroke
				(width 0.1)
				(type default)
			)
			(layer "F.Fab")
		)
		(fp_line
			(start 0.67945 -0.3048)
			(end 0.67945 0.3048)
			(stroke
				(width 0.1)
				(type default)
			)
			(layer "F.Fab")
		)
		(fp_line
			(start -0.67945 -0.305054)
			(end -0.12065 -0.305054)
			(stroke
				(width 0.1)
				(type default)
			)
			(layer "F.Fab")
		)
		(fp_line
			(start -0.12065 -0.305054)
			(end -0.12065 -0.2794)
			(stroke
				(width 0.1)
				(type default)
			)
			(layer "F.Fab")
		)
		(pad "1" smd circle
			(at -0.40005 0 270)
			(size 0 0)
			(layers "F.Cu" "F.Mask" "F.Paste")
			(net "SMB_FAN1_R_SDA")
		)
		(pad "2" smd circle
			(at 0.40005 0 270)
			(size 0 0)
			(layers "F.Cu" "F.Mask" "F.Paste")
			(net "P3V3_AUX")
		)
	)
	(footprint ""
		(layer "F.Cu")
		(at 16.891 -112.649 180)
		(property "Reference" "R5537"
			(at 0 0 180)
			(layer "F.SilkS")
			(hide yes)
			(effects
				(font
					(size 1.27 1.27)
				)
			)
		)
		(property "Value" ""
			(at 0 0 180)
			(layer "F.Fab")
			(effects
				(font
					(size 1.27 1.27)
				)
			)
		)
		(duplicate_pad_numbers_are_jumpers no)
		(fp_line
			(start 0.7874 0.4064)
			(end -0.7874 0.4064)
			(stroke
				(width 0.1524)
				(type default)
			)
			(layer "F.SilkS")
		)
		(fp_line
			(start 0.7874 -0.4064)
			(end 0.7874 0.4064)
			(stroke
				(width 0.1524)
				(type default)
			)
			(layer "F.SilkS")
		)
		(fp_line
			(start -0.7874 0.4064)
			(end -0.7874 -0.4064)
			(stroke
				(width 0.1524)
				(type default)
			)
			(layer "F.SilkS")
		)
		(fp_line
			(start -0.7874 -0.4064)
			(end 0.7874 -0.4064)
			(stroke
				(width 0.1524)
				(type default)
			)
			(layer "F.SilkS")
		)
		(fp_line
			(start 0.67945 0.3048)
			(end 0.120396 0.3048)
			(stroke
				(width 0.1)
				(type default)
			)
			(layer "F.Fab")
		)
		(fp_line
			(start 0.67945 -0.3048)
			(end 0.67945 0.3048)
			(stroke
				(width 0.1)
				(type default)
			)
			(layer "F.Fab")
		)
		(fp_line
			(start 0.12065 -0.2794)
			(end 0.12065 -0.3048)
			(stroke
				(width 0.1)
				(type default)
			)
			(layer "F.Fab")
		)
		(fp_line
			(start 0.12065 -0.3048)
			(end 0.67945 -0.3048)
			(stroke
				(width 0.1)
				(type default)
			)
			(layer "F.Fab")
		)
		(fp_line
			(start 0.120396 0.3048)
			(end 0.120396 0.2794)
			(stroke
				(width 0.1)
				(type default)
			)
			(layer "F.Fab")
		)
		(fp_line
			(start 0.120396 0.2794)
			(end -0.12065 0.2794)
			(stroke
				(width 0.1)
				(type default)
			)
			(layer "F.Fab")
		)
		(fp_line
			(start -0.12065 0.3048)
			(end -0.67945 0.3048)
			(stroke
				(width 0.1)
				(type default)
			)
			(layer "F.Fab")
		)
		(fp_line
			(start -0.12065 0.2794)
			(end -0.12065 0.3048)
			(stroke
				(width 0.1)
				(type default)
			)
			(layer "F.Fab")
		)
		(fp_line
			(start -0.12065 -0.2794)
			(end 0.12065 -0.2794)
			(stroke
				(width 0.1)
				(type default)
			)
			(layer "F.Fab")
		)
		(fp_line
			(start -0.12065 -0.305054)
			(end -0.12065 -0.2794)
			(stroke
				(width 0.1)
				(type default)
			)
			(layer "F.Fab")
		)
		(fp_line
			(start -0.67945 0.3048)
			(end -0.67945 -0.305054)
			(stroke
				(width 0.1)
				(type default)
			)
			(layer "F.Fab")
		)
		(fp_line
			(start -0.67945 -0.305054)
			(end -0.12065 -0.305054)
			(stroke
				(width 0.1)
				(type default)
			)
			(layer "F.Fab")
		)
		(pad "1" smd rect
			(at -0.40005 0)
			(size 0.4572 0.508)
			(layers "F.Cu" "F.Mask" "F.Paste")
			(net "P12V_LED_FAN5")
		)
		(pad "2" smd rect
			(at 0.40005 0)
			(size 0.4572 0.508)
			(layers "F.Cu" "F.Mask" "F.Paste")
			(net "FAN_5_OK_LED_R_N")
		)
	)
	(footprint ""
		(layer "F.Cu")
		(at 37.211 -202.311)
		(property "Reference" "R5412"
			(at 0 0 0)
			(layer "F.SilkS")
			(hide yes)
			(effects
				(font
					(size 1.27 1.27)
				)
			)
		)
		(property "Value" ""
			(at 0 0 0)
			(layer "F.Fab")
			(effects
				(font
					(size 1.27 1.27)
				)
			)
		)
		(duplicate_pad_numbers_are_jumpers no)
		(fp_line
			(start -0.7874 -0.4064)
			(end 0.7874 -0.4064)
			(stroke
				(width 0.1524)
				(type default)
			)
			(layer "F.SilkS")
		)
		(fp_line
			(start -0.7874 0.4064)
			(end -0.7874 -0.4064)
			(stroke
				(width 0.1524)
				(type default)
			)
			(layer "F.SilkS")
		)
		(fp_line
			(start 0.7874 -0.4064)
			(end 0.7874 0.4064)
			(stroke
				(width 0.1524)
				(type default)
			)
			(layer "F.SilkS")
		)
		(fp_line
			(start 0.7874 0.4064)
			(end -0.7874 0.4064)
			(stroke
				(width 0.1524)
				(type default)
			)
			(layer "F.SilkS")
		)
		(fp_line
			(start -0.67945 -0.305054)
			(end -0.12065 -0.305054)
			(stroke
				(width 0.1)
				(type default)
			)
			(layer "F.Fab")
		)
		(fp_line
			(start -0.67945 0.3048)
			(end -0.67945 -0.305054)
			(stroke
				(width 0.1)
				(type default)
			)
			(layer "F.Fab")
		)
		(fp_line
			(start -0.12065 -0.305054)
			(end -0.12065 -0.2794)
			(stroke
				(width 0.1)
				(type default)
			)
			(layer "F.Fab")
		)
		(fp_line
			(start -0.12065 -0.2794)
			(end 0.12065 -0.2794)
			(stroke
				(width 0.1)
				(type default)
			)
			(layer "F.Fab")
		)
		(fp_line
			(start -0.12065 0.2794)
			(end -0.12065 0.3048)
			(stroke
				(width 0.1)
				(type default)
			)
			(layer "F.Fab")
		)
		(fp_line
			(start -0.12065 0.3048)
			(end -0.67945 0.3048)
			(stroke
				(width 0.1)
				(type default)
			)
			(layer "F.Fab")
		)
		(fp_line
			(start 0.120396 0.2794)
			(end -0.12065 0.2794)
			(stroke
				(width 0.1)
				(type default)
			)
			(layer "F.Fab")
		)
		(fp_line
			(start 0.120396 0.3048)
			(end 0.120396 0.2794)
			(stroke
				(width 0.1)
				(type default)
			)
			(layer "F.Fab")
		)
		(fp_line
			(start 0.12065 -0.3048)
			(end 0.67945 -0.3048)
			(stroke
				(width 0.1)
				(type default)
			)
			(layer "F.Fab")
		)
		(fp_line
			(start 0.12065 -0.2794)
			(end 0.12065 -0.3048)
			(stroke
				(width 0.1)
				(type default)
			)
			(layer "F.Fab")
		)
		(fp_line
			(start 0.67945 -0.3048)
			(end 0.67945 0.3048)
			(stroke
				(width 0.1)
				(type default)
			)
			(layer "F.Fab")
		)
		(fp_line
			(start 0.67945 0.3048)
			(end 0.120396 0.3048)
			(stroke
				(width 0.1)
				(type default)
			)
			(layer "F.Fab")
		)
		(pad "1" smd rect
			(at -0.40005 0 180)
			(size 0.4572 0.508)
			(layers "F.Cu" "F.Mask" "F.Paste")
			(net "FAN_1_FAIL_LED_R_N")
		)
		(pad "2" smd rect
			(at 0.40005 0 180)
			(size 0.4572 0.508)
			(layers "F.Cu" "F.Mask" "F.Paste")
			(net "FAN_1_FAIL_R_LED_N")
		)
	)
	(footprint ""
		(layer "F.Cu")
		(at 16.393922 -194.250056)
		(property "Reference" "C2044"
			(at 0 0 0)
			(layer "F.SilkS")
			(hide yes)
			(effects
				(font
					(size 1.27 1.27)
				)
			)
		)
		(property "Value" ""
			(at 0 0 0)
			(layer "F.Fab")
			(effects
				(font
					(size 1.27 1.27)
				)
			)
		)
		(duplicate_pad_numbers_are_jumpers no)
		(fp_line
			(start -0.7874 -0.4064)
			(end 0.7874 -0.4064)
			(stroke
				(width 0.1524)
				(type default)
			)
			(layer "F.SilkS")
		)
		(fp_line
			(start -0.7874 0.4064)
			(end -0.7874 -0.4064)
			(stroke
				(width 0.1524)
				(type default)
			)
			(layer "F.SilkS")
		)
		(fp_line
			(start 0.7874 -0.4064)
			(end 0.7874 0.4064)
			(stroke
				(width 0.1524)
				(type default)
			)
			(layer "F.SilkS")
		)
		(fp_line
			(start 0.7874 0.4064)
			(end -0.7874 0.4064)
			(stroke
				(width 0.1524)
				(type default)
			)
			(layer "F.SilkS")
		)
		(fp_line
			(start -0.67945 -0.305054)
			(end -0.12065 -0.305054)
			(stroke
				(width 0.1)
				(type default)
			)
			(layer "F.Fab")
		)
		(fp_line
			(start -0.67945 0.3048)
			(end -0.67945 -0.305054)
			(stroke
				(width 0.1)
				(type default)
			)
			(layer "F.Fab")
		)
		(fp_line
			(start -0.12065 -0.305054)
			(end -0.12065 -0.2794)
			(stroke
				(width 0.1)
				(type default)
			)
			(layer "F.Fab")
		)
		(fp_line
			(start -0.12065 -0.2794)
			(end 0.12065 -0.2794)
			(stroke
				(width 0.1)
				(type default)
			)
			(layer "F.Fab")
		)
		(fp_line
			(start -0.12065 0.2794)
			(end -0.12065 0.3048)
			(stroke
				(width 0.1)
				(type default)
			)
			(layer "F.Fab")
		)
		(fp_line
			(start -0.12065 0.3048)
			(end -0.67945 0.3048)
			(stroke
				(width 0.1)
				(type default)
			)
			(layer "F.Fab")
		)
		(fp_line
			(start 0.120396 0.2794)
			(end -0.12065 0.2794)
			(stroke
				(width 0.1)
				(type default)
			)
			(layer "F.Fab")
		)
		(fp_line
			(start 0.120396 0.3048)
			(end 0.120396 0.2794)
			(stroke
				(width 0.1)
				(type default)
			)
			(layer "F.Fab")
		)
		(fp_line
			(start 0.12065 -0.3048)
			(end 0.67945 -0.3048)
			(stroke
				(width 0.1)
				(type default)
			)
			(layer "F.Fab")
		)
		(fp_line
			(start 0.12065 -0.2794)
			(end 0.12065 -0.3048)
			(stroke
				(width 0.1)
				(type default)
			)
			(layer "F.Fab")
		)
		(fp_line
			(start 0.67945 -0.3048)
			(end 0.67945 0.3048)
			(stroke
				(width 0.1)
				(type default)
			)
			(layer "F.Fab")
		)
		(fp_line
			(start 0.67945 0.3048)
			(end 0.120396 0.3048)
			(stroke
				(width 0.1)
				(type default)
			)
			(layer "F.Fab")
		)
		(pad "1" smd circle
			(at -0.40005 0)
			(size 0 0)
			(layers "F.Cu" "F.Mask" "F.Paste")
			(net "FAN_6_PWM_OL_R")
		)
		(pad "2" smd circle
			(at 0.40005 0)
			(size 0 0)
			(layers "F.Cu" "F.Mask" "F.Paste")
			(net "GND")
		)
	)
	(footprint ""
		(layer "F.Cu")
		(at 24.257 -98.552)
		(property "Reference" ""
			(at 0 0 0)
			(layer "F.SilkS")
			(hide yes)
			(effects
				(font
					(size 1.27 1.27)
				)
			)
		)
		(property "Value" ""
			(at 0 0 0)
			(layer "F.Fab")
			(effects
				(font
					(size 1.27 1.27)
				)
			)
		)
		(duplicate_pad_numbers_are_jumpers no)
		(pad "1" smd circle
			(at 0 0)
			(size 0.9906 0.9906)
			(layers "F.Cu" "F.Mask" "F.Paste")
			(net "Net_127")
		)
		(zone
			(layer "F.Cu")
			(hatch none 0.5)
			(connect_pads
				(clearance 0)
			)
			(min_thickness 0.25)
			(keepout
				(tracks not_allowed)
				(vias allowed)
				(pads allowed)
				(copperpour not_allowed)
				(footprints allowed)
			)
			(placement
				(enabled no)
				(sheetname "")
			)
			(fill
				(thermal_gap 0.5)
				(thermal_bridge_width 0.5)
				(island_removal_mode 0)
			)
			(polygon
				(pts
					(arc
						(start 25.8826 -98.552)
						(mid 22.6314 -98.552)
						(end 25.8826 -98.552)
					)
				)
			)
		)
	)
	(footprint ""
		(layer "F.Cu")
		(at 42.037 -186.182 180)
		(property "Reference" "R4958"
			(at 0 0 180)
			(layer "F.SilkS")
			(hide yes)
			(effects
				(font
					(size 1.27 1.27)
				)
			)
		)
		(property "Value" ""
			(at 0 0 180)
			(layer "F.Fab")
			(effects
				(font
					(size 1.27 1.27)
				)
			)
		)
		(duplicate_pad_numbers_are_jumpers no)
		(fp_line
			(start 0.7874 0.4064)
			(end -0.7874 0.4064)
			(stroke
				(width 0.1524)
				(type default)
			)
			(layer "F.SilkS")
		)
		(fp_line
			(start 0.7874 -0.4064)
			(end 0.7874 0.4064)
			(stroke
				(width 0.1524)
				(type default)
			)
			(layer "F.SilkS")
		)
		(fp_line
			(start -0.7874 0.4064)
			(end -0.7874 -0.4064)
			(stroke
				(width 0.1524)
				(type default)
			)
			(layer "F.SilkS")
		)
		(fp_line
			(start -0.7874 -0.4064)
			(end 0.7874 -0.4064)
			(stroke
				(width 0.1524)
				(type default)
			)
			(layer "F.SilkS")
		)
		(fp_line
			(start 0.67945 0.3048)
			(end 0.120396 0.3048)
			(stroke
				(width 0.1)
				(type default)
			)
			(layer "F.Fab")
		)
		(fp_line
			(start 0.67945 -0.3048)
			(end 0.67945 0.3048)
			(stroke
				(width 0.1)
				(type default)
			)
			(layer "F.Fab")
		)
		(fp_line
			(start 0.12065 -0.2794)
			(end 0.12065 -0.3048)
			(stroke
				(width 0.1)
				(type default)
			)
			(layer "F.Fab")
		)
		(fp_line
			(start 0.12065 -0.3048)
			(end 0.67945 -0.3048)
			(stroke
				(width 0.1)
				(type default)
			)
			(layer "F.Fab")
		)
		(fp_line
			(start 0.120396 0.3048)
			(end 0.120396 0.2794)
			(stroke
				(width 0.1)
				(type default)
			)
			(layer "F.Fab")
		)
		(fp_line
			(start 0.120396 0.2794)
			(end -0.12065 0.2794)
			(stroke
				(width 0.1)
				(type default)
			)
			(layer "F.Fab")
		)
		(fp_line
			(start -0.12065 0.3048)
			(end -0.67945 0.3048)
			(stroke
				(width 0.1)
				(type default)
			)
			(layer "F.Fab")
		)
		(fp_line
			(start -0.12065 0.2794)
			(end -0.12065 0.3048)
			(stroke
				(width 0.1)
				(type default)
			)
			(layer "F.Fab")
		)
		(fp_line
			(start -0.12065 -0.2794)
			(end 0.12065 -0.2794)
			(stroke
				(width 0.1)
				(type default)
			)
			(layer "F.Fab")
		)
		(fp_line
			(start -0.12065 -0.305054)
			(end -0.12065 -0.2794)
			(stroke
				(width 0.1)
				(type default)
			)
			(layer "F.Fab")
		)
		(fp_line
			(start -0.67945 0.3048)
			(end -0.67945 -0.305054)
			(stroke
				(width 0.1)
				(type default)
			)
			(layer "F.Fab")
		)
		(fp_line
			(start -0.67945 -0.305054)
			(end -0.12065 -0.305054)
			(stroke
				(width 0.1)
				(type default)
			)
			(layer "F.Fab")
		)
		(pad "1" smd circle
			(at -0.40005 0 180)
			(size 0 0)
			(layers "F.Cu" "F.Mask" "F.Paste")
			(net "P3V3_AUX")
		)
		(pad "2" smd circle
			(at 0.40005 0 180)
			(size 0 0)
			(layers "F.Cu" "F.Mask" "F.Paste")
			(net "P52V_FAN_7_BUFF_EN")
		)
	)
	(footprint ""
		(layer "F.Cu")
		(at 15.113 -26.924 -90)
		(property "Reference" "R5349"
			(at 0 0 270)
			(layer "F.SilkS")
			(hide yes)
			(effects
				(font
					(size 1.27 1.27)
				)
			)
		)
		(property "Value" ""
			(at 0 0 270)
			(layer "F.Fab")
			(effects
				(font
					(size 1.27 1.27)
				)
			)
		)
		(duplicate_pad_numbers_are_jumpers no)
		(fp_line
			(start -0.7874 0.4064)
			(end -0.7874 -0.4064)
			(stroke
				(width 0.1524)
				(type default)
			)
			(layer "F.SilkS")
		)
		(fp_line
			(start 0.7874 0.4064)
			(end -0.7874 0.4064)
			(stroke
				(width 0.1524)
				(type default)
			)
			(layer "F.SilkS")
		)
		(fp_line
			(start -0.7874 -0.4064)
			(end 0.7874 -0.4064)
			(stroke
				(width 0.1524)
				(type default)
			)
			(layer "F.SilkS")
		)
		(fp_line
			(start 0.7874 -0.4064)
			(end 0.7874 0.4064)
			(stroke
				(width 0.1524)
				(type default)
			)
			(layer "F.SilkS")
		)
		(fp_line
			(start -0.67945 0.3048)
			(end -0.67945 -0.305054)
			(stroke
				(width 0.1)
				(type default)
			)
			(layer "F.Fab")
		)
		(fp_line
			(start -0.12065 0.3048)
			(end -0.67945 0.3048)
			(stroke
				(width 0.1)
				(type default)
			)
			(layer "F.Fab")
		)
		(fp_line
			(start 0.120396 0.3048)
			(end 0.120396 0.2794)
			(stroke
				(width 0.1)
				(type default)
			)
			(layer "F.Fab")
		)
		(fp_line
			(start 0.67945 0.3048)
			(end 0.120396 0.3048)
			(stroke
				(width 0.1)
				(type default)
			)
			(layer "F.Fab")
		)
		(fp_line
			(start -0.12065 0.2794)
			(end -0.12065 0.3048)
			(stroke
				(width 0.1)
				(type default)
			)
			(layer "F.Fab")
		)
		(fp_line
			(start 0.120396 0.2794)
			(end -0.12065 0.2794)
			(stroke
				(width 0.1)
				(type default)
			)
			(layer "F.Fab")
		)
		(fp_line
			(start -0.12065 -0.2794)
			(end 0.12065 -0.2794)
			(stroke
				(width 0.1)
				(type default)
			)
			(layer "F.Fab")
		)
		(fp_line
			(start 0.12065 -0.2794)
			(end 0.12065 -0.3048)
			(stroke
				(width 0.1)
				(type default)
			)
			(layer "F.Fab")
		)
		(fp_line
			(start 0.12065 -0.3048)
			(end 0.67945 -0.3048)
			(stroke
				(width 0.1)
				(type default)
			)
			(layer "F.Fab")
		)
		(fp_line
			(start 0.67945 -0.3048)
			(end 0.67945 0.3048)
			(stroke
				(width 0.1)
				(type default)
			)
			(layer "F.Fab")
		)
		(fp_line
			(start -0.67945 -0.305054)
			(end -0.12065 -0.305054)
			(stroke
				(width 0.1)
				(type default)
			)
			(layer "F.Fab")
		)
		(fp_line
			(start -0.12065 -0.305054)
			(end -0.12065 -0.2794)
			(stroke
				(width 0.1)
				(type default)
			)
			(layer "F.Fab")
		)
		(pad "1" smd rect
			(at -0.40005 0 90)
			(size 0.4572 0.508)
			(layers "F.Cu" "F.Mask" "F.Paste")
			(net "FAN_4_OK_LED_R_N")
		)
		(pad "2" smd rect
			(at 0.40005 0 90)
			(size 0.4572 0.508)
			(layers "F.Cu" "F.Mask" "F.Paste")
			(net "FAN_4_OK_R_LED_N")
		)
	)
	(footprint ""
		(layer "F.Cu")
		(at 33.528 -31.623)
		(property "Reference" "D285"
			(at 1.397 -1.62433 0)
			(unlocked yes)
			(layer "F.SilkS")
			(effects
				(font
					(size 0.7874 0.5842)
					(thickness 0.1524)
				)
				(justify left)
			)
		)
		(property "Value" ""
			(at 0 0 0)
			(layer "F.Fab")
			(effects
				(font
					(size 1.27 1.27)
				)
			)
		)
		(duplicate_pad_numbers_are_jumpers no)
		(fp_line
			(start -0.854964 -0.450088)
			(end -0.854964 0.450088)
			(stroke
				(width 0.1524)
				(type default)
			)
			(layer "F.SilkS")
		)
		(fp_line
			(start -0.854964 0.450088)
			(end 0.925068 0.450088)
			(stroke
				(width 0.1524)
				(type default)
			)
			(layer "F.SilkS")
		)
		(fp_line
			(start 0.845058 0.4064)
			(end 0.845058 -0.381)
			(stroke
				(width 0.1524)
				(type default)
			)
			(layer "F.SilkS")
		)
		(fp_line
			(start 0.870458 -0.2794)
			(end 0.845058 0.4064)
			(stroke
				(width 0.1524)
				(type default)
			)
			(layer "F.SilkS")
		)
		(fp_line
			(start 0.94488 -0.450088)
			(end -0.854964 -0.450088)
			(stroke
				(width 0.1524)
				(type default)
			)
			(layer "F.SilkS")
		)
		(fp_line
			(start 0.94488 0.450088)
			(end 0.94488 -0.450088)
			(stroke
				(width 0.1524)
				(type default)
			)
			(layer "F.SilkS")
		)
		(fp_line
			(start -0.54991 -0.350012)
			(end -0.54991 0.350012)
			(stroke
				(width 0.1)
				(type default)
			)
			(layer "F.Fab")
		)
		(fp_line
			(start -0.54991 0.350012)
			(end 0.54991 0.350012)
			(stroke
				(width 0.1)
				(type default)
			)
			(layer "F.Fab")
		)
		(fp_line
			(start 0.54991 -0.350012)
			(end -0.54991 -0.350012)
			(stroke
				(width 0.1)
				(type default)
			)
			(layer "F.Fab")
		)
		(fp_line
			(start 0.54991 0.350012)
			(end 0.54991 -0.350012)
			(stroke
				(width 0.1)
				(type default)
			)
			(layer "F.Fab")
		)
		(fp_text user "+"
			(at -0.7112 -0.00889 180)
			(unlocked yes)
			(layer "F.SilkS")
			(effects
				(font
					(size 1.905 1.4224)
					(thickness 0.1524)
				)
				(justify left)
			)
		)
		(fp_text user "-"
			(at 2.31648 0.39751 180)
			(unlocked yes)
			(layer "F.SilkS")
			(effects
				(font
					(size 1.905 1.4224)
					(thickness 0.1524)
				)
				(justify left)
			)
		)
		(fp_text user "+"
			(at -0.808228 0.239014 180)
			(unlocked yes)
			(layer "F.Fab")
			(effects
				(font
					(size 1.905 1.4224)
					(thickness 0.1524)
				)
				(justify left)
			)
		)
		(fp_text user "-"
			(at 2.48539 0.239014 180)
			(unlocked yes)
			(layer "F.Fab")
			(effects
				(font
					(size 1.905 1.4224)
					(thickness 0.1524)
				)
				(justify left)
			)
		)
		(pad "A" smd rect
			(at -0.424942 0)
			(size 0.5588 0.6096)
			(layers "F.Cu" "F.Mask" "F.Paste")
			(net "GND")
		)
		(pad "C" smd rect
			(at 0.424942 0 180)
			(size 0.5588 0.6096)
			(layers "F.Cu" "F.Mask" "F.Paste")
			(net "FAN_3_PWM_OL_R")
		)
	)
	(footprint ""
		(layer "F.Cu")
		(at 18.288 -195.961 -90)
		(property "Reference" "R5318"
			(at 0 0 270)
			(layer "F.SilkS")
			(hide yes)
			(effects
				(font
					(size 1.27 1.27)
				)
			)
		)
		(property "Value" ""
			(at 0 0 270)
			(layer "F.Fab")
			(effects
				(font
					(size 1.27 1.27)
				)
			)
		)
		(duplicate_pad_numbers_are_jumpers no)
		(fp_line
			(start -0.7874 0.4064)
			(end -0.7874 -0.4064)
			(stroke
				(width 0.1524)
				(type default)
			)
			(layer "F.SilkS")
		)
		(fp_line
			(start 0.7874 0.4064)
			(end -0.7874 0.4064)
			(stroke
				(width 0.1524)
				(type default)
			)
			(layer "F.SilkS")
		)
		(fp_line
			(start -0.7874 -0.4064)
			(end 0.7874 -0.4064)
			(stroke
				(width 0.1524)
				(type default)
			)
			(layer "F.SilkS")
		)
		(fp_line
			(start 0.7874 -0.4064)
			(end 0.7874 0.4064)
			(stroke
				(width 0.1524)
				(type default)
			)
			(layer "F.SilkS")
		)
		(fp_line
			(start -0.67945 0.3048)
			(end -0.67945 -0.305054)
			(stroke
				(width 0.1)
				(type default)
			)
			(layer "F.Fab")
		)
		(fp_line
			(start -0.12065 0.3048)
			(end -0.67945 0.3048)
			(stroke
				(width 0.1)
				(type default)
			)
			(layer "F.Fab")
		)
		(fp_line
			(start 0.120396 0.3048)
			(end 0.120396 0.2794)
			(stroke
				(width 0.1)
				(type default)
			)
			(layer "F.Fab")
		)
		(fp_line
			(start 0.67945 0.3048)
			(end 0.120396 0.3048)
			(stroke
				(width 0.1)
				(type default)
			)
			(layer "F.Fab")
		)
		(fp_line
			(start -0.12065 0.2794)
			(end -0.12065 0.3048)
			(stroke
				(width 0.1)
				(type default)
			)
			(layer "F.Fab")
		)
		(fp_line
			(start 0.120396 0.2794)
			(end -0.12065 0.2794)
			(stroke
				(width 0.1)
				(type default)
			)
			(layer "F.Fab")
		)
		(fp_line
			(start -0.12065 -0.2794)
			(end 0.12065 -0.2794)
			(stroke
				(width 0.1)
				(type default)
			)
			(layer "F.Fab")
		)
		(fp_line
			(start 0.12065 -0.2794)
			(end 0.12065 -0.3048)
			(stroke
				(width 0.1)
				(type default)
			)
			(layer "F.Fab")
		)
		(fp_line
			(start 0.12065 -0.3048)
			(end 0.67945 -0.3048)
			(stroke
				(width 0.1)
				(type default)
			)
			(layer "F.Fab")
		)
		(fp_line
			(start 0.67945 -0.3048)
			(end 0.67945 0.3048)
			(stroke
				(width 0.1)
				(type default)
			)
			(layer "F.Fab")
		)
		(fp_line
			(start -0.67945 -0.305054)
			(end -0.12065 -0.305054)
			(stroke
				(width 0.1)
				(type default)
			)
			(layer "F.Fab")
		)
		(fp_line
			(start -0.12065 -0.305054)
			(end -0.12065 -0.2794)
			(stroke
				(width 0.1)
				(type default)
			)
			(layer "F.Fab")
		)
		(pad "1" smd rect
			(at -0.40005 0 90)
			(size 0.4572 0.508)
			(layers "F.Cu" "F.Mask" "F.Paste")
			(net "FAN_6_TACH_IL_R")
		)
		(pad "2" smd rect
			(at 0.40005 0 90)
			(size 0.4572 0.508)
			(layers "F.Cu" "F.Mask" "F.Paste")
			(net "FAN_6_TACH_IL")
		)
	)
	(footprint ""
		(layer "F.Cu")
		(at 26.373582 -260.139434)
		(property "Reference" "ME4"
			(at 0 0 0)
			(layer "F.SilkS")
			(hide yes)
			(effects
				(font
					(size 1.27 1.27)
				)
			)
		)
		(property "Value" ""
			(at 0 0 0)
			(layer "F.Fab")
			(effects
				(font
					(size 1.27 1.27)
				)
			)
		)
		(duplicate_pad_numbers_are_jumpers no)
		(fp_poly
			(pts
				(xy 0 -0.5842) (xy 3.3401 -0.5842) (xy 3.3401 0) (xy 0 0)
			)
			(stroke
				(width 0)
				(type default)
			)
			(fill yes)
			(layer "F.SilkS")
		)
		(fp_poly
			(pts
				(xy 1.32715 -3.4417) (xy 2.01295 -3.4417) (xy 2.01295 -3.2512) (xy 1.32715 -3.2512)
			)
			(stroke
				(width 0)
				(type default)
			)
			(fill yes)
			(layer "F.SilkS")
		)
		(fp_poly
			(pts
				(xy -0.070612 -0.681228) (xy -0.197612 -0.820928) (xy 0.852678 -1.91262) (xy 0.728472 -3.29184)
				(xy -0.248412 -4.300728) (xy -0.184912 -4.478528) (xy -0.007112 -4.503928) (xy 0.684022 -3.785616)
				(xy 0.65659 -4.0894) (xy 0.97155 -4.3434) (xy 1.22555 -4.3561) (xy 1.46685 -4.4704) (xy 2.01295 -4.4704)
				(xy 2.15265 -4.4069) (xy 2.44475 -4.191) (xy 2.49555 -4.191) (xy 2.59715 -4.2926) (xy 2.80035 -4.2672)
				(xy 2.88925 -4.1656) (xy 2.88925 -4.029456) (xy 3.345688 -4.503928) (xy 3.523488 -4.478528) (xy 3.586988 -4.300728)
				(xy 2.88925 -3.58013) (xy 2.88925 -3.3147) (xy 2.82575 -3.2385) (xy 2.67335 -3.2385) (xy 2.521966 -1.875282)
				(xy 2.545842 -1.85039)
				(arc
					(start 2.55905 -1.8415)
					(mid 2.648099 -1.766068)
					(end 2.717292 -1.672082)
				)
				(xy 3.536188 -0.820928) (xy 3.409188 -0.681228) (xy 3.244088 -0.693928)
				(arc
					(start 2.737612 -1.216914)
					(mid 2.31728 -0.925553)
					(end 1.86055 -1.1557)
				)
				(xy 0.92075 -1.1557) (xy 0.888492 -1.51384) (xy 0.094488 -0.693928)
			)
			(stroke
				(width 0)
				(type default)
			)
			(fill yes)
			(layer "F.SilkS")
		)
	)
	(footprint ""
		(layer "F.Cu")
		(at 37.338 -297.053)
		(property "Reference" "R5690"
			(at 0 0 0)
			(layer "F.SilkS")
			(hide yes)
			(effects
				(font
					(size 1.27 1.27)
				)
			)
		)
		(property "Value" ""
			(at 0 0 0)
			(layer "F.Fab")
			(effects
				(font
					(size 1.27 1.27)
				)
			)
		)
		(duplicate_pad_numbers_are_jumpers no)
		(fp_line
			(start -0.7874 -0.4064)
			(end 0.7874 -0.4064)
			(stroke
				(width 0.1524)
				(type default)
			)
			(layer "F.SilkS")
		)
		(fp_line
			(start -0.7874 0.4064)
			(end -0.7874 -0.4064)
			(stroke
				(width 0.1524)
				(type default)
			)
			(layer "F.SilkS")
		)
		(fp_line
			(start 0.7874 -0.4064)
			(end 0.7874 0.4064)
			(stroke
				(width 0.1524)
				(type default)
			)
			(layer "F.SilkS")
		)
		(fp_line
			(start 0.7874 0.4064)
			(end -0.7874 0.4064)
			(stroke
				(width 0.1524)
				(type default)
			)
			(layer "F.SilkS")
		)
		(fp_line
			(start -0.67945 -0.305054)
			(end -0.12065 -0.305054)
			(stroke
				(width 0.1)
				(type default)
			)
			(layer "F.Fab")
		)
		(fp_line
			(start -0.67945 0.3048)
			(end -0.67945 -0.305054)
			(stroke
				(width 0.1)
				(type default)
			)
			(layer "F.Fab")
		)
		(fp_line
			(start -0.12065 -0.305054)
			(end -0.12065 -0.2794)
			(stroke
				(width 0.1)
				(type default)
			)
			(layer "F.Fab")
		)
		(fp_line
			(start -0.12065 -0.2794)
			(end 0.12065 -0.2794)
			(stroke
				(width 0.1)
				(type default)
			)
			(layer "F.Fab")
		)
		(fp_line
			(start -0.12065 0.2794)
			(end -0.12065 0.3048)
			(stroke
				(width 0.1)
				(type default)
			)
			(layer "F.Fab")
		)
		(fp_line
			(start -0.12065 0.3048)
			(end -0.67945 0.3048)
			(stroke
				(width 0.1)
				(type default)
			)
			(layer "F.Fab")
		)
		(fp_line
			(start 0.120396 0.2794)
			(end -0.12065 0.2794)
			(stroke
				(width 0.1)
				(type default)
			)
			(layer "F.Fab")
		)
		(fp_line
			(start 0.120396 0.3048)
			(end 0.120396 0.2794)
			(stroke
				(width 0.1)
				(type default)
			)
			(layer "F.Fab")
		)
		(fp_line
			(start 0.12065 -0.3048)
			(end 0.67945 -0.3048)
			(stroke
				(width 0.1)
				(type default)
			)
			(layer "F.Fab")
		)
		(fp_line
			(start 0.12065 -0.2794)
			(end 0.12065 -0.3048)
			(stroke
				(width 0.1)
				(type default)
			)
			(layer "F.Fab")
		)
		(fp_line
			(start 0.67945 -0.3048)
			(end 0.67945 0.3048)
			(stroke
				(width 0.1)
				(type default)
			)
			(layer "F.Fab")
		)
		(fp_line
			(start 0.67945 0.3048)
			(end 0.120396 0.3048)
			(stroke
				(width 0.1)
				(type default)
			)
			(layer "F.Fab")
		)
		(pad "1" smd rect
			(at -0.40005 0 180)
			(size 0.4572 0.508)
			(layers "F.Cu" "F.Mask" "F.Paste")
			(net "P12V_LED_R_FAN0")
		)
		(pad "2" smd rect
			(at 0.40005 0 180)
			(size 0.4572 0.508)
			(layers "F.Cu" "F.Mask" "F.Paste")
			(net "P12V_LED_R1_FAN0")
		)
	)
	(footprint ""
		(layer "F.Cu")
		(at 12.2936 -306.705)
		(property "Reference" "ME7"
			(at 0 0 0)
			(layer "F.SilkS")
			(hide yes)
			(effects
				(font
					(size 1.27 1.27)
				)
			)
		)
		(property "Value" ""
			(at 0 0 0)
			(layer "F.Fab")
			(effects
				(font
					(size 1.27 1.27)
				)
			)
		)
		(duplicate_pad_numbers_are_jumpers no)
		(fp_line
			(start 0 -5.999988)
			(end 0 -4.475988)
			(stroke
				(width 0.1524)
				(type default)
			)
			(layer "F.SilkS")
		)
		(fp_line
			(start 0 -1.524)
			(end 0 0)
			(stroke
				(width 0.1524)
				(type default)
			)
			(layer "F.SilkS")
		)
		(fp_line
			(start 0 0)
			(end 1.524 0)
			(stroke
				(width 0.1524)
				(type default)
			)
			(layer "F.SilkS")
		)
		(fp_line
			(start 1.524 -5.999988)
			(end 0 -5.999988)
			(stroke
				(width 0.1524)
				(type default)
			)
			(layer "F.SilkS")
		)
		(fp_line
			(start 25.475946 -5.999988)
			(end 26.999946 -5.999988)
			(stroke
				(width 0.1524)
				(type default)
			)
			(layer "F.SilkS")
		)
		(fp_line
			(start 26.999946 -5.999988)
			(end 26.999946 -4.475988)
			(stroke
				(width 0.1524)
				(type default)
			)
			(layer "F.SilkS")
		)
		(fp_line
			(start 26.999946 -1.524)
			(end 26.999946 0)
			(stroke
				(width 0.1524)
				(type default)
			)
			(layer "F.SilkS")
		)
		(fp_line
			(start 26.999946 0)
			(end 25.475946 0)
			(stroke
				(width 0.1524)
				(type default)
			)
			(layer "F.SilkS")
		)
		(fp_text user "S/N"
			(at 0.2032 -4.59105 0)
			(unlocked yes)
			(layer "F.SilkS")
			(effects
				(font
					(size 1.905 1.4224)
					(thickness 0.1524)
				)
				(justify left)
			)
		)
	)
	(footprint ""
		(layer "F.Cu")
		(at 27.432 -182.372 180)
		(property "Reference" "R5487"
			(at 0 0 180)
			(layer "F.SilkS")
			(hide yes)
			(effects
				(font
					(size 1.27 1.27)
				)
			)
		)
		(property "Value" ""
			(at 0 0 180)
			(layer "F.Fab")
			(effects
				(font
					(size 1.27 1.27)
				)
			)
		)
		(duplicate_pad_numbers_are_jumpers no)
		(fp_line
			(start 0.7874 0.4064)
			(end -0.7874 0.4064)
			(stroke
				(width 0.1524)
				(type default)
			)
			(layer "F.SilkS")
		)
		(fp_line
			(start 0.7874 -0.4064)
			(end 0.7874 0.4064)
			(stroke
				(width 0.1524)
				(type default)
			)
			(layer "F.SilkS")
		)
		(fp_line
			(start -0.7874 0.4064)
			(end -0.7874 -0.4064)
			(stroke
				(width 0.1524)
				(type default)
			)
			(layer "F.SilkS")
		)
		(fp_line
			(start -0.7874 -0.4064)
			(end 0.7874 -0.4064)
			(stroke
				(width 0.1524)
				(type default)
			)
			(layer "F.SilkS")
		)
		(fp_line
			(start 0.67945 0.3048)
			(end 0.120396 0.3048)
			(stroke
				(width 0.1)
				(type default)
			)
			(layer "F.Fab")
		)
		(fp_line
			(start 0.67945 -0.3048)
			(end 0.67945 0.3048)
			(stroke
				(width 0.1)
				(type default)
			)
			(layer "F.Fab")
		)
		(fp_line
			(start 0.12065 -0.2794)
			(end 0.12065 -0.3048)
			(stroke
				(width 0.1)
				(type default)
			)
			(layer "F.Fab")
		)
		(fp_line
			(start 0.12065 -0.3048)
			(end 0.67945 -0.3048)
			(stroke
				(width 0.1)
				(type default)
			)
			(layer "F.Fab")
		)
		(fp_line
			(start 0.120396 0.3048)
			(end 0.120396 0.2794)
			(stroke
				(width 0.1)
				(type default)
			)
			(layer "F.Fab")
		)
		(fp_line
			(start 0.120396 0.2794)
			(end -0.12065 0.2794)
			(stroke
				(width 0.1)
				(type default)
			)
			(layer "F.Fab")
		)
		(fp_line
			(start -0.12065 0.3048)
			(end -0.67945 0.3048)
			(stroke
				(width 0.1)
				(type default)
			)
			(layer "F.Fab")
		)
		(fp_line
			(start -0.12065 0.2794)
			(end -0.12065 0.3048)
			(stroke
				(width 0.1)
				(type default)
			)
			(layer "F.Fab")
		)
		(fp_line
			(start -0.12065 -0.2794)
			(end 0.12065 -0.2794)
			(stroke
				(width 0.1)
				(type default)
			)
			(layer "F.Fab")
		)
		(fp_line
			(start -0.12065 -0.305054)
			(end -0.12065 -0.2794)
			(stroke
				(width 0.1)
				(type default)
			)
			(layer "F.Fab")
		)
		(fp_line
			(start -0.67945 0.3048)
			(end -0.67945 -0.305054)
			(stroke
				(width 0.1)
				(type default)
			)
			(layer "F.Fab")
		)
		(fp_line
			(start -0.67945 -0.305054)
			(end -0.12065 -0.305054)
			(stroke
				(width 0.1)
				(type default)
			)
			(layer "F.Fab")
		)
		(pad "1" smd circle
			(at -0.40005 0 180)
			(size 0 0)
			(layers "F.Cu" "F.Mask" "F.Paste")
			(net "P52V_FAN_0_BUFF_EN")
		)
		(pad "2" smd circle
			(at 0.40005 0 180)
			(size 0 0)
			(layers "F.Cu" "F.Mask" "F.Paste")
			(net "P52V_FAN_0_BUFF_EN_R")
		)
	)
	(footprint ""
		(layer "F.Cu")
		(at 34.417 -22.606)
		(property "Reference" "U374"
			(at -4.6482 -0.98933 0)
			(unlocked yes)
			(layer "F.SilkS")
			(effects
				(font
					(size 0.7874 0.5842)
					(thickness 0.1524)
				)
				(justify left)
			)
		)
		(property "Value" ""
			(at 0 0 0)
			(layer "F.Fab")
			(effects
				(font
					(size 1.27 1.27)
				)
			)
		)
		(duplicate_pad_numbers_are_jumpers no)
		(fp_line
			(start -1.335278 -1.100074)
			(end -1.335278 1.100074)
			(stroke
				(width 0.1524)
				(type default)
			)
			(layer "F.SilkS")
		)
		(fp_line
			(start -1.335278 1.100074)
			(end 1.335278 1.100074)
			(stroke
				(width 0.1524)
				(type default)
			)
			(layer "F.SilkS")
		)
		(fp_line
			(start 1.335278 -1.100074)
			(end -1.335278 -1.100074)
			(stroke
				(width 0.1524)
				(type default)
			)
			(layer "F.SilkS")
		)
		(fp_line
			(start 1.335278 1.100074)
			(end 1.335278 -1.100074)
			(stroke
				(width 0.1524)
				(type default)
			)
			(layer "F.SilkS")
		)
		(fp_line
			(start -0.674878 -1.100074)
			(end -0.674878 1.100074)
			(stroke
				(width 0.1)
				(type default)
			)
			(layer "F.Fab")
		)
		(fp_line
			(start -0.674878 1.100074)
			(end 0.674878 1.100074)
			(stroke
				(width 0.1)
				(type default)
			)
			(layer "F.Fab")
		)
		(fp_line
			(start 0.674878 -1.100074)
			(end -0.674878 -1.100074)
			(stroke
				(width 0.1)
				(type default)
			)
			(layer "F.Fab")
		)
		(fp_line
			(start 0.674878 1.100074)
			(end 0.674878 -1.100074)
			(stroke
				(width 0.1)
				(type default)
			)
			(layer "F.Fab")
		)
		(pad "D" smd rect
			(at 0.8001 0 270)
			(size 0.6096 0.8128)
			(layers "F.Cu" "F.Mask" "F.Paste")
			(net "FAN_3_FAIL_LED_R_N")
		)
		(pad "G" smd rect
			(at -0.8001 -0.649986 270)
			(size 0.6096 0.8128)
			(layers "F.Cu" "F.Mask" "F.Paste")
			(net "FAN_3_FAIL_R_LED")
		)
		(pad "S" smd rect
			(at -0.8001 0.649986 270)
			(size 0.6096 0.8128)
			(layers "F.Cu" "F.Mask" "F.Paste")
			(net "GND")
		)
	)
	(footprint ""
		(layer "F.Cu")
		(at 48.019716 -36.101274 90)
		(property "Reference" "C2048"
			(at 0 0 90)
			(layer "F.SilkS")
			(hide yes)
			(effects
				(font
					(size 1.27 1.27)
				)
			)
		)
		(property "Value" ""
			(at 0 0 90)
			(layer "F.Fab")
			(effects
				(font
					(size 1.27 1.27)
				)
			)
		)
		(duplicate_pad_numbers_are_jumpers no)
		(fp_line
			(start 1.524 -0.762)
			(end 1.524 0.762)
			(stroke
				(width 0.1524)
				(type default)
			)
			(layer "F.SilkS")
		)
		(fp_line
			(start -1.524 -0.762)
			(end 1.524 -0.762)
			(stroke
				(width 0.1524)
				(type default)
			)
			(layer "F.SilkS")
		)
		(fp_line
			(start 1.524 0.762)
			(end -1.524 0.762)
			(stroke
				(width 0.1524)
				(type default)
			)
			(layer "F.SilkS")
		)
		(fp_line
			(start -1.524 0.762)
			(end -1.524 -0.762)
			(stroke
				(width 0.1524)
				(type default)
			)
			(layer "F.SilkS")
		)
		(fp_line
			(start 1.1049 -0.724916)
			(end -1.1049 -0.724916)
			(stroke
				(width 0.1)
				(type default)
			)
			(layer "F.Fab")
		)
		(fp_line
			(start -1.1049 -0.724916)
			(end -1.1049 0.724916)
			(stroke
				(width 0.1)
				(type default)
			)
			(layer "F.Fab")
		)
		(fp_line
			(start 1.1049 0.724916)
			(end 1.1049 -0.724916)
			(stroke
				(width 0.1)
				(type default)
			)
			(layer "F.Fab")
		)
		(fp_line
			(start -1.1049 0.724916)
			(end 1.1049 0.724916)
			(stroke
				(width 0.1)
				(type default)
			)
			(layer "F.Fab")
		)
		(pad "1" smd rect
			(at -0.889 0 270)
			(size 1.016 1.27)
			(layers "F.Cu" "F.Mask" "F.Paste")
			(net "P12V_LED_FAN3")
		)
		(pad "2" smd rect
			(at 0.889 0 270)
			(size 1.016 1.27)
			(layers "F.Cu" "F.Mask" "F.Paste")
			(net "GND")
		)
	)
	(footprint ""
		(layer "F.Cu")
		(at 42.037 -182.88)
		(property "Reference" "R520"
			(at 0 0 0)
			(layer "F.SilkS")
			(hide yes)
			(effects
				(font
					(size 1.27 1.27)
				)
			)
		)
		(property "Value" ""
			(at 0 0 0)
			(layer "F.Fab")
			(effects
				(font
					(size 1.27 1.27)
				)
			)
		)
		(duplicate_pad_numbers_are_jumpers no)
		(fp_line
			(start -0.7874 -0.4064)
			(end 0.7874 -0.4064)
			(stroke
				(width 0.1524)
				(type default)
			)
			(layer "F.SilkS")
		)
		(fp_line
			(start -0.7874 0.4064)
			(end -0.7874 -0.4064)
			(stroke
				(width 0.1524)
				(type default)
			)
			(layer "F.SilkS")
		)
		(fp_line
			(start 0.7874 -0.4064)
			(end 0.7874 0.4064)
			(stroke
				(width 0.1524)
				(type default)
			)
			(layer "F.SilkS")
		)
		(fp_line
			(start 0.7874 0.4064)
			(end -0.7874 0.4064)
			(stroke
				(width 0.1524)
				(type default)
			)
			(layer "F.SilkS")
		)
		(fp_line
			(start -0.67945 -0.305054)
			(end -0.12065 -0.305054)
			(stroke
				(width 0.1)
				(type default)
			)
			(layer "F.Fab")
		)
		(fp_line
			(start -0.67945 0.3048)
			(end -0.67945 -0.305054)
			(stroke
				(width 0.1)
				(type default)
			)
			(layer "F.Fab")
		)
		(fp_line
			(start -0.12065 -0.305054)
			(end -0.12065 -0.2794)
			(stroke
				(width 0.1)
				(type default)
			)
			(layer "F.Fab")
		)
		(fp_line
			(start -0.12065 -0.2794)
			(end 0.12065 -0.2794)
			(stroke
				(width 0.1)
				(type default)
			)
			(layer "F.Fab")
		)
		(fp_line
			(start -0.12065 0.2794)
			(end -0.12065 0.3048)
			(stroke
				(width 0.1)
				(type default)
			)
			(layer "F.Fab")
		)
		(fp_line
			(start -0.12065 0.3048)
			(end -0.67945 0.3048)
			(stroke
				(width 0.1)
				(type default)
			)
			(layer "F.Fab")
		)
		(fp_line
			(start 0.120396 0.2794)
			(end -0.12065 0.2794)
			(stroke
				(width 0.1)
				(type default)
			)
			(layer "F.Fab")
		)
		(fp_line
			(start 0.120396 0.3048)
			(end 0.120396 0.2794)
			(stroke
				(width 0.1)
				(type default)
			)
			(layer "F.Fab")
		)
		(fp_line
			(start 0.12065 -0.3048)
			(end 0.67945 -0.3048)
			(stroke
				(width 0.1)
				(type default)
			)
			(layer "F.Fab")
		)
		(fp_line
			(start 0.12065 -0.2794)
			(end 0.12065 -0.3048)
			(stroke
				(width 0.1)
				(type default)
			)
			(layer "F.Fab")
		)
		(fp_line
			(start 0.67945 -0.3048)
			(end 0.67945 0.3048)
			(stroke
				(width 0.1)
				(type default)
			)
			(layer "F.Fab")
		)
		(fp_line
			(start 0.67945 0.3048)
			(end 0.120396 0.3048)
			(stroke
				(width 0.1)
				(type default)
			)
			(layer "F.Fab")
		)
		(pad "1" smd circle
			(at -0.40005 0)
			(size 0 0)
			(layers "F.Cu" "F.Mask" "F.Paste")
			(net "PD_FAN_BUFF_INPUT_U336F")
		)
		(pad "2" smd circle
			(at 0.40005 0)
			(size 0 0)
			(layers "F.Cu" "F.Mask" "F.Paste")
			(net "P3V3_AUX")
		)
	)
	(footprint ""
		(layer "F.Cu")
		(at 42.291 -258.445 180)
		(property "Reference" "PR1"
			(at 0 0 180)
			(layer "F.SilkS")
			(hide yes)
			(effects
				(font
					(size 1.27 1.27)
				)
			)
		)
		(property "Value" ""
			(at 0 0 180)
			(layer "F.Fab")
			(effects
				(font
					(size 1.27 1.27)
				)
			)
		)
		(duplicate_pad_numbers_are_jumpers no)
		(fp_line
			(start 0.7874 0.4064)
			(end -0.7874 0.4064)
			(stroke
				(width 0.1524)
				(type default)
			)
			(layer "F.SilkS")
		)
		(fp_line
			(start 0.7874 -0.4064)
			(end 0.7874 0.4064)
			(stroke
				(width 0.1524)
				(type default)
			)
			(layer "F.SilkS")
		)
		(fp_line
			(start -0.7874 0.4064)
			(end -0.7874 -0.4064)
			(stroke
				(width 0.1524)
				(type default)
			)
			(layer "F.SilkS")
		)
		(fp_line
			(start -0.7874 -0.4064)
			(end 0.7874 -0.4064)
			(stroke
				(width 0.1524)
				(type default)
			)
			(layer "F.SilkS")
		)
		(fp_line
			(start 0.67945 0.3048)
			(end 0.120396 0.3048)
			(stroke
				(width 0.1)
				(type default)
			)
			(layer "F.Fab")
		)
		(fp_line
			(start 0.67945 -0.3048)
			(end 0.67945 0.3048)
			(stroke
				(width 0.1)
				(type default)
			)
			(layer "F.Fab")
		)
		(fp_line
			(start 0.12065 -0.2794)
			(end 0.12065 -0.3048)
			(stroke
				(width 0.1)
				(type default)
			)
			(layer "F.Fab")
		)
		(fp_line
			(start 0.12065 -0.3048)
			(end 0.67945 -0.3048)
			(stroke
				(width 0.1)
				(type default)
			)
			(layer "F.Fab")
		)
		(fp_line
			(start 0.120396 0.3048)
			(end 0.120396 0.2794)
			(stroke
				(width 0.1)
				(type default)
			)
			(layer "F.Fab")
		)
		(fp_line
			(start 0.120396 0.2794)
			(end -0.12065 0.2794)
			(stroke
				(width 0.1)
				(type default)
			)
			(layer "F.Fab")
		)
		(fp_line
			(start -0.12065 0.3048)
			(end -0.67945 0.3048)
			(stroke
				(width 0.1)
				(type default)
			)
			(layer "F.Fab")
		)
		(fp_line
			(start -0.12065 0.2794)
			(end -0.12065 0.3048)
			(stroke
				(width 0.1)
				(type default)
			)
			(layer "F.Fab")
		)
		(fp_line
			(start -0.12065 -0.2794)
			(end 0.12065 -0.2794)
			(stroke
				(width 0.1)
				(type default)
			)
			(layer "F.Fab")
		)
		(fp_line
			(start -0.12065 -0.305054)
			(end -0.12065 -0.2794)
			(stroke
				(width 0.1)
				(type default)
			)
			(layer "F.Fab")
		)
		(fp_line
			(start -0.67945 0.3048)
			(end -0.67945 -0.305054)
			(stroke
				(width 0.1)
				(type default)
			)
			(layer "F.Fab")
		)
		(fp_line
			(start -0.67945 -0.305054)
			(end -0.12065 -0.305054)
			(stroke
				(width 0.1)
				(type default)
			)
			(layer "F.Fab")
		)
		(pad "1" smd circle
			(at -0.40005 0 180)
			(size 0 0)
			(layers "F.Cu" "F.Mask" "F.Paste")
			(net "FAN_0_FAULT_R")
		)
		(pad "2" smd circle
			(at 0.40005 0 180)
			(size 0 0)
			(layers "F.Cu" "F.Mask" "F.Paste")
			(net "FAN_0_P3V_R")
		)
	)
	(footprint ""
		(layer "F.Cu")
		(at 28.956 -173.609 180)
		(property "Reference" "R5107"
			(at 0 0 180)
			(layer "F.SilkS")
			(hide yes)
			(effects
				(font
					(size 1.27 1.27)
				)
			)
		)
		(property "Value" ""
			(at 0 0 180)
			(layer "F.Fab")
			(effects
				(font
					(size 1.27 1.27)
				)
			)
		)
		(duplicate_pad_numbers_are_jumpers no)
		(fp_line
			(start 0.7874 0.4064)
			(end -0.7874 0.4064)
			(stroke
				(width 0.1524)
				(type default)
			)
			(layer "F.SilkS")
		)
		(fp_line
			(start 0.7874 -0.4064)
			(end 0.7874 0.4064)
			(stroke
				(width 0.1524)
				(type default)
			)
			(layer "F.SilkS")
		)
		(fp_line
			(start -0.7874 0.4064)
			(end -0.7874 -0.4064)
			(stroke
				(width 0.1524)
				(type default)
			)
			(layer "F.SilkS")
		)
		(fp_line
			(start -0.7874 -0.4064)
			(end 0.7874 -0.4064)
			(stroke
				(width 0.1524)
				(type default)
			)
			(layer "F.SilkS")
		)
		(fp_line
			(start 0.67945 0.3048)
			(end 0.120396 0.3048)
			(stroke
				(width 0.1)
				(type default)
			)
			(layer "F.Fab")
		)
		(fp_line
			(start 0.67945 -0.3048)
			(end 0.67945 0.3048)
			(stroke
				(width 0.1)
				(type default)
			)
			(layer "F.Fab")
		)
		(fp_line
			(start 0.12065 -0.2794)
			(end 0.12065 -0.3048)
			(stroke
				(width 0.1)
				(type default)
			)
			(layer "F.Fab")
		)
		(fp_line
			(start 0.12065 -0.3048)
			(end 0.67945 -0.3048)
			(stroke
				(width 0.1)
				(type default)
			)
			(layer "F.Fab")
		)
		(fp_line
			(start 0.120396 0.3048)
			(end 0.120396 0.2794)
			(stroke
				(width 0.1)
				(type default)
			)
			(layer "F.Fab")
		)
		(fp_line
			(start 0.120396 0.2794)
			(end -0.12065 0.2794)
			(stroke
				(width 0.1)
				(type default)
			)
			(layer "F.Fab")
		)
		(fp_line
			(start -0.12065 0.3048)
			(end -0.67945 0.3048)
			(stroke
				(width 0.1)
				(type default)
			)
			(layer "F.Fab")
		)
		(fp_line
			(start -0.12065 0.2794)
			(end -0.12065 0.3048)
			(stroke
				(width 0.1)
				(type default)
			)
			(layer "F.Fab")
		)
		(fp_line
			(start -0.12065 -0.2794)
			(end 0.12065 -0.2794)
			(stroke
				(width 0.1)
				(type default)
			)
			(layer "F.Fab")
		)
		(fp_line
			(start -0.12065 -0.305054)
			(end -0.12065 -0.2794)
			(stroke
				(width 0.1)
				(type default)
			)
			(layer "F.Fab")
		)
		(fp_line
			(start -0.67945 0.3048)
			(end -0.67945 -0.305054)
			(stroke
				(width 0.1)
				(type default)
			)
			(layer "F.Fab")
		)
		(fp_line
			(start -0.67945 -0.305054)
			(end -0.12065 -0.305054)
			(stroke
				(width 0.1)
				(type default)
			)
			(layer "F.Fab")
		)
		(pad "1" smd circle
			(at -0.40005 0 180)
			(size 0 0)
			(layers "F.Cu" "F.Mask" "F.Paste")
			(net "FAN_6_OK_LED")
		)
		(pad "2" smd circle
			(at 0.40005 0 180)
			(size 0 0)
			(layers "F.Cu" "F.Mask" "F.Paste")
			(net "FAN_6_OK_R_LED")
		)
	)
	(footprint ""
		(layer "F.Cu")
		(at 35.2806 -90.9574 180)
		(property "Reference" "PC29"
			(at -2.413 -5.94487 0)
			(unlocked yes)
			(layer "F.SilkS")
			(effects
				(font
					(size 0.7874 0.5842)
					(thickness 0.1524)
				)
				(justify left)
			)
		)
		(property "Value" ""
			(at 0 0 180)
			(layer "F.Fab")
			(effects
				(font
					(size 1.27 1.27)
				)
			)
		)
		(duplicate_pad_numbers_are_jumpers no)
		(fp_line
			(start 5.249926 5.249926)
			(end 5.249926 1.2446)
			(stroke
				(width 0.1524)
				(type default)
			)
			(layer "F.SilkS")
		)
		(fp_line
			(start 5.249926 -1.2446)
			(end 5.249926 -5.249926)
			(stroke
				(width 0.1524)
				(type default)
			)
			(layer "F.SilkS")
		)
		(fp_line
			(start 5.249926 -5.249926)
			(end -3.979926 -5.249926)
			(stroke
				(width 0.1524)
				(type default)
			)
			(layer "F.SilkS")
		)
		(fp_line
			(start -3.979926 5.249926)
			(end 5.249926 5.249926)
			(stroke
				(width 0.1524)
				(type default)
			)
			(layer "F.SilkS")
		)
		(fp_line
			(start -3.979926 -5.249926)
			(end -5.249926 -3.979926)
			(stroke
				(width 0.1524)
				(type default)
			)
			(layer "F.SilkS")
		)
		(fp_line
			(start -5.249926 3.979926)
			(end -3.979926 5.249926)
			(stroke
				(width 0.1524)
				(type default)
			)
			(layer "F.SilkS")
		)
		(fp_line
			(start -5.249926 1.2446)
			(end -5.249926 3.979926)
			(stroke
				(width 0.1524)
				(type default)
			)
			(layer "F.SilkS")
		)
		(fp_line
			(start -5.249926 -3.979926)
			(end -5.249926 -1.2446)
			(stroke
				(width 0.1524)
				(type default)
			)
			(layer "F.SilkS")
		)
		(fp_line
			(start 5.249926 5.249926)
			(end 5.249926 -5.249926)
			(stroke
				(width 0.1)
				(type default)
			)
			(layer "F.Fab")
		)
		(fp_line
			(start 5.249926 -5.249926)
			(end -5.249926 -5.249926)
			(stroke
				(width 0.1)
				(type default)
			)
			(layer "F.Fab")
		)
		(fp_line
			(start -5.249926 5.249926)
			(end 5.249926 5.249926)
			(stroke
				(width 0.1)
				(type default)
			)
			(layer "F.Fab")
		)
		(fp_line
			(start -5.249926 -5.249926)
			(end -5.249926 5.249926)
			(stroke
				(width 0.1)
				(type default)
			)
			(layer "F.Fab")
		)
		(pad "1" smd rect
			(at -4.45008 0 270)
			(size 2.2098 4.4196)
			(layers "F.Cu" "F.Mask" "F.Paste")
			(net "P52V_FAN_2")
		)
		(pad "2" smd rect
			(at 4.45008 0 270)
			(size 2.2098 4.4196)
			(layers "F.Cu" "F.Mask" "F.Paste")
			(net "GND")
		)
	)
	(footprint ""
		(layer "F.Cu")
		(at 42.418 -73.66 90)
		(property "Reference" "PR36"
			(at 0 0 90)
			(layer "F.SilkS")
			(hide yes)
			(effects
				(font
					(size 1.27 1.27)
				)
			)
		)
		(property "Value" ""
			(at 0 0 90)
			(layer "F.Fab")
			(effects
				(font
					(size 1.27 1.27)
				)
			)
		)
		(duplicate_pad_numbers_are_jumpers no)
		(fp_line
			(start 0.7874 -0.4064)
			(end 0.7874 0.4064)
			(stroke
				(width 0.1524)
				(type default)
			)
			(layer "F.SilkS")
		)
		(fp_line
			(start -0.7874 -0.4064)
			(end 0.7874 -0.4064)
			(stroke
				(width 0.1524)
				(type default)
			)
			(layer "F.SilkS")
		)
		(fp_line
			(start 0.7874 0.4064)
			(end -0.7874 0.4064)
			(stroke
				(width 0.1524)
				(type default)
			)
			(layer "F.SilkS")
		)
		(fp_line
			(start -0.7874 0.4064)
			(end -0.7874 -0.4064)
			(stroke
				(width 0.1524)
				(type default)
			)
			(layer "F.SilkS")
		)
		(fp_line
			(start -0.12065 -0.305054)
			(end -0.12065 -0.2794)
			(stroke
				(width 0.1)
				(type default)
			)
			(layer "F.Fab")
		)
		(fp_line
			(start -0.67945 -0.305054)
			(end -0.12065 -0.305054)
			(stroke
				(width 0.1)
				(type default)
			)
			(layer "F.Fab")
		)
		(fp_line
			(start 0.67945 -0.3048)
			(end 0.67945 0.3048)
			(stroke
				(width 0.1)
				(type default)
			)
			(layer "F.Fab")
		)
		(fp_line
			(start 0.12065 -0.3048)
			(end 0.67945 -0.3048)
			(stroke
				(width 0.1)
				(type default)
			)
			(layer "F.Fab")
		)
		(fp_line
			(start 0.12065 -0.2794)
			(end 0.12065 -0.3048)
			(stroke
				(width 0.1)
				(type default)
			)
			(layer "F.Fab")
		)
		(fp_line
			(start -0.12065 -0.2794)
			(end 0.12065 -0.2794)
			(stroke
				(width 0.1)
				(type default)
			)
			(layer "F.Fab")
		)
		(fp_line
			(start 0.120396 0.2794)
			(end -0.12065 0.2794)
			(stroke
				(width 0.1)
				(type default)
			)
			(layer "F.Fab")
		)
		(fp_line
			(start -0.12065 0.2794)
			(end -0.12065 0.3048)
			(stroke
				(width 0.1)
				(type default)
			)
			(layer "F.Fab")
		)
		(fp_line
			(start 0.67945 0.3048)
			(end 0.120396 0.3048)
			(stroke
				(width 0.1)
				(type default)
			)
			(layer "F.Fab")
		)
		(fp_line
			(start 0.120396 0.3048)
			(end 0.120396 0.2794)
			(stroke
				(width 0.1)
				(type default)
			)
			(layer "F.Fab")
		)
		(fp_line
			(start -0.12065 0.3048)
			(end -0.67945 0.3048)
			(stroke
				(width 0.1)
				(type default)
			)
			(layer "F.Fab")
		)
		(fp_line
			(start -0.67945 0.3048)
			(end -0.67945 -0.305054)
			(stroke
				(width 0.1)
				(type default)
			)
			(layer "F.Fab")
		)
		(pad "1" smd rect
			(at -0.40005 0 270)
			(size 0.4572 0.508)
			(layers "F.Cu" "F.Mask" "F.Paste")
			(net "FAN_2_FAULT_R")
		)
		(pad "2" smd rect
			(at 0.40005 0 270)
			(size 0.4572 0.508)
			(layers "F.Cu" "F.Mask" "F.Paste")
			(net "FAN_2_FAULT")
		)
	)
	(footprint ""
		(layer "F.Cu")
		(at 36.322 -117.602)
		(property "Reference" "D137"
			(at 2.96926 -0.13843 0)
			(unlocked yes)
			(layer "F.SilkS")
			(effects
				(font
					(size 0.635 0.4064)
					(thickness 0.1524)
				)
				(justify left)
			)
		)
		(property "Value" ""
			(at 0 0 0)
			(layer "F.Fab")
			(effects
				(font
					(size 1.27 1.27)
				)
			)
		)
		(duplicate_pad_numbers_are_jumpers no)
		(fp_line
			(start -0.299974 -0.500126)
			(end -0.299974 0.500126)
			(stroke
				(width 0.1524)
				(type default)
			)
			(layer "F.SilkS")
		)
		(fp_line
			(start -0.299974 0.500126)
			(end 0.199898 0)
			(stroke
				(width 0.1524)
				(type default)
			)
			(layer "F.SilkS")
		)
		(fp_line
			(start 0.199898 0)
			(end -0.299974 -0.500126)
			(stroke
				(width 0.1524)
				(type default)
			)
			(layer "F.SilkS")
		)
		(fp_line
			(start 0.299974 -0.500126)
			(end 0.299974 0.500126)
			(stroke
				(width 0.1524)
				(type default)
			)
			(layer "F.SilkS")
		)
		(fp_line
			(start 1.651 -0.6858)
			(end 1.651 0.6858)
			(stroke
				(width 0.1524)
				(type default)
			)
			(layer "F.SilkS")
		)
		(fp_line
			(start 1.778 0.6858)
			(end 1.778 -0.6858)
			(stroke
				(width 0.1524)
				(type default)
			)
			(layer "F.SilkS")
		)
		(fp_line
			(start -1.35001 -0.225044)
			(end -0.899922 -0.225044)
			(stroke
				(width 0.1)
				(type default)
			)
			(layer "F.Fab")
		)
		(fp_line
			(start -1.35001 0.175006)
			(end -1.35001 -0.225044)
			(stroke
				(width 0.1)
				(type default)
			)
			(layer "F.Fab")
		)
		(fp_line
			(start -0.899922 -0.700024)
			(end 0.899922 -0.700024)
			(stroke
				(width 0.1)
				(type default)
			)
			(layer "F.Fab")
		)
		(fp_line
			(start -0.899922 -0.225044)
			(end -0.899922 -0.700024)
			(stroke
				(width 0.1)
				(type default)
			)
			(layer "F.Fab")
		)
		(fp_line
			(start -0.899922 0.175006)
			(end -1.35001 0.175006)
			(stroke
				(width 0.1)
				(type default)
			)
			(layer "F.Fab")
		)
		(fp_line
			(start -0.899922 0.700024)
			(end -0.899922 0.175006)
			(stroke
				(width 0.1)
				(type default)
			)
			(layer "F.Fab")
		)
		(fp_line
			(start -0.299974 -0.500126)
			(end -0.299974 0.500126)
			(stroke
				(width 0.1)
				(type default)
			)
			(layer "F.Fab")
		)
		(fp_line
			(start -0.299974 0.500126)
			(end 0.199898 0)
			(stroke
				(width 0.1)
				(type default)
			)
			(layer "F.Fab")
		)
		(fp_line
			(start 0.199898 0)
			(end -0.299974 -0.500126)
			(stroke
				(width 0.1)
				(type default)
			)
			(layer "F.Fab")
		)
		(fp_line
			(start 0.299974 -0.500126)
			(end 0.299974 0.500126)
			(stroke
				(width 0.1)
				(type default)
			)
			(layer "F.Fab")
		)
		(fp_line
			(start 0.899922 -0.700024)
			(end 0.899922 -0.225044)
			(stroke
				(width 0.1)
				(type default)
			)
			(layer "F.Fab")
		)
		(fp_line
			(start 0.899922 -0.225044)
			(end 1.35001 -0.225044)
			(stroke
				(width 0.1)
				(type default)
			)
			(layer "F.Fab")
		)
		(fp_line
			(start 0.899922 0.175006)
			(end 0.899922 0.700024)
			(stroke
				(width 0.1)
				(type default)
			)
			(layer "F.Fab")
		)
		(fp_line
			(start 0.899922 0.700024)
			(end -0.899922 0.700024)
			(stroke
				(width 0.1)
				(type default)
			)
			(layer "F.Fab")
		)
		(fp_line
			(start 1.35001 -0.225044)
			(end 1.35001 0.175006)
			(stroke
				(width 0.1)
				(type default)
			)
			(layer "F.Fab")
		)
		(fp_line
			(start 1.35001 0.175006)
			(end 0.899922 0.175006)
			(stroke
				(width 0.1)
				(type default)
			)
			(layer "F.Fab")
		)
		(fp_text user "+"
			(at -2.667 0.79375 0)
			(unlocked yes)
			(layer "F.SilkS")
			(effects
				(font
					(size 1.905 1.4224)
					(thickness 0.1524)
				)
				(justify left)
			)
		)
		(fp_text user "-"
			(at 0.508 -1.23825 0)
			(unlocked yes)
			(layer "F.SilkS")
			(effects
				(font
					(size 1.905 1.4224)
					(thickness 0.1524)
				)
				(justify left)
			)
		)
		(fp_text user "+"
			(at -2.794 -0.19685 0)
			(unlocked yes)
			(layer "F.Fab")
			(effects
				(font
					(size 1.905 1.4224)
					(thickness 0.1524)
				)
				(justify left)
			)
		)
		(fp_text user "-"
			(at 1.8288 -0.24765 0)
			(unlocked yes)
			(layer "F.Fab")
			(effects
				(font
					(size 1.905 1.4224)
					(thickness 0.1524)
				)
				(justify left)
			)
		)
		(pad "1" smd rect
			(at -1.0922 0 180)
			(size 0.8128 0.8636)
			(layers "F.Cu" "F.Mask" "F.Paste")
			(net "FAN_2_TACH_IL_R")
		)
		(pad "2" smd rect
			(at 1.0922 0)
			(size 0.8128 0.8636)
			(layers "F.Cu" "F.Mask" "F.Paste")
			(net "FAN_2_TACH_IL_D")
		)
	)
	(footprint ""
		(layer "F.Cu")
		(at 4.191 -167.64 180)
		(property "Reference" "R105"
			(at 0 0 180)
			(layer "F.SilkS")
			(hide yes)
			(effects
				(font
					(size 1.27 1.27)
				)
			)
		)
		(property "Value" ""
			(at 0 0 180)
			(layer "F.Fab")
			(effects
				(font
					(size 1.27 1.27)
				)
			)
		)
		(duplicate_pad_numbers_are_jumpers no)
		(fp_line
			(start 0.7874 0.4064)
			(end -0.7874 0.4064)
			(stroke
				(width 0.1524)
				(type default)
			)
			(layer "F.SilkS")
		)
		(fp_line
			(start 0.7874 -0.4064)
			(end 0.7874 0.4064)
			(stroke
				(width 0.1524)
				(type default)
			)
			(layer "F.SilkS")
		)
		(fp_line
			(start -0.7874 0.4064)
			(end -0.7874 -0.4064)
			(stroke
				(width 0.1524)
				(type default)
			)
			(layer "F.SilkS")
		)
		(fp_line
			(start -0.7874 -0.4064)
			(end 0.7874 -0.4064)
			(stroke
				(width 0.1524)
				(type default)
			)
			(layer "F.SilkS")
		)
		(fp_line
			(start 0.67945 0.3048)
			(end 0.120396 0.3048)
			(stroke
				(width 0.1)
				(type default)
			)
			(layer "F.Fab")
		)
		(fp_line
			(start 0.67945 -0.3048)
			(end 0.67945 0.3048)
			(stroke
				(width 0.1)
				(type default)
			)
			(layer "F.Fab")
		)
		(fp_line
			(start 0.12065 -0.2794)
			(end 0.12065 -0.3048)
			(stroke
				(width 0.1)
				(type default)
			)
			(layer "F.Fab")
		)
		(fp_line
			(start 0.12065 -0.3048)
			(end 0.67945 -0.3048)
			(stroke
				(width 0.1)
				(type default)
			)
			(layer "F.Fab")
		)
		(fp_line
			(start 0.120396 0.3048)
			(end 0.120396 0.2794)
			(stroke
				(width 0.1)
				(type default)
			)
			(layer "F.Fab")
		)
		(fp_line
			(start 0.120396 0.2794)
			(end -0.12065 0.2794)
			(stroke
				(width 0.1)
				(type default)
			)
			(layer "F.Fab")
		)
		(fp_line
			(start -0.12065 0.3048)
			(end -0.67945 0.3048)
			(stroke
				(width 0.1)
				(type default)
			)
			(layer "F.Fab")
		)
		(fp_line
			(start -0.12065 0.2794)
			(end -0.12065 0.3048)
			(stroke
				(width 0.1)
				(type default)
			)
			(layer "F.Fab")
		)
		(fp_line
			(start -0.12065 -0.2794)
			(end 0.12065 -0.2794)
			(stroke
				(width 0.1)
				(type default)
			)
			(layer "F.Fab")
		)
		(fp_line
			(start -0.12065 -0.305054)
			(end -0.12065 -0.2794)
			(stroke
				(width 0.1)
				(type default)
			)
			(layer "F.Fab")
		)
		(fp_line
			(start -0.67945 0.3048)
			(end -0.67945 -0.305054)
			(stroke
				(width 0.1)
				(type default)
			)
			(layer "F.Fab")
		)
		(fp_line
			(start -0.67945 -0.305054)
			(end -0.12065 -0.305054)
			(stroke
				(width 0.1)
				(type default)
			)
			(layer "F.Fab")
		)
		(pad "1" smd circle
			(at -0.40005 0 180)
			(size 0 0)
			(layers "F.Cu" "F.Mask" "F.Paste")
			(net "FAN_3_PRSNT_BUF_R_N")
		)
		(pad "2" smd circle
			(at 0.40005 0 180)
			(size 0 0)
			(layers "F.Cu" "F.Mask" "F.Paste")
			(net "FAN_3_PRSNT_BUF_N")
		)
	)
	(footprint ""
		(layer "F.Cu")
		(at 45.466 -98.806 90)
		(property "Reference" "R5652"
			(at 0 0 90)
			(layer "F.SilkS")
			(hide yes)
			(effects
				(font
					(size 1.27 1.27)
				)
			)
		)
		(property "Value" ""
			(at 0 0 90)
			(layer "F.Fab")
			(effects
				(font
					(size 1.27 1.27)
				)
			)
		)
		(duplicate_pad_numbers_are_jumpers no)
		(fp_line
			(start 0.7874 -0.4064)
			(end 0.7874 0.4064)
			(stroke
				(width 0.1524)
				(type default)
			)
			(layer "F.SilkS")
		)
		(fp_line
			(start -0.7874 -0.4064)
			(end 0.7874 -0.4064)
			(stroke
				(width 0.1524)
				(type default)
			)
			(layer "F.SilkS")
		)
		(fp_line
			(start 0.7874 0.4064)
			(end -0.7874 0.4064)
			(stroke
				(width 0.1524)
				(type default)
			)
			(layer "F.SilkS")
		)
		(fp_line
			(start -0.7874 0.4064)
			(end -0.7874 -0.4064)
			(stroke
				(width 0.1524)
				(type default)
			)
			(layer "F.SilkS")
		)
		(fp_line
			(start -0.12065 -0.305054)
			(end -0.12065 -0.2794)
			(stroke
				(width 0.1)
				(type default)
			)
			(layer "F.Fab")
		)
		(fp_line
			(start -0.67945 -0.305054)
			(end -0.12065 -0.305054)
			(stroke
				(width 0.1)
				(type default)
			)
			(layer "F.Fab")
		)
		(fp_line
			(start 0.67945 -0.3048)
			(end 0.67945 0.3048)
			(stroke
				(width 0.1)
				(type default)
			)
			(layer "F.Fab")
		)
		(fp_line
			(start 0.12065 -0.3048)
			(end 0.67945 -0.3048)
			(stroke
				(width 0.1)
				(type default)
			)
			(layer "F.Fab")
		)
		(fp_line
			(start 0.12065 -0.2794)
			(end 0.12065 -0.3048)
			(stroke
				(width 0.1)
				(type default)
			)
			(layer "F.Fab")
		)
		(fp_line
			(start -0.12065 -0.2794)
			(end 0.12065 -0.2794)
			(stroke
				(width 0.1)
				(type default)
			)
			(layer "F.Fab")
		)
		(fp_line
			(start 0.120396 0.2794)
			(end -0.12065 0.2794)
			(stroke
				(width 0.1)
				(type default)
			)
			(layer "F.Fab")
		)
		(fp_line
			(start -0.12065 0.2794)
			(end -0.12065 0.3048)
			(stroke
				(width 0.1)
				(type default)
			)
			(layer "F.Fab")
		)
		(fp_line
			(start 0.67945 0.3048)
			(end 0.120396 0.3048)
			(stroke
				(width 0.1)
				(type default)
			)
			(layer "F.Fab")
		)
		(fp_line
			(start 0.120396 0.3048)
			(end 0.120396 0.2794)
			(stroke
				(width 0.1)
				(type default)
			)
			(layer "F.Fab")
		)
		(fp_line
			(start -0.12065 0.3048)
			(end -0.67945 0.3048)
			(stroke
				(width 0.1)
				(type default)
			)
			(layer "F.Fab")
		)
		(fp_line
			(start -0.67945 0.3048)
			(end -0.67945 -0.305054)
			(stroke
				(width 0.1)
				(type default)
			)
			(layer "F.Fab")
		)
		(pad "1" smd rect
			(at -0.40005 0 270)
			(size 0.4572 0.508)
			(layers "F.Cu" "F.Mask" "F.Paste")
			(net "P12V_LED")
		)
		(pad "2" smd rect
			(at 0.40005 0 270)
			(size 0.4572 0.508)
			(layers "F.Cu" "F.Mask" "F.Paste")
			(net "U407_D1")
		)
	)
	(footprint ""
		(layer "F.Cu")
		(at 37.338 -201.041)
		(property "Reference" "D270"
			(at 1.905 0.02667 0)
			(unlocked yes)
			(layer "F.SilkS")
			(effects
				(font
					(size 0.7874 0.5842)
					(thickness 0.1524)
				)
				(justify left)
			)
		)
		(property "Value" ""
			(at 0 0 0)
			(layer "F.Fab")
			(effects
				(font
					(size 1.27 1.27)
				)
			)
		)
		(duplicate_pad_numbers_are_jumpers no)
		(fp_line
			(start -0.854964 -0.450088)
			(end -0.854964 0.450088)
			(stroke
				(width 0.1524)
				(type default)
			)
			(layer "F.SilkS")
		)
		(fp_line
			(start -0.854964 0.450088)
			(end 0.925068 0.450088)
			(stroke
				(width 0.1524)
				(type default)
			)
			(layer "F.SilkS")
		)
		(fp_line
			(start 0.845058 0.4064)
			(end 0.845058 -0.381)
			(stroke
				(width 0.1524)
				(type default)
			)
			(layer "F.SilkS")
		)
		(fp_line
			(start 0.870458 -0.2794)
			(end 0.845058 0.4064)
			(stroke
				(width 0.1524)
				(type default)
			)
			(layer "F.SilkS")
		)
		(fp_line
			(start 0.94488 -0.450088)
			(end -0.854964 -0.450088)
			(stroke
				(width 0.1524)
				(type default)
			)
			(layer "F.SilkS")
		)
		(fp_line
			(start 0.94488 0.450088)
			(end 0.94488 -0.450088)
			(stroke
				(width 0.1524)
				(type default)
			)
			(layer "F.SilkS")
		)
		(fp_line
			(start -0.54991 -0.350012)
			(end -0.54991 0.350012)
			(stroke
				(width 0.1)
				(type default)
			)
			(layer "F.Fab")
		)
		(fp_line
			(start -0.54991 0.350012)
			(end 0.54991 0.350012)
			(stroke
				(width 0.1)
				(type default)
			)
			(layer "F.Fab")
		)
		(fp_line
			(start 0.54991 -0.350012)
			(end -0.54991 -0.350012)
			(stroke
				(width 0.1)
				(type default)
			)
			(layer "F.Fab")
		)
		(fp_line
			(start 0.54991 0.350012)
			(end 0.54991 -0.350012)
			(stroke
				(width 0.1)
				(type default)
			)
			(layer "F.Fab")
		)
		(fp_text user "+"
			(at -0.635 0.22225 180)
			(unlocked yes)
			(layer "F.SilkS")
			(effects
				(font
					(size 1.905 1.4224)
					(thickness 0.1524)
				)
				(justify left)
			)
		)
		(fp_text user "-"
			(at 2.159 0.22225 180)
			(unlocked yes)
			(layer "F.SilkS")
			(effects
				(font
					(size 1.905 1.4224)
					(thickness 0.1524)
				)
				(justify left)
			)
		)
		(fp_text user "+"
			(at -0.808228 0.239014 180)
			(unlocked yes)
			(layer "F.Fab")
			(effects
				(font
					(size 1.905 1.4224)
					(thickness 0.1524)
				)
				(justify left)
			)
		)
		(fp_text user "-"
			(at 2.48539 0.239014 180)
			(unlocked yes)
			(layer "F.Fab")
			(effects
				(font
					(size 1.905 1.4224)
					(thickness 0.1524)
				)
				(justify left)
			)
		)
		(pad "A" smd rect
			(at -0.424942 0)
			(size 0.5588 0.6096)
			(layers "F.Cu" "F.Mask" "F.Paste")
			(net "GND")
		)
		(pad "C" smd rect
			(at 0.424942 0 180)
			(size 0.5588 0.6096)
			(layers "F.Cu" "F.Mask" "F.Paste")
			(net "FAN_1_OK_R_LED_N")
		)
	)
	(footprint ""
		(layer "F.Cu")
		(at 15.621 -166.4716)
		(property "Reference" "C56"
			(at 0 0 0)
			(layer "F.SilkS")
			(hide yes)
			(effects
				(font
					(size 1.27 1.27)
				)
			)
		)
		(property "Value" ""
			(at 0 0 0)
			(layer "F.Fab")
			(effects
				(font
					(size 1.27 1.27)
				)
			)
		)
		(duplicate_pad_numbers_are_jumpers no)
		(fp_line
			(start -0.7874 -0.4064)
			(end 0.7874 -0.4064)
			(stroke
				(width 0.1524)
				(type default)
			)
			(layer "F.SilkS")
		)
		(fp_line
			(start -0.7874 0.4064)
			(end -0.7874 -0.4064)
			(stroke
				(width 0.1524)
				(type default)
			)
			(layer "F.SilkS")
		)
		(fp_line
			(start 0.7874 -0.4064)
			(end 0.7874 0.4064)
			(stroke
				(width 0.1524)
				(type default)
			)
			(layer "F.SilkS")
		)
		(fp_line
			(start 0.7874 0.4064)
			(end -0.7874 0.4064)
			(stroke
				(width 0.1524)
				(type default)
			)
			(layer "F.SilkS")
		)
		(fp_line
			(start -0.67945 -0.305054)
			(end -0.12065 -0.305054)
			(stroke
				(width 0.1)
				(type default)
			)
			(layer "F.Fab")
		)
		(fp_line
			(start -0.67945 0.3048)
			(end -0.67945 -0.305054)
			(stroke
				(width 0.1)
				(type default)
			)
			(layer "F.Fab")
		)
		(fp_line
			(start -0.12065 -0.305054)
			(end -0.12065 -0.2794)
			(stroke
				(width 0.1)
				(type default)
			)
			(layer "F.Fab")
		)
		(fp_line
			(start -0.12065 -0.2794)
			(end 0.12065 -0.2794)
			(stroke
				(width 0.1)
				(type default)
			)
			(layer "F.Fab")
		)
		(fp_line
			(start -0.12065 0.2794)
			(end -0.12065 0.3048)
			(stroke
				(width 0.1)
				(type default)
			)
			(layer "F.Fab")
		)
		(fp_line
			(start -0.12065 0.3048)
			(end -0.67945 0.3048)
			(stroke
				(width 0.1)
				(type default)
			)
			(layer "F.Fab")
		)
		(fp_line
			(start 0.120396 0.2794)
			(end -0.12065 0.2794)
			(stroke
				(width 0.1)
				(type default)
			)
			(layer "F.Fab")
		)
		(fp_line
			(start 0.120396 0.3048)
			(end 0.120396 0.2794)
			(stroke
				(width 0.1)
				(type default)
			)
			(layer "F.Fab")
		)
		(fp_line
			(start 0.12065 -0.3048)
			(end 0.67945 -0.3048)
			(stroke
				(width 0.1)
				(type default)
			)
			(layer "F.Fab")
		)
		(fp_line
			(start 0.12065 -0.2794)
			(end 0.12065 -0.3048)
			(stroke
				(width 0.1)
				(type default)
			)
			(layer "F.Fab")
		)
		(fp_line
			(start 0.67945 -0.3048)
			(end 0.67945 0.3048)
			(stroke
				(width 0.1)
				(type default)
			)
			(layer "F.Fab")
		)
		(fp_line
			(start 0.67945 0.3048)
			(end 0.120396 0.3048)
			(stroke
				(width 0.1)
				(type default)
			)
			(layer "F.Fab")
		)
		(pad "1" smd circle
			(at -0.40005 0)
			(size 0 0)
			(layers "F.Cu" "F.Mask" "F.Paste")
			(net "FAN_2_PRESENT_N")
		)
		(pad "2" smd circle
			(at 0.40005 0)
			(size 0 0)
			(layers "F.Cu" "F.Mask" "F.Paste")
			(net "GND")
		)
	)
	(footprint ""
		(layer "F.Cu")
		(at 37.846 -128.778 180)
		(property "Reference" "R5604"
			(at 0 0 180)
			(layer "F.SilkS")
			(hide yes)
			(effects
				(font
					(size 1.27 1.27)
				)
			)
		)
		(property "Value" ""
			(at 0 0 180)
			(layer "F.Fab")
			(effects
				(font
					(size 1.27 1.27)
				)
			)
		)
		(duplicate_pad_numbers_are_jumpers no)
		(fp_line
			(start 0.7874 0.4064)
			(end -0.7874 0.4064)
			(stroke
				(width 0.1524)
				(type default)
			)
			(layer "F.SilkS")
		)
		(fp_line
			(start 0.7874 -0.4064)
			(end 0.7874 0.4064)
			(stroke
				(width 0.1524)
				(type default)
			)
			(layer "F.SilkS")
		)
		(fp_line
			(start -0.7874 0.4064)
			(end -0.7874 -0.4064)
			(stroke
				(width 0.1524)
				(type default)
			)
			(layer "F.SilkS")
		)
		(fp_line
			(start -0.7874 -0.4064)
			(end 0.7874 -0.4064)
			(stroke
				(width 0.1524)
				(type default)
			)
			(layer "F.SilkS")
		)
		(fp_line
			(start 0.67945 0.3048)
			(end 0.120396 0.3048)
			(stroke
				(width 0.1)
				(type default)
			)
			(layer "F.Fab")
		)
		(fp_line
			(start 0.67945 -0.3048)
			(end 0.67945 0.3048)
			(stroke
				(width 0.1)
				(type default)
			)
			(layer "F.Fab")
		)
		(fp_line
			(start 0.12065 -0.2794)
			(end 0.12065 -0.3048)
			(stroke
				(width 0.1)
				(type default)
			)
			(layer "F.Fab")
		)
		(fp_line
			(start 0.12065 -0.3048)
			(end 0.67945 -0.3048)
			(stroke
				(width 0.1)
				(type default)
			)
			(layer "F.Fab")
		)
		(fp_line
			(start 0.120396 0.3048)
			(end 0.120396 0.2794)
			(stroke
				(width 0.1)
				(type default)
			)
			(layer "F.Fab")
		)
		(fp_line
			(start 0.120396 0.2794)
			(end -0.12065 0.2794)
			(stroke
				(width 0.1)
				(type default)
			)
			(layer "F.Fab")
		)
		(fp_line
			(start -0.12065 0.3048)
			(end -0.67945 0.3048)
			(stroke
				(width 0.1)
				(type default)
			)
			(layer "F.Fab")
		)
		(fp_line
			(start -0.12065 0.2794)
			(end -0.12065 0.3048)
			(stroke
				(width 0.1)
				(type default)
			)
			(layer "F.Fab")
		)
		(fp_line
			(start -0.12065 -0.2794)
			(end 0.12065 -0.2794)
			(stroke
				(width 0.1)
				(type default)
			)
			(layer "F.Fab")
		)
		(fp_line
			(start -0.12065 -0.305054)
			(end -0.12065 -0.2794)
			(stroke
				(width 0.1)
				(type default)
			)
			(layer "F.Fab")
		)
		(fp_line
			(start -0.67945 0.3048)
			(end -0.67945 -0.305054)
			(stroke
				(width 0.1)
				(type default)
			)
			(layer "F.Fab")
		)
		(fp_line
			(start -0.67945 -0.305054)
			(end -0.12065 -0.305054)
			(stroke
				(width 0.1)
				(type default)
			)
			(layer "F.Fab")
		)
		(pad "1" smd rect
			(at -0.40005 0)
			(size 0.4572 0.508)
			(layers "F.Cu" "F.Mask" "F.Paste")
			(net "FAN_2_TACH_IL")
		)
		(pad "2" smd rect
			(at 0.40005 0)
			(size 0.4572 0.508)
			(layers "F.Cu" "F.Mask" "F.Paste")
			(net "FAN_2_TACH_IL_R1")
		)
	)
	(footprint ""
		(layer "F.Cu")
		(at 35.306 -304.165 180)
		(property "Reference" "C2020"
			(at 0 0 180)
			(layer "F.SilkS")
			(hide yes)
			(effects
				(font
					(size 1.27 1.27)
				)
			)
		)
		(property "Value" ""
			(at 0 0 180)
			(layer "F.Fab")
			(effects
				(font
					(size 1.27 1.27)
				)
			)
		)
		(duplicate_pad_numbers_are_jumpers no)
		(fp_line
			(start 0.7874 0.4064)
			(end -0.7874 0.4064)
			(stroke
				(width 0.1524)
				(type default)
			)
			(layer "F.SilkS")
		)
		(fp_line
			(start 0.7874 -0.4064)
			(end 0.7874 0.4064)
			(stroke
				(width 0.1524)
				(type default)
			)
			(layer "F.SilkS")
		)
		(fp_line
			(start -0.7874 0.4064)
			(end -0.7874 -0.4064)
			(stroke
				(width 0.1524)
				(type default)
			)
			(layer "F.SilkS")
		)
		(fp_line
			(start -0.7874 -0.4064)
			(end 0.7874 -0.4064)
			(stroke
				(width 0.1524)
				(type default)
			)
			(layer "F.SilkS")
		)
		(fp_line
			(start 0.67945 0.3048)
			(end 0.120396 0.3048)
			(stroke
				(width 0.1)
				(type default)
			)
			(layer "F.Fab")
		)
		(fp_line
			(start 0.67945 -0.3048)
			(end 0.67945 0.3048)
			(stroke
				(width 0.1)
				(type default)
			)
			(layer "F.Fab")
		)
		(fp_line
			(start 0.12065 -0.2794)
			(end 0.12065 -0.3048)
			(stroke
				(width 0.1)
				(type default)
			)
			(layer "F.Fab")
		)
		(fp_line
			(start 0.12065 -0.3048)
			(end 0.67945 -0.3048)
			(stroke
				(width 0.1)
				(type default)
			)
			(layer "F.Fab")
		)
		(fp_line
			(start 0.120396 0.3048)
			(end 0.120396 0.2794)
			(stroke
				(width 0.1)
				(type default)
			)
			(layer "F.Fab")
		)
		(fp_line
			(start 0.120396 0.2794)
			(end -0.12065 0.2794)
			(stroke
				(width 0.1)
				(type default)
			)
			(layer "F.Fab")
		)
		(fp_line
			(start -0.12065 0.3048)
			(end -0.67945 0.3048)
			(stroke
				(width 0.1)
				(type default)
			)
			(layer "F.Fab")
		)
		(fp_line
			(start -0.12065 0.2794)
			(end -0.12065 0.3048)
			(stroke
				(width 0.1)
				(type default)
			)
			(layer "F.Fab")
		)
		(fp_line
			(start -0.12065 -0.2794)
			(end 0.12065 -0.2794)
			(stroke
				(width 0.1)
				(type default)
			)
			(layer "F.Fab")
		)
		(fp_line
			(start -0.12065 -0.305054)
			(end -0.12065 -0.2794)
			(stroke
				(width 0.1)
				(type default)
			)
			(layer "F.Fab")
		)
		(fp_line
			(start -0.67945 0.3048)
			(end -0.67945 -0.305054)
			(stroke
				(width 0.1)
				(type default)
			)
			(layer "F.Fab")
		)
		(fp_line
			(start -0.67945 -0.305054)
			(end -0.12065 -0.305054)
			(stroke
				(width 0.1)
				(type default)
			)
			(layer "F.Fab")
		)
		(pad "1" smd circle
			(at -0.40005 0 180)
			(size 0 0)
			(layers "F.Cu" "F.Mask" "F.Paste")
			(net "FAN_0_PWM_OL_R")
		)
		(pad "2" smd circle
			(at 0.40005 0 180)
			(size 0 0)
			(layers "F.Cu" "F.Mask" "F.Paste")
			(net "GND")
		)
	)
	(footprint ""
		(layer "F.Cu")
		(at 5.461 -186.436)
		(property "Reference" "R310"
			(at 0 0 0)
			(layer "F.SilkS")
			(hide yes)
			(effects
				(font
					(size 1.27 1.27)
				)
			)
		)
		(property "Value" ""
			(at 0 0 0)
			(layer "F.Fab")
			(effects
				(font
					(size 1.27 1.27)
				)
			)
		)
		(duplicate_pad_numbers_are_jumpers no)
		(fp_line
			(start -0.7874 -0.4064)
			(end 0.7874 -0.4064)
			(stroke
				(width 0.1524)
				(type default)
			)
			(layer "F.SilkS")
		)
		(fp_line
			(start -0.7874 0.4064)
			(end -0.7874 -0.4064)
			(stroke
				(width 0.1524)
				(type default)
			)
			(layer "F.SilkS")
		)
		(fp_line
			(start 0.7874 -0.4064)
			(end 0.7874 0.4064)
			(stroke
				(width 0.1524)
				(type default)
			)
			(layer "F.SilkS")
		)
		(fp_line
			(start 0.7874 0.4064)
			(end -0.7874 0.4064)
			(stroke
				(width 0.1524)
				(type default)
			)
			(layer "F.SilkS")
		)
		(fp_line
			(start -0.67945 -0.305054)
			(end -0.12065 -0.305054)
			(stroke
				(width 0.1)
				(type default)
			)
			(layer "F.Fab")
		)
		(fp_line
			(start -0.67945 0.3048)
			(end -0.67945 -0.305054)
			(stroke
				(width 0.1)
				(type default)
			)
			(layer "F.Fab")
		)
		(fp_line
			(start -0.12065 -0.305054)
			(end -0.12065 -0.2794)
			(stroke
				(width 0.1)
				(type default)
			)
			(layer "F.Fab")
		)
		(fp_line
			(start -0.12065 -0.2794)
			(end 0.12065 -0.2794)
			(stroke
				(width 0.1)
				(type default)
			)
			(layer "F.Fab")
		)
		(fp_line
			(start -0.12065 0.2794)
			(end -0.12065 0.3048)
			(stroke
				(width 0.1)
				(type default)
			)
			(layer "F.Fab")
		)
		(fp_line
			(start -0.12065 0.3048)
			(end -0.67945 0.3048)
			(stroke
				(width 0.1)
				(type default)
			)
			(layer "F.Fab")
		)
		(fp_line
			(start 0.120396 0.2794)
			(end -0.12065 0.2794)
			(stroke
				(width 0.1)
				(type default)
			)
			(layer "F.Fab")
		)
		(fp_line
			(start 0.120396 0.3048)
			(end 0.120396 0.2794)
			(stroke
				(width 0.1)
				(type default)
			)
			(layer "F.Fab")
		)
		(fp_line
			(start 0.12065 -0.3048)
			(end 0.67945 -0.3048)
			(stroke
				(width 0.1)
				(type default)
			)
			(layer "F.Fab")
		)
		(fp_line
			(start 0.12065 -0.2794)
			(end 0.12065 -0.3048)
			(stroke
				(width 0.1)
				(type default)
			)
			(layer "F.Fab")
		)
		(fp_line
			(start 0.67945 -0.3048)
			(end 0.67945 0.3048)
			(stroke
				(width 0.1)
				(type default)
			)
			(layer "F.Fab")
		)
		(fp_line
			(start 0.67945 0.3048)
			(end 0.120396 0.3048)
			(stroke
				(width 0.1)
				(type default)
			)
			(layer "F.Fab")
		)
		(pad "1" smd circle
			(at -0.40005 0)
			(size 0 0)
			(layers "F.Cu" "F.Mask" "F.Paste")
			(net "P3V3_AUX")
		)
		(pad "2" smd circle
			(at 0.40005 0)
			(size 0 0)
			(layers "F.Cu" "F.Mask" "F.Paste")
			(net "FRU_ADDR2")
		)
	)
	(footprint ""
		(layer "F.Cu")
		(at 2.794 -31.496)
		(property "Reference" "R5703"
			(at 0 0 0)
			(layer "F.SilkS")
			(hide yes)
			(effects
				(font
					(size 1.27 1.27)
				)
			)
		)
		(property "Value" ""
			(at 0 0 0)
			(layer "F.Fab")
			(effects
				(font
					(size 1.27 1.27)
				)
			)
		)
		(duplicate_pad_numbers_are_jumpers no)
		(fp_line
			(start -0.7874 -0.4064)
			(end 0.7874 -0.4064)
			(stroke
				(width 0.1524)
				(type default)
			)
			(layer "F.SilkS")
		)
		(fp_line
			(start -0.7874 0.4064)
			(end -0.7874 -0.4064)
			(stroke
				(width 0.1524)
				(type default)
			)
			(layer "F.SilkS")
		)
		(fp_line
			(start 0.7874 -0.4064)
			(end 0.7874 0.4064)
			(stroke
				(width 0.1524)
				(type default)
			)
			(layer "F.SilkS")
		)
		(fp_line
			(start 0.7874 0.4064)
			(end -0.7874 0.4064)
			(stroke
				(width 0.1524)
				(type default)
			)
			(layer "F.SilkS")
		)
		(fp_line
			(start -0.67945 -0.305054)
			(end -0.12065 -0.305054)
			(stroke
				(width 0.1)
				(type default)
			)
			(layer "F.Fab")
		)
		(fp_line
			(start -0.67945 0.3048)
			(end -0.67945 -0.305054)
			(stroke
				(width 0.1)
				(type default)
			)
			(layer "F.Fab")
		)
		(fp_line
			(start -0.12065 -0.305054)
			(end -0.12065 -0.2794)
			(stroke
				(width 0.1)
				(type default)
			)
			(layer "F.Fab")
		)
		(fp_line
			(start -0.12065 -0.2794)
			(end 0.12065 -0.2794)
			(stroke
				(width 0.1)
				(type default)
			)
			(layer "F.Fab")
		)
		(fp_line
			(start -0.12065 0.2794)
			(end -0.12065 0.3048)
			(stroke
				(width 0.1)
				(type default)
			)
			(layer "F.Fab")
		)
		(fp_line
			(start -0.12065 0.3048)
			(end -0.67945 0.3048)
			(stroke
				(width 0.1)
				(type default)
			)
			(layer "F.Fab")
		)
		(fp_line
			(start 0.120396 0.2794)
			(end -0.12065 0.2794)
			(stroke
				(width 0.1)
				(type default)
			)
			(layer "F.Fab")
		)
		(fp_line
			(start 0.120396 0.3048)
			(end 0.120396 0.2794)
			(stroke
				(width 0.1)
				(type default)
			)
			(layer "F.Fab")
		)
		(fp_line
			(start 0.12065 -0.3048)
			(end 0.67945 -0.3048)
			(stroke
				(width 0.1)
				(type default)
			)
			(layer "F.Fab")
		)
		(fp_line
			(start 0.12065 -0.2794)
			(end 0.12065 -0.3048)
			(stroke
				(width 0.1)
				(type default)
			)
			(layer "F.Fab")
		)
		(fp_line
			(start 0.67945 -0.3048)
			(end 0.67945 0.3048)
			(stroke
				(width 0.1)
				(type default)
			)
			(layer "F.Fab")
		)
		(fp_line
			(start 0.67945 0.3048)
			(end 0.120396 0.3048)
			(stroke
				(width 0.1)
				(type default)
			)
			(layer "F.Fab")
		)
		(pad "1" smd rect
			(at -0.40005 0 180)
			(size 0.4572 0.508)
			(layers "F.Cu" "F.Mask" "F.Paste")
			(net "P12V_LED_FAN4")
		)
		(pad "2" smd rect
			(at 0.40005 0 180)
			(size 0.4572 0.508)
			(layers "F.Cu" "F.Mask" "F.Paste")
			(net "P12V_LED_R_FAN4")
		)
	)
	(footprint ""
		(layer "F.Cu")
		(at 6.477 -163.957)
		(property "Reference" "R99"
			(at 0 0 0)
			(layer "F.SilkS")
			(hide yes)
			(effects
				(font
					(size 1.27 1.27)
				)
			)
		)
		(property "Value" ""
			(at 0 0 0)
			(layer "F.Fab")
			(effects
				(font
					(size 1.27 1.27)
				)
			)
		)
		(duplicate_pad_numbers_are_jumpers no)
		(fp_line
			(start -0.7874 -0.4064)
			(end 0.7874 -0.4064)
			(stroke
				(width 0.1524)
				(type default)
			)
			(layer "F.SilkS")
		)
		(fp_line
			(start -0.7874 0.4064)
			(end -0.7874 -0.4064)
			(stroke
				(width 0.1524)
				(type default)
			)
			(layer "F.SilkS")
		)
		(fp_line
			(start 0.7874 -0.4064)
			(end 0.7874 0.4064)
			(stroke
				(width 0.1524)
				(type default)
			)
			(layer "F.SilkS")
		)
		(fp_line
			(start 0.7874 0.4064)
			(end -0.7874 0.4064)
			(stroke
				(width 0.1524)
				(type default)
			)
			(layer "F.SilkS")
		)
		(fp_line
			(start -0.67945 -0.305054)
			(end -0.12065 -0.305054)
			(stroke
				(width 0.1)
				(type default)
			)
			(layer "F.Fab")
		)
		(fp_line
			(start -0.67945 0.3048)
			(end -0.67945 -0.305054)
			(stroke
				(width 0.1)
				(type default)
			)
			(layer "F.Fab")
		)
		(fp_line
			(start -0.12065 -0.305054)
			(end -0.12065 -0.2794)
			(stroke
				(width 0.1)
				(type default)
			)
			(layer "F.Fab")
		)
		(fp_line
			(start -0.12065 -0.2794)
			(end 0.12065 -0.2794)
			(stroke
				(width 0.1)
				(type default)
			)
			(layer "F.Fab")
		)
		(fp_line
			(start -0.12065 0.2794)
			(end -0.12065 0.3048)
			(stroke
				(width 0.1)
				(type default)
			)
			(layer "F.Fab")
		)
		(fp_line
			(start -0.12065 0.3048)
			(end -0.67945 0.3048)
			(stroke
				(width 0.1)
				(type default)
			)
			(layer "F.Fab")
		)
		(fp_line
			(start 0.120396 0.2794)
			(end -0.12065 0.2794)
			(stroke
				(width 0.1)
				(type default)
			)
			(layer "F.Fab")
		)
		(fp_line
			(start 0.120396 0.3048)
			(end 0.120396 0.2794)
			(stroke
				(width 0.1)
				(type default)
			)
			(layer "F.Fab")
		)
		(fp_line
			(start 0.12065 -0.3048)
			(end 0.67945 -0.3048)
			(stroke
				(width 0.1)
				(type default)
			)
			(layer "F.Fab")
		)
		(fp_line
			(start 0.12065 -0.2794)
			(end 0.12065 -0.3048)
			(stroke
				(width 0.1)
				(type default)
			)
			(layer "F.Fab")
		)
		(fp_line
			(start 0.67945 -0.3048)
			(end 0.67945 0.3048)
			(stroke
				(width 0.1)
				(type default)
			)
			(layer "F.Fab")
		)
		(fp_line
			(start 0.67945 0.3048)
			(end 0.120396 0.3048)
			(stroke
				(width 0.1)
				(type default)
			)
			(layer "F.Fab")
		)
		(pad "1" smd circle
			(at -0.40005 0)
			(size 0 0)
			(layers "F.Cu" "F.Mask" "F.Paste")
			(net "P3V3_AUX")
		)
		(pad "2" smd circle
			(at 0.40005 0)
			(size 0 0)
			(layers "F.Cu" "F.Mask" "F.Paste")
			(net "FAN_1_PRSNT_BUF_R_N")
		)
	)
	(footprint ""
		(layer "F.Cu")
		(at 17.272 -294.64 180)
		(property "Reference" "U367"
			(at -2.667 1.11633 0)
			(unlocked yes)
			(layer "F.SilkS")
			(effects
				(font
					(size 0.7874 0.5842)
					(thickness 0.1524)
				)
				(justify left)
			)
		)
		(property "Value" ""
			(at 0 0 180)
			(layer "F.Fab")
			(effects
				(font
					(size 1.27 1.27)
				)
			)
		)
		(duplicate_pad_numbers_are_jumpers no)
		(fp_line
			(start 1.335278 1.100074)
			(end 1.335278 -1.100074)
			(stroke
				(width 0.1524)
				(type default)
			)
			(layer "F.SilkS")
		)
		(fp_line
			(start 1.335278 -1.100074)
			(end -1.335278 -1.100074)
			(stroke
				(width 0.1524)
				(type default)
			)
			(layer "F.SilkS")
		)
		(fp_line
			(start -1.335278 1.100074)
			(end 1.335278 1.100074)
			(stroke
				(width 0.1524)
				(type default)
			)
			(layer "F.SilkS")
		)
		(fp_line
			(start -1.335278 -1.100074)
			(end -1.335278 1.100074)
			(stroke
				(width 0.1524)
				(type default)
			)
			(layer "F.SilkS")
		)
		(fp_line
			(start 0.674878 1.100074)
			(end 0.674878 -1.100074)
			(stroke
				(width 0.1)
				(type default)
			)
			(layer "F.Fab")
		)
		(fp_line
			(start 0.674878 -1.100074)
			(end -0.674878 -1.100074)
			(stroke
				(width 0.1)
				(type default)
			)
			(layer "F.Fab")
		)
		(fp_line
			(start -0.674878 1.100074)
			(end 0.674878 1.100074)
			(stroke
				(width 0.1)
				(type default)
			)
			(layer "F.Fab")
		)
		(fp_line
			(start -0.674878 -1.100074)
			(end -0.674878 1.100074)
			(stroke
				(width 0.1)
				(type default)
			)
			(layer "F.Fab")
		)
		(pad "D" smd rect
			(at 0.8001 0 90)
			(size 0.6096 0.8128)
			(layers "F.Cu" "F.Mask" "F.Paste")
			(net "FAN_7_FAIL_LED_R_N")
		)
		(pad "G" smd rect
			(at -0.8001 -0.649986 90)
			(size 0.6096 0.8128)
			(layers "F.Cu" "F.Mask" "F.Paste")
			(net "FAN_7_FAIL_R_LED")
		)
		(pad "S" smd rect
			(at -0.8001 0.649986 90)
			(size 0.6096 0.8128)
			(layers "F.Cu" "F.Mask" "F.Paste")
			(net "GND")
		)
	)
	(footprint ""
		(layer "F.Cu")
		(at 15.504922 -30.566868 180)
		(property "Reference" "D114"
			(at 6.056122 0.000762 0)
			(unlocked yes)
			(layer "F.SilkS")
			(effects
				(font
					(size 0.7874 0.5842)
					(thickness 0.1524)
				)
				(justify left)
			)
		)
		(property "Value" ""
			(at 0 0 180)
			(layer "F.Fab")
			(effects
				(font
					(size 1.27 1.27)
				)
			)
		)
		(duplicate_pad_numbers_are_jumpers no)
		(fp_line
			(start 1.905 -0.6858)
			(end 1.905 0.6858)
			(stroke
				(width 0.1524)
				(type default)
			)
			(layer "F.SilkS")
		)
		(fp_line
			(start 1.865122 0.7112)
			(end -1.651 0.7112)
			(stroke
				(width 0.1524)
				(type default)
			)
			(layer "F.SilkS")
		)
		(fp_line
			(start 1.778 0.6858)
			(end 1.778 -0.6858)
			(stroke
				(width 0.1524)
				(type default)
			)
			(layer "F.SilkS")
		)
		(fp_line
			(start 1.651 -0.6858)
			(end 1.651 0.6858)
			(stroke
				(width 0.1524)
				(type default)
			)
			(layer "F.SilkS")
		)
		(fp_line
			(start 0.299974 -0.500126)
			(end 0.299974 0.500126)
			(stroke
				(width 0.1524)
				(type default)
			)
			(layer "F.SilkS")
		)
		(fp_line
			(start 0.199898 0)
			(end -0.299974 -0.500126)
			(stroke
				(width 0.1524)
				(type default)
			)
			(layer "F.SilkS")
		)
		(fp_line
			(start -0.299974 0.500126)
			(end 0.199898 0)
			(stroke
				(width 0.1524)
				(type default)
			)
			(layer "F.SilkS")
		)
		(fp_line
			(start -0.299974 -0.500126)
			(end -0.299974 0.500126)
			(stroke
				(width 0.1524)
				(type default)
			)
			(layer "F.SilkS")
		)
		(fp_line
			(start -1.651 0.7112)
			(end -1.651 -0.7112)
			(stroke
				(width 0.1524)
				(type default)
			)
			(layer "F.SilkS")
		)
		(fp_line
			(start -1.651 -0.7112)
			(end 1.814322 -0.7112)
			(stroke
				(width 0.1524)
				(type default)
			)
			(layer "F.SilkS")
		)
		(fp_line
			(start 1.35001 0.175006)
			(end 0.899922 0.175006)
			(stroke
				(width 0.1)
				(type default)
			)
			(layer "F.Fab")
		)
		(fp_line
			(start 1.35001 -0.225044)
			(end 1.35001 0.175006)
			(stroke
				(width 0.1)
				(type default)
			)
			(layer "F.Fab")
		)
		(fp_line
			(start 0.899922 0.700024)
			(end -0.899922 0.700024)
			(stroke
				(width 0.1)
				(type default)
			)
			(layer "F.Fab")
		)
		(fp_line
			(start 0.899922 0.175006)
			(end 0.899922 0.700024)
			(stroke
				(width 0.1)
				(type default)
			)
			(layer "F.Fab")
		)
		(fp_line
			(start 0.899922 -0.225044)
			(end 1.35001 -0.225044)
			(stroke
				(width 0.1)
				(type default)
			)
			(layer "F.Fab")
		)
		(fp_line
			(start 0.899922 -0.700024)
			(end 0.899922 -0.225044)
			(stroke
				(width 0.1)
				(type default)
			)
			(layer "F.Fab")
		)
		(fp_line
			(start 0.299974 -0.500126)
			(end 0.299974 0.500126)
			(stroke
				(width 0.1)
				(type default)
			)
			(layer "F.Fab")
		)
		(fp_line
			(start 0.199898 0)
			(end -0.299974 -0.500126)
			(stroke
				(width 0.1)
				(type default)
			)
			(layer "F.Fab")
		)
		(fp_line
			(start -0.299974 0.500126)
			(end 0.199898 0)
			(stroke
				(width 0.1)
				(type default)
			)
			(layer "F.Fab")
		)
		(fp_line
			(start -0.299974 -0.500126)
			(end -0.299974 0.500126)
			(stroke
				(width 0.1)
				(type default)
			)
			(layer "F.Fab")
		)
		(fp_line
			(start -0.899922 0.700024)
			(end -0.899922 0.175006)
			(stroke
				(width 0.1)
				(type default)
			)
			(layer "F.Fab")
		)
		(fp_line
			(start -0.899922 0.175006)
			(end -1.35001 0.175006)
			(stroke
				(width 0.1)
				(type default)
			)
			(layer "F.Fab")
		)
		(fp_line
			(start -0.899922 -0.225044)
			(end -0.899922 -0.700024)
			(stroke
				(width 0.1)
				(type default)
			)
			(layer "F.Fab")
		)
		(fp_line
			(start -0.899922 -0.700024)
			(end 0.899922 -0.700024)
			(stroke
				(width 0.1)
				(type default)
			)
			(layer "F.Fab")
		)
		(fp_line
			(start -1.35001 0.175006)
			(end -1.35001 -0.225044)
			(stroke
				(width 0.1)
				(type default)
			)
			(layer "F.Fab")
		)
		(fp_line
			(start -1.35001 -0.225044)
			(end -0.899922 -0.225044)
			(stroke
				(width 0.1)
				(type default)
			)
			(layer "F.Fab")
		)
		(fp_text user "-"
			(at 1.026922 0.833882 180)
			(unlocked yes)
			(layer "F.SilkS")
			(effects
				(font
					(size 1.905 1.4224)
					(thickness 0.1524)
				)
				(justify left)
			)
		)
		(fp_text user "+"
			(at -2.529078 1.087882 180)
			(unlocked yes)
			(layer "F.SilkS")
			(effects
				(font
					(size 1.905 1.4224)
					(thickness 0.1524)
				)
				(justify left)
			)
		)
		(fp_text user "-"
			(at 1.8288 -0.24765 180)
			(unlocked yes)
			(layer "F.Fab")
			(effects
				(font
					(size 1.905 1.4224)
					(thickness 0.1524)
				)
				(justify left)
			)
		)
		(fp_text user "+"
			(at -2.794 -0.19685 180)
			(unlocked yes)
			(layer "F.Fab")
			(effects
				(font
					(size 1.905 1.4224)
					(thickness 0.1524)
				)
				(justify left)
			)
		)
		(pad "1" smd rect
			(at -1.0922 0)
			(size 0.8128 0.8636)
			(layers "F.Cu" "F.Mask" "F.Paste")
			(net "FAN_4_TACH_OL_R")
		)
		(pad "2" smd rect
			(at 1.0922 0 180)
			(size 0.8128 0.8636)
			(layers "F.Cu" "F.Mask" "F.Paste")
			(net "FAN_4_TACH_OL_D")
		)
	)
	(footprint ""
		(layer "F.Cu")
		(at 25.781 -289.433)
		(property "Reference" "U329"
			(at -1.6129 -1.75387 0)
			(unlocked yes)
			(layer "F.SilkS")
			(effects
				(font
					(size 0.7874 0.5842)
					(thickness 0.1524)
				)
				(justify left)
			)
		)
		(property "Value" ""
			(at 0 0 0)
			(layer "F.Fab")
			(effects
				(font
					(size 1.27 1.27)
				)
			)
		)
		(duplicate_pad_numbers_are_jumpers no)
		(fp_line
			(start -1.538478 -1.150874)
			(end -1.538478 1.150874)
			(stroke
				(width 0.1524)
				(type default)
			)
			(layer "F.SilkS")
		)
		(fp_line
			(start -1.538478 1.150874)
			(end 1.538478 1.150874)
			(stroke
				(width 0.1524)
				(type default)
			)
			(layer "F.SilkS")
		)
		(fp_line
			(start 1.538478 -1.150874)
			(end -1.538478 -1.150874)
			(stroke
				(width 0.1524)
				(type default)
			)
			(layer "F.SilkS")
		)
		(fp_line
			(start 1.538478 1.150874)
			(end 1.538478 -1.150874)
			(stroke
				(width 0.1524)
				(type default)
			)
			(layer "F.SilkS")
		)
		(fp_line
			(start -0.674878 -1.100074)
			(end -0.674878 1.100074)
			(stroke
				(width 0.1)
				(type default)
			)
			(layer "F.Fab")
		)
		(fp_line
			(start -0.674878 1.100074)
			(end 0.674878 1.100074)
			(stroke
				(width 0.1)
				(type default)
			)
			(layer "F.Fab")
		)
		(fp_line
			(start 0.674878 -1.100074)
			(end -0.674878 -1.100074)
			(stroke
				(width 0.1)
				(type default)
			)
			(layer "F.Fab")
		)
		(fp_line
			(start 0.674878 1.100074)
			(end 0.674878 -1.100074)
			(stroke
				(width 0.1)
				(type default)
			)
			(layer "F.Fab")
		)
		(pad "1" smd rect
			(at -0.94996 -0.649986 90)
			(size 0.7112 0.9144)
			(layers "F.Cu" "F.Mask" "F.Paste")
			(net "FAN_7_PWM_IL")
		)
		(pad "2" smd rect
			(at -0.94996 0.649986 90)
			(size 0.7112 0.9144)
			(layers "F.Cu" "F.Mask" "F.Paste")
			(net "FAN_7_PWM_OL")
		)
		(pad "3" smd rect
			(at 0.94996 0 90)
			(size 0.7112 0.9144)
			(layers "F.Cu" "F.Mask" "F.Paste")
			(net "FAN_7_PWM_BUF")
		)
	)
	(footprint ""
		(layer "F.Cu")
		(at 27.813 -102.108 90)
		(property "Reference" "R5516"
			(at 0 0 90)
			(layer "F.SilkS")
			(hide yes)
			(effects
				(font
					(size 1.27 1.27)
				)
			)
		)
		(property "Value" ""
			(at 0 0 90)
			(layer "F.Fab")
			(effects
				(font
					(size 1.27 1.27)
				)
			)
		)
		(duplicate_pad_numbers_are_jumpers no)
		(fp_line
			(start 0.7874 -0.4064)
			(end 0.7874 0.4064)
			(stroke
				(width 0.1524)
				(type default)
			)
			(layer "F.SilkS")
		)
		(fp_line
			(start -0.7874 -0.4064)
			(end 0.7874 -0.4064)
			(stroke
				(width 0.1524)
				(type default)
			)
			(layer "F.SilkS")
		)
		(fp_line
			(start 0.7874 0.4064)
			(end -0.7874 0.4064)
			(stroke
				(width 0.1524)
				(type default)
			)
			(layer "F.SilkS")
		)
		(fp_line
			(start -0.7874 0.4064)
			(end -0.7874 -0.4064)
			(stroke
				(width 0.1524)
				(type default)
			)
			(layer "F.SilkS")
		)
		(fp_line
			(start -0.12065 -0.305054)
			(end -0.12065 -0.2794)
			(stroke
				(width 0.1)
				(type default)
			)
			(layer "F.Fab")
		)
		(fp_line
			(start -0.67945 -0.305054)
			(end -0.12065 -0.305054)
			(stroke
				(width 0.1)
				(type default)
			)
			(layer "F.Fab")
		)
		(fp_line
			(start 0.67945 -0.3048)
			(end 0.67945 0.3048)
			(stroke
				(width 0.1)
				(type default)
			)
			(layer "F.Fab")
		)
		(fp_line
			(start 0.12065 -0.3048)
			(end 0.67945 -0.3048)
			(stroke
				(width 0.1)
				(type default)
			)
			(layer "F.Fab")
		)
		(fp_line
			(start 0.12065 -0.2794)
			(end 0.12065 -0.3048)
			(stroke
				(width 0.1)
				(type default)
			)
			(layer "F.Fab")
		)
		(fp_line
			(start -0.12065 -0.2794)
			(end 0.12065 -0.2794)
			(stroke
				(width 0.1)
				(type default)
			)
			(layer "F.Fab")
		)
		(fp_line
			(start 0.120396 0.2794)
			(end -0.12065 0.2794)
			(stroke
				(width 0.1)
				(type default)
			)
			(layer "F.Fab")
		)
		(fp_line
			(start -0.12065 0.2794)
			(end -0.12065 0.3048)
			(stroke
				(width 0.1)
				(type default)
			)
			(layer "F.Fab")
		)
		(fp_line
			(start 0.67945 0.3048)
			(end 0.120396 0.3048)
			(stroke
				(width 0.1)
				(type default)
			)
			(layer "F.Fab")
		)
		(fp_line
			(start 0.120396 0.3048)
			(end 0.120396 0.2794)
			(stroke
				(width 0.1)
				(type default)
			)
			(layer "F.Fab")
		)
		(fp_line
			(start -0.12065 0.3048)
			(end -0.67945 0.3048)
			(stroke
				(width 0.1)
				(type default)
			)
			(layer "F.Fab")
		)
		(fp_line
			(start -0.67945 0.3048)
			(end -0.67945 -0.305054)
			(stroke
				(width 0.1)
				(type default)
			)
			(layer "F.Fab")
		)
		(pad "1" smd circle
			(at -0.40005 0 90)
			(size 0 0)
			(layers "F.Cu" "F.Mask" "F.Paste")
			(net "P3V3_AUX")
		)
		(pad "2" smd circle
			(at 0.40005 0 90)
			(size 0 0)
			(layers "F.Cu" "F.Mask" "F.Paste")
			(net "FAN_5_PWM_BUF")
		)
	)
	(footprint ""
		(layer "F.Cu")
		(at 33.02 -124.206 90)
		(property "Reference" "R4778"
			(at 0 0 90)
			(layer "F.SilkS")
			(hide yes)
			(effects
				(font
					(size 1.27 1.27)
				)
			)
		)
		(property "Value" ""
			(at 0 0 90)
			(layer "F.Fab")
			(effects
				(font
					(size 1.27 1.27)
				)
			)
		)
		(duplicate_pad_numbers_are_jumpers no)
		(fp_line
			(start 0.7874 -0.4064)
			(end 0.7874 0.4064)
			(stroke
				(width 0.1524)
				(type default)
			)
			(layer "F.SilkS")
		)
		(fp_line
			(start -0.7874 -0.4064)
			(end 0.7874 -0.4064)
			(stroke
				(width 0.1524)
				(type default)
			)
			(layer "F.SilkS")
		)
		(fp_line
			(start 0.7874 0.4064)
			(end -0.7874 0.4064)
			(stroke
				(width 0.1524)
				(type default)
			)
			(layer "F.SilkS")
		)
		(fp_line
			(start -0.7874 0.4064)
			(end -0.7874 -0.4064)
			(stroke
				(width 0.1524)
				(type default)
			)
			(layer "F.SilkS")
		)
		(fp_line
			(start -0.12065 -0.305054)
			(end -0.12065 -0.2794)
			(stroke
				(width 0.1)
				(type default)
			)
			(layer "F.Fab")
		)
		(fp_line
			(start -0.67945 -0.305054)
			(end -0.12065 -0.305054)
			(stroke
				(width 0.1)
				(type default)
			)
			(layer "F.Fab")
		)
		(fp_line
			(start 0.67945 -0.3048)
			(end 0.67945 0.3048)
			(stroke
				(width 0.1)
				(type default)
			)
			(layer "F.Fab")
		)
		(fp_line
			(start 0.12065 -0.3048)
			(end 0.67945 -0.3048)
			(stroke
				(width 0.1)
				(type default)
			)
			(layer "F.Fab")
		)
		(fp_line
			(start 0.12065 -0.2794)
			(end 0.12065 -0.3048)
			(stroke
				(width 0.1)
				(type default)
			)
			(layer "F.Fab")
		)
		(fp_line
			(start -0.12065 -0.2794)
			(end 0.12065 -0.2794)
			(stroke
				(width 0.1)
				(type default)
			)
			(layer "F.Fab")
		)
		(fp_line
			(start 0.120396 0.2794)
			(end -0.12065 0.2794)
			(stroke
				(width 0.1)
				(type default)
			)
			(layer "F.Fab")
		)
		(fp_line
			(start -0.12065 0.2794)
			(end -0.12065 0.3048)
			(stroke
				(width 0.1)
				(type default)
			)
			(layer "F.Fab")
		)
		(fp_line
			(start 0.67945 0.3048)
			(end 0.120396 0.3048)
			(stroke
				(width 0.1)
				(type default)
			)
			(layer "F.Fab")
		)
		(fp_line
			(start 0.120396 0.3048)
			(end 0.120396 0.2794)
			(stroke
				(width 0.1)
				(type default)
			)
			(layer "F.Fab")
		)
		(fp_line
			(start -0.12065 0.3048)
			(end -0.67945 0.3048)
			(stroke
				(width 0.1)
				(type default)
			)
			(layer "F.Fab")
		)
		(fp_line
			(start -0.67945 0.3048)
			(end -0.67945 -0.305054)
			(stroke
				(width 0.1)
				(type default)
			)
			(layer "F.Fab")
		)
		(pad "1" smd circle
			(at -0.40005 0 90)
			(size 0 0)
			(layers "F.Cu" "F.Mask" "F.Paste")
			(net "P3V3_AUX")
		)
		(pad "2" smd circle
			(at 0.40005 0 90)
			(size 0 0)
			(layers "F.Cu" "F.Mask" "F.Paste")
			(net "MAX31790_U317_ADD0")
		)
	)
	(footprint ""
		(layer "F.Cu")
		(at 6.477 -170.815)
		(property "Reference" "R4856"
			(at 0 0 0)
			(layer "F.SilkS")
			(hide yes)
			(effects
				(font
					(size 1.27 1.27)
				)
			)
		)
		(property "Value" ""
			(at 0 0 0)
			(layer "F.Fab")
			(effects
				(font
					(size 1.27 1.27)
				)
			)
		)
		(duplicate_pad_numbers_are_jumpers no)
		(fp_line
			(start -0.7874 -0.4064)
			(end 0.7874 -0.4064)
			(stroke
				(width 0.1524)
				(type default)
			)
			(layer "F.SilkS")
		)
		(fp_line
			(start -0.7874 0.4064)
			(end -0.7874 -0.4064)
			(stroke
				(width 0.1524)
				(type default)
			)
			(layer "F.SilkS")
		)
		(fp_line
			(start 0.7874 -0.4064)
			(end 0.7874 0.4064)
			(stroke
				(width 0.1524)
				(type default)
			)
			(layer "F.SilkS")
		)
		(fp_line
			(start 0.7874 0.4064)
			(end -0.7874 0.4064)
			(stroke
				(width 0.1524)
				(type default)
			)
			(layer "F.SilkS")
		)
		(fp_line
			(start -0.67945 -0.305054)
			(end -0.12065 -0.305054)
			(stroke
				(width 0.1)
				(type default)
			)
			(layer "F.Fab")
		)
		(fp_line
			(start -0.67945 0.3048)
			(end -0.67945 -0.305054)
			(stroke
				(width 0.1)
				(type default)
			)
			(layer "F.Fab")
		)
		(fp_line
			(start -0.12065 -0.305054)
			(end -0.12065 -0.2794)
			(stroke
				(width 0.1)
				(type default)
			)
			(layer "F.Fab")
		)
		(fp_line
			(start -0.12065 -0.2794)
			(end 0.12065 -0.2794)
			(stroke
				(width 0.1)
				(type default)
			)
			(layer "F.Fab")
		)
		(fp_line
			(start -0.12065 0.2794)
			(end -0.12065 0.3048)
			(stroke
				(width 0.1)
				(type default)
			)
			(layer "F.Fab")
		)
		(fp_line
			(start -0.12065 0.3048)
			(end -0.67945 0.3048)
			(stroke
				(width 0.1)
				(type default)
			)
			(layer "F.Fab")
		)
		(fp_line
			(start 0.120396 0.2794)
			(end -0.12065 0.2794)
			(stroke
				(width 0.1)
				(type default)
			)
			(layer "F.Fab")
		)
		(fp_line
			(start 0.120396 0.3048)
			(end 0.120396 0.2794)
			(stroke
				(width 0.1)
				(type default)
			)
			(layer "F.Fab")
		)
		(fp_line
			(start 0.12065 -0.3048)
			(end 0.67945 -0.3048)
			(stroke
				(width 0.1)
				(type default)
			)
			(layer "F.Fab")
		)
		(fp_line
			(start 0.12065 -0.2794)
			(end 0.12065 -0.3048)
			(stroke
				(width 0.1)
				(type default)
			)
			(layer "F.Fab")
		)
		(fp_line
			(start 0.67945 -0.3048)
			(end 0.67945 0.3048)
			(stroke
				(width 0.1)
				(type default)
			)
			(layer "F.Fab")
		)
		(fp_line
			(start 0.67945 0.3048)
			(end 0.120396 0.3048)
			(stroke
				(width 0.1)
				(type default)
			)
			(layer "F.Fab")
		)
		(pad "1" smd circle
			(at -0.40005 0)
			(size 0 0)
			(layers "F.Cu" "F.Mask" "F.Paste")
			(net "P3V3_AUX")
		)
		(pad "2" smd circle
			(at 0.40005 0)
			(size 0 0)
			(layers "F.Cu" "F.Mask" "F.Paste")
			(net "FAN_5_PRSNT_BUF_R_N")
		)
	)
	(footprint ""
		(layer "F.Cu")
		(at 8.709914 -252.857)
		(property "Reference" "R5423"
			(at 0 0 0)
			(layer "F.SilkS")
			(hide yes)
			(effects
				(font
					(size 1.27 1.27)
				)
			)
		)
		(property "Value" ""
			(at 0 0 0)
			(layer "F.Fab")
			(effects
				(font
					(size 1.27 1.27)
				)
			)
		)
		(duplicate_pad_numbers_are_jumpers no)
		(fp_line
			(start -0.7874 -0.4064)
			(end 0.7874 -0.4064)
			(stroke
				(width 0.1524)
				(type default)
			)
			(layer "F.SilkS")
		)
		(fp_line
			(start -0.7874 0.4064)
			(end -0.7874 -0.4064)
			(stroke
				(width 0.1524)
				(type default)
			)
			(layer "F.SilkS")
		)
		(fp_line
			(start 0.7874 -0.4064)
			(end 0.7874 0.4064)
			(stroke
				(width 0.1524)
				(type default)
			)
			(layer "F.SilkS")
		)
		(fp_line
			(start 0.7874 0.4064)
			(end -0.7874 0.4064)
			(stroke
				(width 0.1524)
				(type default)
			)
			(layer "F.SilkS")
		)
		(fp_line
			(start -0.67945 -0.305054)
			(end -0.12065 -0.305054)
			(stroke
				(width 0.1)
				(type default)
			)
			(layer "F.Fab")
		)
		(fp_line
			(start -0.67945 0.3048)
			(end -0.67945 -0.305054)
			(stroke
				(width 0.1)
				(type default)
			)
			(layer "F.Fab")
		)
		(fp_line
			(start -0.12065 -0.305054)
			(end -0.12065 -0.2794)
			(stroke
				(width 0.1)
				(type default)
			)
			(layer "F.Fab")
		)
		(fp_line
			(start -0.12065 -0.2794)
			(end 0.12065 -0.2794)
			(stroke
				(width 0.1)
				(type default)
			)
			(layer "F.Fab")
		)
		(fp_line
			(start -0.12065 0.2794)
			(end -0.12065 0.3048)
			(stroke
				(width 0.1)
				(type default)
			)
			(layer "F.Fab")
		)
		(fp_line
			(start -0.12065 0.3048)
			(end -0.67945 0.3048)
			(stroke
				(width 0.1)
				(type default)
			)
			(layer "F.Fab")
		)
		(fp_line
			(start 0.120396 0.2794)
			(end -0.12065 0.2794)
			(stroke
				(width 0.1)
				(type default)
			)
			(layer "F.Fab")
		)
		(fp_line
			(start 0.120396 0.3048)
			(end 0.120396 0.2794)
			(stroke
				(width 0.1)
				(type default)
			)
			(layer "F.Fab")
		)
		(fp_line
			(start 0.12065 -0.3048)
			(end 0.67945 -0.3048)
			(stroke
				(width 0.1)
				(type default)
			)
			(layer "F.Fab")
		)
		(fp_line
			(start 0.12065 -0.2794)
			(end 0.12065 -0.3048)
			(stroke
				(width 0.1)
				(type default)
			)
			(layer "F.Fab")
		)
		(fp_line
			(start 0.67945 -0.3048)
			(end 0.67945 0.3048)
			(stroke
				(width 0.1)
				(type default)
			)
			(layer "F.Fab")
		)
		(fp_line
			(start 0.67945 0.3048)
			(end 0.120396 0.3048)
			(stroke
				(width 0.1)
				(type default)
			)
			(layer "F.Fab")
		)
		(pad "1" smd circle
			(at -0.40005 0)
			(size 0 0)
			(layers "F.Cu" "F.Mask" "F.Paste")
			(net "FAN_6_ON")
		)
		(pad "2" smd circle
			(at 0.40005 0)
			(size 0 0)
			(layers "F.Cu" "F.Mask" "F.Paste")
			(net "P52V_FAN_6_EN")
		)
	)
	(footprint ""
		(layer "F.Cu")
		(at 6.858 -135.255 -90)
		(property "Reference" "R5565"
			(at 0 0 270)
			(layer "F.SilkS")
			(hide yes)
			(effects
				(font
					(size 1.27 1.27)
				)
			)
		)
		(property "Value" ""
			(at 0 0 270)
			(layer "F.Fab")
			(effects
				(font
					(size 1.27 1.27)
				)
			)
		)
		(duplicate_pad_numbers_are_jumpers no)
		(fp_line
			(start -0.7874 0.4064)
			(end -0.7874 -0.4064)
			(stroke
				(width 0.1524)
				(type default)
			)
			(layer "F.SilkS")
		)
		(fp_line
			(start 0.7874 0.4064)
			(end -0.7874 0.4064)
			(stroke
				(width 0.1524)
				(type default)
			)
			(layer "F.SilkS")
		)
		(fp_line
			(start -0.7874 -0.4064)
			(end 0.7874 -0.4064)
			(stroke
				(width 0.1524)
				(type default)
			)
			(layer "F.SilkS")
		)
		(fp_line
			(start 0.7874 -0.4064)
			(end 0.7874 0.4064)
			(stroke
				(width 0.1524)
				(type default)
			)
			(layer "F.SilkS")
		)
		(fp_line
			(start -0.67945 0.3048)
			(end -0.67945 -0.305054)
			(stroke
				(width 0.1)
				(type default)
			)
			(layer "F.Fab")
		)
		(fp_line
			(start -0.12065 0.3048)
			(end -0.67945 0.3048)
			(stroke
				(width 0.1)
				(type default)
			)
			(layer "F.Fab")
		)
		(fp_line
			(start 0.120396 0.3048)
			(end 0.120396 0.2794)
			(stroke
				(width 0.1)
				(type default)
			)
			(layer "F.Fab")
		)
		(fp_line
			(start 0.67945 0.3048)
			(end 0.120396 0.3048)
			(stroke
				(width 0.1)
				(type default)
			)
			(layer "F.Fab")
		)
		(fp_line
			(start -0.12065 0.2794)
			(end -0.12065 0.3048)
			(stroke
				(width 0.1)
				(type default)
			)
			(layer "F.Fab")
		)
		(fp_line
			(start 0.120396 0.2794)
			(end -0.12065 0.2794)
			(stroke
				(width 0.1)
				(type default)
			)
			(layer "F.Fab")
		)
		(fp_line
			(start -0.12065 -0.2794)
			(end 0.12065 -0.2794)
			(stroke
				(width 0.1)
				(type default)
			)
			(layer "F.Fab")
		)
		(fp_line
			(start 0.12065 -0.2794)
			(end 0.12065 -0.3048)
			(stroke
				(width 0.1)
				(type default)
			)
			(layer "F.Fab")
		)
		(fp_line
			(start 0.12065 -0.3048)
			(end 0.67945 -0.3048)
			(stroke
				(width 0.1)
				(type default)
			)
			(layer "F.Fab")
		)
		(fp_line
			(start 0.67945 -0.3048)
			(end 0.67945 0.3048)
			(stroke
				(width 0.1)
				(type default)
			)
			(layer "F.Fab")
		)
		(fp_line
			(start -0.67945 -0.305054)
			(end -0.12065 -0.305054)
			(stroke
				(width 0.1)
				(type default)
			)
			(layer "F.Fab")
		)
		(fp_line
			(start -0.12065 -0.305054)
			(end -0.12065 -0.2794)
			(stroke
				(width 0.1)
				(type default)
			)
			(layer "F.Fab")
		)
		(pad "1" smd circle
			(at -0.40005 0 270)
			(size 0 0)
			(layers "F.Cu" "F.Mask" "F.Paste")
			(net "P3V3_AUX")
		)
		(pad "2" smd circle
			(at 0.40005 0 270)
			(size 0 0)
			(layers "F.Cu" "F.Mask" "F.Paste")
			(net "U404_ADD0")
		)
	)
	(footprint ""
		(layer "F.Cu")
		(at 14.351 -208.435956 180)
		(property "Reference" "D252"
			(at 4.064 -1.071626 0)
			(unlocked yes)
			(layer "F.SilkS")
			(effects
				(font
					(size 0.7874 0.5842)
					(thickness 0.1524)
				)
				(justify left)
			)
		)
		(property "Value" ""
			(at 0 0 180)
			(layer "F.Fab")
			(effects
				(font
					(size 1.27 1.27)
				)
			)
		)
		(duplicate_pad_numbers_are_jumpers no)
		(fp_line
			(start 0.94488 0.450088)
			(end 0.94488 -0.450088)
			(stroke
				(width 0.1524)
				(type default)
			)
			(layer "F.SilkS")
		)
		(fp_line
			(start 0.94488 -0.450088)
			(end -0.854964 -0.450088)
			(stroke
				(width 0.1524)
				(type default)
			)
			(layer "F.SilkS")
		)
		(fp_line
			(start 0.870458 -0.2794)
			(end 0.845058 0.4064)
			(stroke
				(width 0.1524)
				(type default)
			)
			(layer "F.SilkS")
		)
		(fp_line
			(start 0.845058 0.4064)
			(end 0.845058 -0.381)
			(stroke
				(width 0.1524)
				(type default)
			)
			(layer "F.SilkS")
		)
		(fp_line
			(start -0.854964 0.450088)
			(end 0.925068 0.450088)
			(stroke
				(width 0.1524)
				(type default)
			)
			(layer "F.SilkS")
		)
		(fp_line
			(start -0.854964 -0.450088)
			(end -0.854964 0.450088)
			(stroke
				(width 0.1524)
				(type default)
			)
			(layer "F.SilkS")
		)
		(fp_line
			(start 0.54991 0.350012)
			(end 0.54991 -0.350012)
			(stroke
				(width 0.1)
				(type default)
			)
			(layer "F.Fab")
		)
		(fp_line
			(start 0.54991 -0.350012)
			(end -0.54991 -0.350012)
			(stroke
				(width 0.1)
				(type default)
			)
			(layer "F.Fab")
		)
		(fp_line
			(start -0.54991 0.350012)
			(end 0.54991 0.350012)
			(stroke
				(width 0.1)
				(type default)
			)
			(layer "F.Fab")
		)
		(fp_line
			(start -0.54991 -0.350012)
			(end -0.54991 0.350012)
			(stroke
				(width 0.1)
				(type default)
			)
			(layer "F.Fab")
		)
		(fp_text user "-"
			(at 2.159 0.193294 0)
			(unlocked yes)
			(layer "F.SilkS")
			(effects
				(font
					(size 1.905 1.4224)
					(thickness 0.1524)
				)
				(justify left)
			)
		)
		(fp_text user "+"
			(at -2.38125 0.987044 270)
			(unlocked yes)
			(layer "F.SilkS")
			(effects
				(font
					(size 1.905 1.4224)
					(thickness 0.1524)
				)
				(justify left)
			)
		)
		(fp_text user "-"
			(at 2.48539 0.239014 0)
			(unlocked yes)
			(layer "F.Fab")
			(effects
				(font
					(size 1.905 1.4224)
					(thickness 0.1524)
				)
				(justify left)
			)
		)
		(fp_text user "+"
			(at -0.808228 0.239014 0)
			(unlocked yes)
			(layer "F.Fab")
			(effects
				(font
					(size 1.905 1.4224)
					(thickness 0.1524)
				)
				(justify left)
			)
		)
		(pad "A" smd rect
			(at -0.424942 0 180)
			(size 0.5588 0.6096)
			(layers "F.Cu" "F.Mask" "F.Paste")
			(net "GND")
		)
		(pad "C" smd rect
			(at 0.424942 0)
			(size 0.5588 0.6096)
			(layers "F.Cu" "F.Mask" "F.Paste")
			(net "FAN_6_OK_R_LED_N")
		)
	)
	(footprint ""
		(layer "F.Cu")
		(at 2.6924 -219.583 -90)
		(property "Reference" "C2039"
			(at 0 0 270)
			(layer "F.SilkS")
			(hide yes)
			(effects
				(font
					(size 1.27 1.27)
				)
			)
		)
		(property "Value" ""
			(at 0 0 270)
			(layer "F.Fab")
			(effects
				(font
					(size 1.27 1.27)
				)
			)
		)
		(duplicate_pad_numbers_are_jumpers no)
		(fp_line
			(start -0.7874 0.4064)
			(end -0.7874 -0.4064)
			(stroke
				(width 0.1524)
				(type default)
			)
			(layer "F.SilkS")
		)
		(fp_line
			(start 0.7874 0.4064)
			(end -0.7874 0.4064)
			(stroke
				(width 0.1524)
				(type default)
			)
			(layer "F.SilkS")
		)
		(fp_line
			(start -0.7874 -0.4064)
			(end 0.7874 -0.4064)
			(stroke
				(width 0.1524)
				(type default)
			)
			(layer "F.SilkS")
		)
		(fp_line
			(start 0.7874 -0.4064)
			(end 0.7874 0.4064)
			(stroke
				(width 0.1524)
				(type default)
			)
			(layer "F.SilkS")
		)
		(fp_line
			(start -0.6858 0.3048)
			(end -0.6858 -0.3048)
			(stroke
				(width 0.1)
				(type default)
			)
			(layer "F.Fab")
		)
		(fp_line
			(start -0.1016 0.3048)
			(end -0.6858 0.3048)
			(stroke
				(width 0.1)
				(type default)
			)
			(layer "F.Fab")
		)
		(fp_line
			(start 0.1016 0.3048)
			(end 0.1016 0.2794)
			(stroke
				(width 0.1)
				(type default)
			)
			(layer "F.Fab")
		)
		(fp_line
			(start 0.6858 0.3048)
			(end 0.1016 0.3048)
			(stroke
				(width 0.1)
				(type default)
			)
			(layer "F.Fab")
		)
		(fp_line
			(start -0.1016 0.2794)
			(end -0.1016 0.3048)
			(stroke
				(width 0.1)
				(type default)
			)
			(layer "F.Fab")
		)
		(fp_line
			(start 0.1016 0.2794)
			(end -0.1016 0.2794)
			(stroke
				(width 0.1)
				(type default)
			)
			(layer "F.Fab")
		)
		(fp_line
			(start -0.1016 -0.2794)
			(end 0.1016 -0.2794)
			(stroke
				(width 0.1)
				(type default)
			)
			(layer "F.Fab")
		)
		(fp_line
			(start 0.1016 -0.2794)
			(end 0.1016 -0.3048)
			(stroke
				(width 0.1)
				(type default)
			)
			(layer "F.Fab")
		)
		(fp_line
			(start -0.6858 -0.3048)
			(end -0.1016 -0.3048)
			(stroke
				(width 0.1)
				(type default)
			)
			(layer "F.Fab")
		)
		(fp_line
			(start -0.1016 -0.3048)
			(end -0.1016 -0.2794)
			(stroke
				(width 0.1)
				(type default)
			)
			(layer "F.Fab")
		)
		(fp_line
			(start 0.1016 -0.3048)
			(end 0.6858 -0.3048)
			(stroke
				(width 0.1)
				(type default)
			)
			(layer "F.Fab")
		)
		(fp_line
			(start 0.6858 -0.3048)
			(end 0.6858 0.3048)
			(stroke
				(width 0.1)
				(type default)
			)
			(layer "F.Fab")
		)
		(pad "1" smd rect
			(at -0.40005 0 90)
			(size 0.4572 0.508)
			(layers "F.Cu" "F.Mask" "F.Paste")
			(net "GND")
		)
		(pad "2" smd rect
			(at 0.40005 0 90)
			(size 0.4572 0.508)
			(layers "F.Cu" "F.Mask" "F.Paste")
			(net "P12V_LED_FAN6")
		)
	)
	(footprint ""
		(layer "F.Cu")
		(at 37.338 -25.105868 180)
		(property "Reference" "R5244"
			(at 0 0 180)
			(layer "F.SilkS")
			(hide yes)
			(effects
				(font
					(size 1.27 1.27)
				)
			)
		)
		(property "Value" ""
			(at 0 0 180)
			(layer "F.Fab")
			(effects
				(font
					(size 1.27 1.27)
				)
			)
		)
		(duplicate_pad_numbers_are_jumpers no)
		(fp_line
			(start 0.7874 0.4064)
			(end -0.7874 0.4064)
			(stroke
				(width 0.1524)
				(type default)
			)
			(layer "F.SilkS")
		)
		(fp_line
			(start 0.7874 -0.4064)
			(end 0.7874 0.4064)
			(stroke
				(width 0.1524)
				(type default)
			)
			(layer "F.SilkS")
		)
		(fp_line
			(start -0.7874 0.4064)
			(end -0.7874 -0.4064)
			(stroke
				(width 0.1524)
				(type default)
			)
			(layer "F.SilkS")
		)
		(fp_line
			(start -0.7874 -0.4064)
			(end 0.7874 -0.4064)
			(stroke
				(width 0.1524)
				(type default)
			)
			(layer "F.SilkS")
		)
		(fp_line
			(start 0.67945 0.3048)
			(end 0.120396 0.3048)
			(stroke
				(width 0.1)
				(type default)
			)
			(layer "F.Fab")
		)
		(fp_line
			(start 0.67945 -0.3048)
			(end 0.67945 0.3048)
			(stroke
				(width 0.1)
				(type default)
			)
			(layer "F.Fab")
		)
		(fp_line
			(start 0.12065 -0.2794)
			(end 0.12065 -0.3048)
			(stroke
				(width 0.1)
				(type default)
			)
			(layer "F.Fab")
		)
		(fp_line
			(start 0.12065 -0.3048)
			(end 0.67945 -0.3048)
			(stroke
				(width 0.1)
				(type default)
			)
			(layer "F.Fab")
		)
		(fp_line
			(start 0.120396 0.3048)
			(end 0.120396 0.2794)
			(stroke
				(width 0.1)
				(type default)
			)
			(layer "F.Fab")
		)
		(fp_line
			(start 0.120396 0.2794)
			(end -0.12065 0.2794)
			(stroke
				(width 0.1)
				(type default)
			)
			(layer "F.Fab")
		)
		(fp_line
			(start -0.12065 0.3048)
			(end -0.67945 0.3048)
			(stroke
				(width 0.1)
				(type default)
			)
			(layer "F.Fab")
		)
		(fp_line
			(start -0.12065 0.2794)
			(end -0.12065 0.3048)
			(stroke
				(width 0.1)
				(type default)
			)
			(layer "F.Fab")
		)
		(fp_line
			(start -0.12065 -0.2794)
			(end 0.12065 -0.2794)
			(stroke
				(width 0.1)
				(type default)
			)
			(layer "F.Fab")
		)
		(fp_line
			(start -0.12065 -0.305054)
			(end -0.12065 -0.2794)
			(stroke
				(width 0.1)
				(type default)
			)
			(layer "F.Fab")
		)
		(fp_line
			(start -0.67945 0.3048)
			(end -0.67945 -0.305054)
			(stroke
				(width 0.1)
				(type default)
			)
			(layer "F.Fab")
		)
		(fp_line
			(start -0.67945 -0.305054)
			(end -0.12065 -0.305054)
			(stroke
				(width 0.1)
				(type default)
			)
			(layer "F.Fab")
		)
		(pad "1" smd circle
			(at -0.40005 0 180)
			(size 0 0)
			(layers "F.Cu" "F.Mask" "F.Paste")
			(net "SMB_FAN3_SDA_R")
		)
		(pad "2" smd circle
			(at 0.40005 0 180)
			(size 0 0)
			(layers "F.Cu" "F.Mask" "F.Paste")
			(net "SMB_FAN3_SDA")
		)
	)
	(footprint ""
		(layer "F.Cu")
		(at 47.752 -310.134)
		(property "Reference" "C2018"
			(at 0 0 0)
			(layer "F.SilkS")
			(hide yes)
			(effects
				(font
					(size 1.27 1.27)
				)
			)
		)
		(property "Value" ""
			(at 0 0 0)
			(layer "F.Fab")
			(effects
				(font
					(size 1.27 1.27)
				)
			)
		)
		(duplicate_pad_numbers_are_jumpers no)
		(fp_line
			(start -1.524 -0.762)
			(end 1.524 -0.762)
			(stroke
				(width 0.1524)
				(type default)
			)
			(layer "F.SilkS")
		)
		(fp_line
			(start -1.524 0.762)
			(end -1.524 -0.762)
			(stroke
				(width 0.1524)
				(type default)
			)
			(layer "F.SilkS")
		)
		(fp_line
			(start 1.524 -0.762)
			(end 1.524 0.762)
			(stroke
				(width 0.1524)
				(type default)
			)
			(layer "F.SilkS")
		)
		(fp_line
			(start 1.524 0.762)
			(end -1.524 0.762)
			(stroke
				(width 0.1524)
				(type default)
			)
			(layer "F.SilkS")
		)
		(fp_line
			(start -1.1049 -0.724916)
			(end -1.1049 0.724916)
			(stroke
				(width 0.1)
				(type default)
			)
			(layer "F.Fab")
		)
		(fp_line
			(start -1.1049 0.724916)
			(end 1.1049 0.724916)
			(stroke
				(width 0.1)
				(type default)
			)
			(layer "F.Fab")
		)
		(fp_line
			(start 1.1049 -0.724916)
			(end -1.1049 -0.724916)
			(stroke
				(width 0.1)
				(type default)
			)
			(layer "F.Fab")
		)
		(fp_line
			(start 1.1049 0.724916)
			(end 1.1049 -0.724916)
			(stroke
				(width 0.1)
				(type default)
			)
			(layer "F.Fab")
		)
		(pad "1" smd rect
			(at -0.889 0 180)
			(size 1.016 1.27)
			(layers "F.Cu" "F.Mask" "F.Paste")
			(net "P12V_LED_FAN0")
		)
		(pad "2" smd rect
			(at 0.889 0 180)
			(size 1.016 1.27)
			(layers "F.Cu" "F.Mask" "F.Paste")
			(net "GND")
		)
	)
	(footprint ""
		(layer "F.Cu")
		(at 38.6461 -127.508)
		(property "Reference" "R5581"
			(at 0 0 0)
			(layer "F.SilkS")
			(hide yes)
			(effects
				(font
					(size 1.27 1.27)
				)
			)
		)
		(property "Value" ""
			(at 0 0 0)
			(layer "F.Fab")
			(effects
				(font
					(size 1.27 1.27)
				)
			)
		)
		(duplicate_pad_numbers_are_jumpers no)
		(fp_line
			(start -0.7874 -0.4064)
			(end 0.7874 -0.4064)
			(stroke
				(width 0.1524)
				(type default)
			)
			(layer "F.SilkS")
		)
		(fp_line
			(start -0.7874 0.4064)
			(end -0.7874 -0.4064)
			(stroke
				(width 0.1524)
				(type default)
			)
			(layer "F.SilkS")
		)
		(fp_line
			(start 0.7874 -0.4064)
			(end 0.7874 0.4064)
			(stroke
				(width 0.1524)
				(type default)
			)
			(layer "F.SilkS")
		)
		(fp_line
			(start 0.7874 0.4064)
			(end -0.7874 0.4064)
			(stroke
				(width 0.1524)
				(type default)
			)
			(layer "F.SilkS")
		)
		(fp_line
			(start -0.67945 -0.305054)
			(end -0.12065 -0.305054)
			(stroke
				(width 0.1)
				(type default)
			)
			(layer "F.Fab")
		)
		(fp_line
			(start -0.67945 0.3048)
			(end -0.67945 -0.305054)
			(stroke
				(width 0.1)
				(type default)
			)
			(layer "F.Fab")
		)
		(fp_line
			(start -0.12065 -0.305054)
			(end -0.12065 -0.2794)
			(stroke
				(width 0.1)
				(type default)
			)
			(layer "F.Fab")
		)
		(fp_line
			(start -0.12065 -0.2794)
			(end 0.12065 -0.2794)
			(stroke
				(width 0.1)
				(type default)
			)
			(layer "F.Fab")
		)
		(fp_line
			(start -0.12065 0.2794)
			(end -0.12065 0.3048)
			(stroke
				(width 0.1)
				(type default)
			)
			(layer "F.Fab")
		)
		(fp_line
			(start -0.12065 0.3048)
			(end -0.67945 0.3048)
			(stroke
				(width 0.1)
				(type default)
			)
			(layer "F.Fab")
		)
		(fp_line
			(start 0.120396 0.2794)
			(end -0.12065 0.2794)
			(stroke
				(width 0.1)
				(type default)
			)
			(layer "F.Fab")
		)
		(fp_line
			(start 0.120396 0.3048)
			(end 0.120396 0.2794)
			(stroke
				(width 0.1)
				(type default)
			)
			(layer "F.Fab")
		)
		(fp_line
			(start 0.12065 -0.3048)
			(end 0.67945 -0.3048)
			(stroke
				(width 0.1)
				(type default)
			)
			(layer "F.Fab")
		)
		(fp_line
			(start 0.12065 -0.2794)
			(end 0.12065 -0.3048)
			(stroke
				(width 0.1)
				(type default)
			)
			(layer "F.Fab")
		)
		(fp_line
			(start 0.67945 -0.3048)
			(end 0.67945 0.3048)
			(stroke
				(width 0.1)
				(type default)
			)
			(layer "F.Fab")
		)
		(fp_line
			(start 0.67945 0.3048)
			(end 0.120396 0.3048)
			(stroke
				(width 0.1)
				(type default)
			)
			(layer "F.Fab")
		)
		(pad "1" smd rect
			(at -0.40005 0 180)
			(size 0.4572 0.508)
			(layers "F.Cu" "F.Mask" "F.Paste")
			(net "FAN_3_TACH_IL")
		)
		(pad "2" smd rect
			(at 0.40005 0 180)
			(size 0.4572 0.508)
			(layers "F.Cu" "F.Mask" "F.Paste")
			(net "FAN_3_TACH_IL_R2")
		)
	)
	(footprint ""
		(layer "F.Cu")
		(at 3.81 -128.651)
		(property "Reference" "R5572"
			(at 0 0 0)
			(layer "F.SilkS")
			(hide yes)
			(effects
				(font
					(size 1.27 1.27)
				)
			)
		)
		(property "Value" ""
			(at 0 0 0)
			(layer "F.Fab")
			(effects
				(font
					(size 1.27 1.27)
				)
			)
		)
		(duplicate_pad_numbers_are_jumpers no)
		(fp_line
			(start -0.7874 -0.4064)
			(end 0.7874 -0.4064)
			(stroke
				(width 0.1524)
				(type default)
			)
			(layer "F.SilkS")
		)
		(fp_line
			(start -0.7874 0.4064)
			(end -0.7874 -0.4064)
			(stroke
				(width 0.1524)
				(type default)
			)
			(layer "F.SilkS")
		)
		(fp_line
			(start 0.7874 -0.4064)
			(end 0.7874 0.4064)
			(stroke
				(width 0.1524)
				(type default)
			)
			(layer "F.SilkS")
		)
		(fp_line
			(start 0.7874 0.4064)
			(end -0.7874 0.4064)
			(stroke
				(width 0.1524)
				(type default)
			)
			(layer "F.SilkS")
		)
		(fp_line
			(start -0.67945 -0.305054)
			(end -0.12065 -0.305054)
			(stroke
				(width 0.1)
				(type default)
			)
			(layer "F.Fab")
		)
		(fp_line
			(start -0.67945 0.3048)
			(end -0.67945 -0.305054)
			(stroke
				(width 0.1)
				(type default)
			)
			(layer "F.Fab")
		)
		(fp_line
			(start -0.12065 -0.305054)
			(end -0.12065 -0.2794)
			(stroke
				(width 0.1)
				(type default)
			)
			(layer "F.Fab")
		)
		(fp_line
			(start -0.12065 -0.2794)
			(end 0.12065 -0.2794)
			(stroke
				(width 0.1)
				(type default)
			)
			(layer "F.Fab")
		)
		(fp_line
			(start -0.12065 0.2794)
			(end -0.12065 0.3048)
			(stroke
				(width 0.1)
				(type default)
			)
			(layer "F.Fab")
		)
		(fp_line
			(start -0.12065 0.3048)
			(end -0.67945 0.3048)
			(stroke
				(width 0.1)
				(type default)
			)
			(layer "F.Fab")
		)
		(fp_line
			(start 0.120396 0.2794)
			(end -0.12065 0.2794)
			(stroke
				(width 0.1)
				(type default)
			)
			(layer "F.Fab")
		)
		(fp_line
			(start 0.120396 0.3048)
			(end 0.120396 0.2794)
			(stroke
				(width 0.1)
				(type default)
			)
			(layer "F.Fab")
		)
		(fp_line
			(start 0.12065 -0.3048)
			(end 0.67945 -0.3048)
			(stroke
				(width 0.1)
				(type default)
			)
			(layer "F.Fab")
		)
		(fp_line
			(start 0.12065 -0.2794)
			(end 0.12065 -0.3048)
			(stroke
				(width 0.1)
				(type default)
			)
			(layer "F.Fab")
		)
		(fp_line
			(start 0.67945 -0.3048)
			(end 0.67945 0.3048)
			(stroke
				(width 0.1)
				(type default)
			)
			(layer "F.Fab")
		)
		(fp_line
			(start 0.67945 0.3048)
			(end 0.120396 0.3048)
			(stroke
				(width 0.1)
				(type default)
			)
			(layer "F.Fab")
		)
		(pad "1" smd circle
			(at -0.40005 0)
			(size 0 0)
			(layers "F.Cu" "F.Mask" "F.Paste")
			(net "GND")
		)
		(pad "2" smd circle
			(at 0.40005 0)
			(size 0 0)
			(layers "F.Cu" "F.Mask" "F.Paste")
			(net "U404_ADD2")
		)
	)
	(footprint ""
		(layer "F.Cu")
		(at 15.377922 -105.506012 180)
		(property "Reference" "D248"
			(at 5.344922 -0.884682 0)
			(unlocked yes)
			(layer "F.SilkS")
			(effects
				(font
					(size 0.7874 0.5842)
					(thickness 0.1524)
				)
				(justify left)
			)
		)
		(property "Value" ""
			(at 0 0 180)
			(layer "F.Fab")
			(effects
				(font
					(size 1.27 1.27)
				)
			)
		)
		(duplicate_pad_numbers_are_jumpers no)
		(fp_line
			(start 0.94488 0.450088)
			(end 0.94488 -0.450088)
			(stroke
				(width 0.1524)
				(type default)
			)
			(layer "F.SilkS")
		)
		(fp_line
			(start 0.94488 -0.450088)
			(end -0.854964 -0.450088)
			(stroke
				(width 0.1524)
				(type default)
			)
			(layer "F.SilkS")
		)
		(fp_line
			(start 0.870458 -0.2794)
			(end 0.845058 0.4064)
			(stroke
				(width 0.1524)
				(type default)
			)
			(layer "F.SilkS")
		)
		(fp_line
			(start 0.845058 0.4064)
			(end 0.845058 -0.381)
			(stroke
				(width 0.1524)
				(type default)
			)
			(layer "F.SilkS")
		)
		(fp_line
			(start -0.854964 0.450088)
			(end 0.925068 0.450088)
			(stroke
				(width 0.1524)
				(type default)
			)
			(layer "F.SilkS")
		)
		(fp_line
			(start -0.854964 -0.450088)
			(end -0.854964 0.450088)
			(stroke
				(width 0.1524)
				(type default)
			)
			(layer "F.SilkS")
		)
		(fp_line
			(start 0.54991 0.350012)
			(end 0.54991 -0.350012)
			(stroke
				(width 0.1)
				(type default)
			)
			(layer "F.Fab")
		)
		(fp_line
			(start 0.54991 -0.350012)
			(end -0.54991 -0.350012)
			(stroke
				(width 0.1)
				(type default)
			)
			(layer "F.Fab")
		)
		(fp_line
			(start -0.54991 0.350012)
			(end 0.54991 0.350012)
			(stroke
				(width 0.1)
				(type default)
			)
			(layer "F.Fab")
		)
		(fp_line
			(start -0.54991 -0.350012)
			(end -0.54991 0.350012)
			(stroke
				(width 0.1)
				(type default)
			)
			(layer "F.Fab")
		)
		(fp_text user "-"
			(at 2.296922 0.253238 0)
			(unlocked yes)
			(layer "F.SilkS")
			(effects
				(font
					(size 1.905 1.4224)
					(thickness 0.1524)
				)
				(justify left)
			)
		)
		(fp_text user "+"
			(at -0.624078 0.253238 0)
			(unlocked yes)
			(layer "F.SilkS")
			(effects
				(font
					(size 1.905 1.4224)
					(thickness 0.1524)
				)
				(justify left)
			)
		)
		(fp_text user "-"
			(at 2.48539 0.239014 0)
			(unlocked yes)
			(layer "F.Fab")
			(effects
				(font
					(size 1.905 1.4224)
					(thickness 0.1524)
				)
				(justify left)
			)
		)
		(fp_text user "+"
			(at -0.808228 0.239014 0)
			(unlocked yes)
			(layer "F.Fab")
			(effects
				(font
					(size 1.905 1.4224)
					(thickness 0.1524)
				)
				(justify left)
			)
		)
		(pad "A" smd rect
			(at -0.424942 0 180)
			(size 0.5588 0.6096)
			(layers "F.Cu" "F.Mask" "F.Paste")
			(net "GND")
		)
		(pad "C" smd rect
			(at 0.424942 0)
			(size 0.5588 0.6096)
			(layers "F.Cu" "F.Mask" "F.Paste")
			(net "FAN_5_TACH_IL_D")
		)
	)
	(footprint ""
		(layer "F.Cu")
		(at 34.417 -202.819)
		(property "Reference" "U371"
			(at -1.524 -1.87833 0)
			(unlocked yes)
			(layer "F.SilkS")
			(effects
				(font
					(size 0.7874 0.5842)
					(thickness 0.1524)
				)
				(justify left)
			)
		)
		(property "Value" ""
			(at 0 0 0)
			(layer "F.Fab")
			(effects
				(font
					(size 1.27 1.27)
				)
			)
		)
		(duplicate_pad_numbers_are_jumpers no)
		(fp_line
			(start -1.335278 -1.100074)
			(end -1.335278 1.100074)
			(stroke
				(width 0.1524)
				(type default)
			)
			(layer "F.SilkS")
		)
		(fp_line
			(start -1.335278 1.100074)
			(end 1.335278 1.100074)
			(stroke
				(width 0.1524)
				(type default)
			)
			(layer "F.SilkS")
		)
		(fp_line
			(start 1.335278 -1.100074)
			(end -1.335278 -1.100074)
			(stroke
				(width 0.1524)
				(type default)
			)
			(layer "F.SilkS")
		)
		(fp_line
			(start 1.335278 1.100074)
			(end 1.335278 -1.100074)
			(stroke
				(width 0.1524)
				(type default)
			)
			(layer "F.SilkS")
		)
		(fp_line
			(start -0.674878 -1.100074)
			(end -0.674878 1.100074)
			(stroke
				(width 0.1)
				(type default)
			)
			(layer "F.Fab")
		)
		(fp_line
			(start -0.674878 1.100074)
			(end 0.674878 1.100074)
			(stroke
				(width 0.1)
				(type default)
			)
			(layer "F.Fab")
		)
		(fp_line
			(start 0.674878 -1.100074)
			(end -0.674878 -1.100074)
			(stroke
				(width 0.1)
				(type default)
			)
			(layer "F.Fab")
		)
		(fp_line
			(start 0.674878 1.100074)
			(end 0.674878 -1.100074)
			(stroke
				(width 0.1)
				(type default)
			)
			(layer "F.Fab")
		)
		(pad "D" smd rect
			(at 0.8001 0 270)
			(size 0.6096 0.8128)
			(layers "F.Cu" "F.Mask" "F.Paste")
			(net "FAN_1_FAIL_LED_R_N")
		)
		(pad "G" smd rect
			(at -0.8001 -0.649986 270)
			(size 0.6096 0.8128)
			(layers "F.Cu" "F.Mask" "F.Paste")
			(net "FAN_1_FAIL_R_LED")
		)
		(pad "S" smd rect
			(at -0.8001 0.649986 270)
			(size 0.6096 0.8128)
			(layers "F.Cu" "F.Mask" "F.Paste")
			(net "GND")
		)
	)
	(footprint ""
		(layer "F.Cu")
		(at 18.415 -180.213 180)
		(property "Reference" "R5685"
			(at 0 0 180)
			(layer "F.SilkS")
			(hide yes)
			(effects
				(font
					(size 1.27 1.27)
				)
			)
		)
		(property "Value" ""
			(at 0 0 180)
			(layer "F.Fab")
			(effects
				(font
					(size 1.27 1.27)
				)
			)
		)
		(duplicate_pad_numbers_are_jumpers no)
		(fp_line
			(start 0.7874 0.4064)
			(end -0.7874 0.4064)
			(stroke
				(width 0.1524)
				(type default)
			)
			(layer "F.SilkS")
		)
		(fp_line
			(start 0.7874 -0.4064)
			(end 0.7874 0.4064)
			(stroke
				(width 0.1524)
				(type default)
			)
			(layer "F.SilkS")
		)
		(fp_line
			(start -0.7874 0.4064)
			(end -0.7874 -0.4064)
			(stroke
				(width 0.1524)
				(type default)
			)
			(layer "F.SilkS")
		)
		(fp_line
			(start -0.7874 -0.4064)
			(end 0.7874 -0.4064)
			(stroke
				(width 0.1524)
				(type default)
			)
			(layer "F.SilkS")
		)
		(fp_line
			(start 0.67945 0.3048)
			(end 0.120396 0.3048)
			(stroke
				(width 0.1)
				(type default)
			)
			(layer "F.Fab")
		)
		(fp_line
			(start 0.67945 -0.3048)
			(end 0.67945 0.3048)
			(stroke
				(width 0.1)
				(type default)
			)
			(layer "F.Fab")
		)
		(fp_line
			(start 0.12065 -0.2794)
			(end 0.12065 -0.3048)
			(stroke
				(width 0.1)
				(type default)
			)
			(layer "F.Fab")
		)
		(fp_line
			(start 0.12065 -0.3048)
			(end 0.67945 -0.3048)
			(stroke
				(width 0.1)
				(type default)
			)
			(layer "F.Fab")
		)
		(fp_line
			(start 0.120396 0.3048)
			(end 0.120396 0.2794)
			(stroke
				(width 0.1)
				(type default)
			)
			(layer "F.Fab")
		)
		(fp_line
			(start 0.120396 0.2794)
			(end -0.12065 0.2794)
			(stroke
				(width 0.1)
				(type default)
			)
			(layer "F.Fab")
		)
		(fp_line
			(start -0.12065 0.3048)
			(end -0.67945 0.3048)
			(stroke
				(width 0.1)
				(type default)
			)
			(layer "F.Fab")
		)
		(fp_line
			(start -0.12065 0.2794)
			(end -0.12065 0.3048)
			(stroke
				(width 0.1)
				(type default)
			)
			(layer "F.Fab")
		)
		(fp_line
			(start -0.12065 -0.2794)
			(end 0.12065 -0.2794)
			(stroke
				(width 0.1)
				(type default)
			)
			(layer "F.Fab")
		)
		(fp_line
			(start -0.12065 -0.305054)
			(end -0.12065 -0.2794)
			(stroke
				(width 0.1)
				(type default)
			)
			(layer "F.Fab")
		)
		(fp_line
			(start -0.67945 0.3048)
			(end -0.67945 -0.305054)
			(stroke
				(width 0.1)
				(type default)
			)
			(layer "F.Fab")
		)
		(fp_line
			(start -0.67945 -0.305054)
			(end -0.12065 -0.305054)
			(stroke
				(width 0.1)
				(type default)
			)
			(layer "F.Fab")
		)
		(pad "1" smd circle
			(at -0.40005 0 180)
			(size 0 0)
			(layers "F.Cu" "F.Mask" "F.Paste")
			(net "P3V3_AUX")
		)
		(pad "2" smd circle
			(at 0.40005 0 180)
			(size 0 0)
			(layers "F.Cu" "F.Mask" "F.Paste")
			(net "FM_BOARD_ID2")
		)
	)
	(footprint ""
		(layer "F.Cu")
		(at 3.81 -181.61 180)
		(property "Reference" "R2362"
			(at 0 0 180)
			(layer "F.SilkS")
			(hide yes)
			(effects
				(font
					(size 1.27 1.27)
				)
			)
		)
		(property "Value" ""
			(at 0 0 180)
			(layer "F.Fab")
			(effects
				(font
					(size 1.27 1.27)
				)
			)
		)
		(duplicate_pad_numbers_are_jumpers no)
		(fp_line
			(start 0.7874 0.4064)
			(end -0.7874 0.4064)
			(stroke
				(width 0.1524)
				(type default)
			)
			(layer "F.SilkS")
		)
		(fp_line
			(start 0.7874 -0.4064)
			(end 0.7874 0.4064)
			(stroke
				(width 0.1524)
				(type default)
			)
			(layer "F.SilkS")
		)
		(fp_line
			(start -0.7874 0.4064)
			(end -0.7874 -0.4064)
			(stroke
				(width 0.1524)
				(type default)
			)
			(layer "F.SilkS")
		)
		(fp_line
			(start -0.7874 -0.4064)
			(end 0.7874 -0.4064)
			(stroke
				(width 0.1524)
				(type default)
			)
			(layer "F.SilkS")
		)
		(fp_line
			(start 0.67945 0.3048)
			(end 0.120396 0.3048)
			(stroke
				(width 0.1)
				(type default)
			)
			(layer "F.Fab")
		)
		(fp_line
			(start 0.67945 -0.3048)
			(end 0.67945 0.3048)
			(stroke
				(width 0.1)
				(type default)
			)
			(layer "F.Fab")
		)
		(fp_line
			(start 0.12065 -0.2794)
			(end 0.12065 -0.3048)
			(stroke
				(width 0.1)
				(type default)
			)
			(layer "F.Fab")
		)
		(fp_line
			(start 0.12065 -0.3048)
			(end 0.67945 -0.3048)
			(stroke
				(width 0.1)
				(type default)
			)
			(layer "F.Fab")
		)
		(fp_line
			(start 0.120396 0.3048)
			(end 0.120396 0.2794)
			(stroke
				(width 0.1)
				(type default)
			)
			(layer "F.Fab")
		)
		(fp_line
			(start 0.120396 0.2794)
			(end -0.12065 0.2794)
			(stroke
				(width 0.1)
				(type default)
			)
			(layer "F.Fab")
		)
		(fp_line
			(start -0.12065 0.3048)
			(end -0.67945 0.3048)
			(stroke
				(width 0.1)
				(type default)
			)
			(layer "F.Fab")
		)
		(fp_line
			(start -0.12065 0.2794)
			(end -0.12065 0.3048)
			(stroke
				(width 0.1)
				(type default)
			)
			(layer "F.Fab")
		)
		(fp_line
			(start -0.12065 -0.2794)
			(end 0.12065 -0.2794)
			(stroke
				(width 0.1)
				(type default)
			)
			(layer "F.Fab")
		)
		(fp_line
			(start -0.12065 -0.305054)
			(end -0.12065 -0.2794)
			(stroke
				(width 0.1)
				(type default)
			)
			(layer "F.Fab")
		)
		(fp_line
			(start -0.67945 0.3048)
			(end -0.67945 -0.305054)
			(stroke
				(width 0.1)
				(type default)
			)
			(layer "F.Fab")
		)
		(fp_line
			(start -0.67945 -0.305054)
			(end -0.12065 -0.305054)
			(stroke
				(width 0.1)
				(type default)
			)
			(layer "F.Fab")
		)
		(pad "1" smd circle
			(at -0.40005 0 180)
			(size 0 0)
			(layers "F.Cu" "F.Mask" "F.Paste")
			(net "PCA9555_MB0_A2")
		)
		(pad "2" smd circle
			(at 0.40005 0 180)
			(size 0 0)
			(layers "F.Cu" "F.Mask" "F.Paste")
			(net "GND")
		)
	)
	(footprint ""
		(layer "F.Cu")
		(at 14.0589 -124.587 180)
		(property "Reference" "R5587"
			(at 0 0 180)
			(layer "F.SilkS")
			(hide yes)
			(effects
				(font
					(size 1.27 1.27)
				)
			)
		)
		(property "Value" ""
			(at 0 0 180)
			(layer "F.Fab")
			(effects
				(font
					(size 1.27 1.27)
				)
			)
		)
		(duplicate_pad_numbers_are_jumpers no)
		(fp_line
			(start 0.7874 0.4064)
			(end -0.7874 0.4064)
			(stroke
				(width 0.1524)
				(type default)
			)
			(layer "F.SilkS")
		)
		(fp_line
			(start 0.7874 -0.4064)
			(end 0.7874 0.4064)
			(stroke
				(width 0.1524)
				(type default)
			)
			(layer "F.SilkS")
		)
		(fp_line
			(start -0.7874 0.4064)
			(end -0.7874 -0.4064)
			(stroke
				(width 0.1524)
				(type default)
			)
			(layer "F.SilkS")
		)
		(fp_line
			(start -0.7874 -0.4064)
			(end 0.7874 -0.4064)
			(stroke
				(width 0.1524)
				(type default)
			)
			(layer "F.SilkS")
		)
		(fp_line
			(start 0.67945 0.3048)
			(end 0.120396 0.3048)
			(stroke
				(width 0.1)
				(type default)
			)
			(layer "F.Fab")
		)
		(fp_line
			(start 0.67945 -0.3048)
			(end 0.67945 0.3048)
			(stroke
				(width 0.1)
				(type default)
			)
			(layer "F.Fab")
		)
		(fp_line
			(start 0.12065 -0.2794)
			(end 0.12065 -0.3048)
			(stroke
				(width 0.1)
				(type default)
			)
			(layer "F.Fab")
		)
		(fp_line
			(start 0.12065 -0.3048)
			(end 0.67945 -0.3048)
			(stroke
				(width 0.1)
				(type default)
			)
			(layer "F.Fab")
		)
		(fp_line
			(start 0.120396 0.3048)
			(end 0.120396 0.2794)
			(stroke
				(width 0.1)
				(type default)
			)
			(layer "F.Fab")
		)
		(fp_line
			(start 0.120396 0.2794)
			(end -0.12065 0.2794)
			(stroke
				(width 0.1)
				(type default)
			)
			(layer "F.Fab")
		)
		(fp_line
			(start -0.12065 0.3048)
			(end -0.67945 0.3048)
			(stroke
				(width 0.1)
				(type default)
			)
			(layer "F.Fab")
		)
		(fp_line
			(start -0.12065 0.2794)
			(end -0.12065 0.3048)
			(stroke
				(width 0.1)
				(type default)
			)
			(layer "F.Fab")
		)
		(fp_line
			(start -0.12065 -0.2794)
			(end 0.12065 -0.2794)
			(stroke
				(width 0.1)
				(type default)
			)
			(layer "F.Fab")
		)
		(fp_line
			(start -0.12065 -0.305054)
			(end -0.12065 -0.2794)
			(stroke
				(width 0.1)
				(type default)
			)
			(layer "F.Fab")
		)
		(fp_line
			(start -0.67945 0.3048)
			(end -0.67945 -0.305054)
			(stroke
				(width 0.1)
				(type default)
			)
			(layer "F.Fab")
		)
		(fp_line
			(start -0.67945 -0.305054)
			(end -0.12065 -0.305054)
			(stroke
				(width 0.1)
				(type default)
			)
			(layer "F.Fab")
		)
		(pad "1" smd rect
			(at -0.40005 0)
			(size 0.4572 0.508)
			(layers "F.Cu" "F.Mask" "F.Paste")
			(net "FAN_5_TACH_IL")
		)
		(pad "2" smd rect
			(at 0.40005 0)
			(size 0.4572 0.508)
			(layers "F.Cu" "F.Mask" "F.Paste")
			(net "FAN_5_TACH_IL_R2")
		)
	)
	(footprint ""
		(layer "B.Cu")
		(at 9.906 -168.783 180)
		(property "Reference" "C57"
			(at 0 0 0)
			(layer "B.SilkS")
			(hide yes)
			(effects
				(font
					(size 1.27 1.27)
				)
				(justify mirror)
			)
		)
		(property "Value" ""
			(at 0 0 0)
			(layer "B.Fab")
			(effects
				(font
					(size 1.27 1.27)
				)
				(justify mirror)
			)
		)
		(duplicate_pad_numbers_are_jumpers no)
		(fp_line
			(start 0.7874 0.4064)
			(end 0.7874 -0.4064)
			(stroke
				(width 0.1524)
				(type default)
			)
			(layer "B.SilkS")
		)
		(fp_line
			(start 0.7874 -0.4064)
			(end -0.7874 -0.4064)
			(stroke
				(width 0.1524)
				(type default)
			)
			(layer "B.SilkS")
		)
		(fp_line
			(start -0.7874 0.4064)
			(end 0.7874 0.4064)
			(stroke
				(width 0.1524)
				(type default)
			)
			(layer "B.SilkS")
		)
		(fp_line
			(start -0.7874 -0.4064)
			(end -0.7874 0.4064)
			(stroke
				(width 0.1524)
				(type default)
			)
			(layer "B.SilkS")
		)
		(fp_line
			(start 0.67945 0.3048)
			(end 0.67945 -0.305054)
			(stroke
				(width 0.1)
				(type default)
			)
			(layer "B.Fab")
		)
		(fp_line
			(start 0.67945 -0.305054)
			(end 0.12065 -0.305054)
			(stroke
				(width 0.1)
				(type default)
			)
			(layer "B.Fab")
		)
		(fp_line
			(start 0.12065 0.3048)
			(end 0.67945 0.3048)
			(stroke
				(width 0.1)
				(type default)
			)
			(layer "B.Fab")
		)
		(fp_line
			(start 0.12065 0.2794)
			(end 0.12065 0.3048)
			(stroke
				(width 0.1)
				(type default)
			)
			(layer "B.Fab")
		)
		(fp_line
			(start 0.12065 -0.2794)
			(end -0.12065 -0.2794)
			(stroke
				(width 0.1)
				(type default)
			)
			(layer "B.Fab")
		)
		(fp_line
			(start 0.12065 -0.305054)
			(end 0.12065 -0.2794)
			(stroke
				(width 0.1)
				(type default)
			)
			(layer "B.Fab")
		)
		(fp_line
			(start -0.120396 0.3048)
			(end -0.120396 0.2794)
			(stroke
				(width 0.1)
				(type default)
			)
			(layer "B.Fab")
		)
		(fp_line
			(start -0.120396 0.2794)
			(end 0.12065 0.2794)
			(stroke
				(width 0.1)
				(type default)
			)
			(layer "B.Fab")
		)
		(fp_line
			(start -0.12065 -0.2794)
			(end -0.12065 -0.3048)
			(stroke
				(width 0.1)
				(type default)
			)
			(layer "B.Fab")
		)
		(fp_line
			(start -0.12065 -0.3048)
			(end -0.67945 -0.3048)
			(stroke
				(width 0.1)
				(type default)
			)
			(layer "B.Fab")
		)
		(fp_line
			(start -0.67945 0.3048)
			(end -0.120396 0.3048)
			(stroke
				(width 0.1)
				(type default)
			)
			(layer "B.Fab")
		)
		(fp_line
			(start -0.67945 -0.3048)
			(end -0.67945 0.3048)
			(stroke
				(width 0.1)
				(type default)
			)
			(layer "B.Fab")
		)
		(pad "1" smd circle
			(at 0.40005 0)
			(size 0 0)
			(layers "B.Cu" "B.Mask" "B.Paste")
			(net "P3V3_AUX")
		)
		(pad "2" smd circle
			(at -0.40005 0)
			(size 0 0)
			(layers "B.Cu" "B.Mask" "B.Paste")
			(net "GND")
		)
	)
	(footprint ""
		(layer "B.Cu")
		(at 44.704 -313.436 -90)
		(property "Reference" "C2120"
			(at 0 0 90)
			(layer "B.SilkS")
			(hide yes)
			(effects
				(font
					(size 1.27 1.27)
				)
				(justify mirror)
			)
		)
		(property "Value" ""
			(at 0 0 90)
			(layer "B.Fab")
			(effects
				(font
					(size 1.27 1.27)
				)
				(justify mirror)
			)
		)
		(duplicate_pad_numbers_are_jumpers no)
		(fp_line
			(start -1.2954 0.5842)
			(end 1.2954 0.5842)
			(stroke
				(width 0.1524)
				(type default)
			)
			(layer "B.SilkS")
		)
		(fp_line
			(start 1.2954 0.5842)
			(end 1.2954 -0.5842)
			(stroke
				(width 0.1524)
				(type default)
			)
			(layer "B.SilkS")
		)
		(fp_line
			(start -1.2954 -0.5842)
			(end -1.2954 0.5842)
			(stroke
				(width 0.1524)
				(type default)
			)
			(layer "B.SilkS")
		)
		(fp_line
			(start 1.2954 -0.5842)
			(end -1.2954 -0.5842)
			(stroke
				(width 0.1524)
				(type default)
			)
			(layer "B.SilkS")
		)
		(fp_line
			(start -0.8636 0.4572)
			(end 0.8636 0.4572)
			(stroke
				(width 0.1)
				(type default)
			)
			(layer "B.Fab")
		)
		(fp_line
			(start 0.8636 0.4572)
			(end 0.8636 0.4064)
			(stroke
				(width 0.1)
				(type default)
			)
			(layer "B.Fab")
		)
		(fp_line
			(start -1.1938 0.4064)
			(end -0.8636 0.4064)
			(stroke
				(width 0.1)
				(type default)
			)
			(layer "B.Fab")
		)
		(fp_line
			(start -0.8636 0.4064)
			(end -0.8636 0.4572)
			(stroke
				(width 0.1)
				(type default)
			)
			(layer "B.Fab")
		)
		(fp_line
			(start 0.8636 0.4064)
			(end 1.1938 0.4064)
			(stroke
				(width 0.1)
				(type default)
			)
			(layer "B.Fab")
		)
		(fp_line
			(start 1.1938 0.4064)
			(end 1.1938 -0.4064)
			(stroke
				(width 0.1)
				(type default)
			)
			(layer "B.Fab")
		)
		(fp_line
			(start -1.1938 -0.4064)
			(end -1.1938 0.4064)
			(stroke
				(width 0.1)
				(type default)
			)
			(layer "B.Fab")
		)
		(fp_line
			(start -0.8636 -0.4064)
			(end -1.1938 -0.4064)
			(stroke
				(width 0.1)
				(type default)
			)
			(layer "B.Fab")
		)
		(fp_line
			(start 0.8636 -0.4064)
			(end 0.8636 -0.4572)
			(stroke
				(width 0.1)
				(type default)
			)
			(layer "B.Fab")
		)
		(fp_line
			(start 1.1938 -0.4064)
			(end 0.8636 -0.4064)
			(stroke
				(width 0.1)
				(type default)
			)
			(layer "B.Fab")
		)
		(fp_line
			(start -0.8636 -0.4572)
			(end -0.8636 -0.4064)
			(stroke
				(width 0.1)
				(type default)
			)
			(layer "B.Fab")
		)
		(fp_line
			(start 0.8636 -0.4572)
			(end -0.8636 -0.4572)
			(stroke
				(width 0.1)
				(type default)
			)
			(layer "B.Fab")
		)
		(pad "1" smd rect
			(at 0.7366 0 180)
			(size 0.7112 0.8128)
			(layers "B.Cu" "B.Mask" "B.Paste")
			(net "U405_D1")
		)
		(pad "2" smd rect
			(at -0.7366 0 180)
			(size 0.7112 0.8128)
			(layers "B.Cu" "B.Mask" "B.Paste")
			(net "GND")
		)
	)
	(footprint ""
		(layer "B.Cu")
		(at 37.31768 -58.995056)
		(property "Reference" "PU3"
			(at 5.22732 2.252726 0)
			(unlocked yes)
			(layer "B.SilkS")
			(effects
				(font
					(size 0.7874 0.5842)
					(thickness 0.1524)
				)
				(justify left mirror)
			)
		)
		(property "Value" ""
			(at 0 0 0)
			(layer "B.Fab")
			(effects
				(font
					(size 1.27 1.27)
				)
				(justify mirror)
			)
		)
		(duplicate_pad_numbers_are_jumpers no)
		(fp_line
			(start -2.549906 -2.549906)
			(end -2.4384 -2.549906)
			(stroke
				(width 0.1524)
				(type default)
			)
			(layer "B.SilkS")
		)
		(fp_line
			(start -2.549906 -2.2352)
			(end -2.549906 -2.549906)
			(stroke
				(width 0.1524)
				(type default)
			)
			(layer "B.SilkS")
		)
		(fp_line
			(start -2.549906 -1.4986)
			(end -2.549906 -1.7526)
			(stroke
				(width 0.1524)
				(type default)
			)
			(layer "B.SilkS")
		)
		(fp_line
			(start -2.549906 -0.6858)
			(end -2.549906 -0.9144)
			(stroke
				(width 0.1524)
				(type default)
			)
			(layer "B.SilkS")
		)
		(fp_line
			(start -2.549906 0.9144)
			(end -2.549906 -0.1016)
			(stroke
				(width 0.1524)
				(type default)
			)
			(layer "B.SilkS")
		)
		(fp_line
			(start -2.549906 1.7526)
			(end -2.549906 1.4986)
			(stroke
				(width 0.1524)
				(type default)
			)
			(layer "B.SilkS")
		)
		(fp_line
			(start -2.549906 2.549906)
			(end -2.549906 2.2352)
			(stroke
				(width 0.1524)
				(type default)
			)
			(layer "B.SilkS")
		)
		(fp_line
			(start -2.4384 2.549906)
			(end -2.549906 2.549906)
			(stroke
				(width 0.1524)
				(type default)
			)
			(layer "B.SilkS")
		)
		(fp_line
			(start -2.199894 2.9464)
			(end -2.199894 3.4544)
			(stroke
				(width 0.1524)
				(type default)
			)
			(layer "B.SilkS")
		)
		(fp_line
			(start -1.800098 -3.9624)
			(end -1.800098 -2.9464)
			(stroke
				(width 0.1524)
				(type default)
			)
			(layer "B.SilkS")
		)
		(fp_line
			(start -0.199898 2.9464)
			(end -0.199898 3.9624)
			(stroke
				(width 0.1524)
				(type default)
			)
			(layer "B.SilkS")
		)
		(fp_line
			(start 0.199898 -3.4544)
			(end 0.199898 -2.9464)
			(stroke
				(width 0.1524)
				(type default)
			)
			(layer "B.SilkS")
		)
		(fp_line
			(start 1.800098 2.9464)
			(end 1.800098 3.4544)
			(stroke
				(width 0.1524)
				(type default)
			)
			(layer "B.SilkS")
		)
		(fp_line
			(start 2.199894 -3.9624)
			(end 2.199894 -2.9464)
			(stroke
				(width 0.1524)
				(type default)
			)
			(layer "B.SilkS")
		)
		(fp_line
			(start 2.4384 -2.549906)
			(end 2.549906 -2.549906)
			(stroke
				(width 0.1524)
				(type default)
			)
			(layer "B.SilkS")
		)
		(fp_line
			(start 2.549906 -2.549906)
			(end 2.549906 -2.2352)
			(stroke
				(width 0.1524)
				(type default)
			)
			(layer "B.SilkS")
		)
		(fp_line
			(start 2.549906 -1.7526)
			(end 2.549906 -1.4986)
			(stroke
				(width 0.1524)
				(type default)
			)
			(layer "B.SilkS")
		)
		(fp_line
			(start 2.549906 -0.9144)
			(end 2.549906 0.1016)
			(stroke
				(width 0.1524)
				(type default)
			)
			(layer "B.SilkS")
		)
		(fp_line
			(start 2.549906 0.6858)
			(end 2.549906 0.9144)
			(stroke
				(width 0.1524)
				(type default)
			)
			(layer "B.SilkS")
		)
		(fp_line
			(start 2.549906 1.4986)
			(end 2.549906 1.7526)
			(stroke
				(width 0.1524)
				(type default)
			)
			(layer "B.SilkS")
		)
		(fp_line
			(start 2.549906 2.2352)
			(end 2.549906 2.549906)
			(stroke
				(width 0.1524)
				(type default)
			)
			(layer "B.SilkS")
		)
		(fp_line
			(start 2.549906 2.549906)
			(end 2.4384 2.549906)
			(stroke
				(width 0.1524)
				(type default)
			)
			(layer "B.SilkS")
		)
		(fp_poly
			(pts
				(xy 3.7084 -1.584706) (xy 2.939034 -1.199896) (xy 3.7084 -0.81534)
			)
			(stroke
				(width 0)
				(type default)
			)
			(fill yes)
			(layer "B.SilkS")
		)
		(fp_line
			(start -2.549906 -2.549906)
			(end 2.549906 -2.549906)
			(stroke
				(width 0.1)
				(type default)
			)
			(layer "B.Fab")
		)
		(fp_line
			(start -2.549906 2.549906)
			(end -2.549906 -2.549906)
			(stroke
				(width 0.1)
				(type default)
			)
			(layer "B.Fab")
		)
		(fp_line
			(start -2.199894 2.9464)
			(end -2.199894 3.4544)
			(stroke
				(width 0.1)
				(type default)
			)
			(layer "B.Fab")
		)
		(fp_line
			(start -1.800098 -3.9624)
			(end -1.800098 -2.9464)
			(stroke
				(width 0.1)
				(type default)
			)
			(layer "B.Fab")
		)
		(fp_line
			(start -0.199898 2.9464)
			(end -0.199898 3.9624)
			(stroke
				(width 0.1)
				(type default)
			)
			(layer "B.Fab")
		)
		(fp_line
			(start 0.199898 -3.4544)
			(end 0.199898 -2.9464)
			(stroke
				(width 0.1)
				(type default)
			)
			(layer "B.Fab")
		)
		(fp_line
			(start 1.800098 2.9464)
			(end 1.800098 3.4544)
			(stroke
				(width 0.1)
				(type default)
			)
			(layer "B.Fab")
		)
		(fp_line
			(start 2.199894 -3.9624)
			(end 2.199894 -2.9464)
			(stroke
				(width 0.1)
				(type default)
			)
			(layer "B.Fab")
		)
		(fp_line
			(start 2.549906 -2.549906)
			(end 2.549906 2.549906)
			(stroke
				(width 0.1)
				(type default)
			)
			(layer "B.Fab")
		)
		(fp_line
			(start 2.549906 2.549906)
			(end -2.549906 2.549906)
			(stroke
				(width 0.1)
				(type default)
			)
			(layer "B.Fab")
		)
		(fp_poly
			(pts
				(xy 3.7084 -1.584706) (xy 2.939034 -1.199896) (xy 3.7084 -0.81534)
			)
			(stroke
				(width 0)
				(type default)
			)
			(fill yes)
			(layer "B.Fab")
		)
		(fp_text user "16"
			(at -3.329432 1.2192 270)
			(unlocked yes)
			(layer "B.SilkS")
			(effects
				(font
					(size 0.635 0.4064)
					(thickness 0.1524)
				)
				(justify mirror)
			)
		)
		(fp_text user "18"
			(at -3.304032 -1.2192 270)
			(unlocked yes)
			(layer "B.SilkS")
			(effects
				(font
					(size 0.635 0.4064)
					(thickness 0.1524)
				)
				(justify mirror)
			)
		)
		(fp_text user "15"
			(at -2.8956 3.126232 0)
			(unlocked yes)
			(layer "B.SilkS")
			(effects
				(font
					(size 0.635 0.4064)
					(thickness 0.1524)
				)
				(justify mirror)
			)
		)
		(fp_text user "19"
			(at -2.8448 -3.096768 0)
			(unlocked yes)
			(layer "B.SilkS")
			(effects
				(font
					(size 0.635 0.4064)
					(thickness 0.1524)
				)
				(justify mirror)
			)
		)
		(fp_text user "4"
			(at 2.6416 3.151632 0)
			(unlocked yes)
			(layer "B.SilkS")
			(effects
				(font
					(size 0.635 0.4064)
					(thickness 0.1524)
				)
				(justify mirror)
			)
		)
		(fp_text user "30"
			(at 2.9464 -3.045968 0)
			(unlocked yes)
			(layer "B.SilkS")
			(effects
				(font
					(size 0.635 0.4064)
					(thickness 0.1524)
				)
				(justify mirror)
			)
		)
		(fp_text user "3"
			(at 3.299968 1.1938 270)
			(unlocked yes)
			(layer "B.SilkS")
			(effects
				(font
					(size 0.635 0.4064)
					(thickness 0.1524)
				)
				(justify mirror)
			)
		)
		(fp_text user "16"
			(at -3.329432 1.2192 270)
			(unlocked yes)
			(layer "B.Fab")
			(effects
				(font
					(size 0.635 0.4064)
					(thickness 0.1524)
				)
				(justify mirror)
			)
		)
		(fp_text user "18"
			(at -3.304032 -1.2192 270)
			(unlocked yes)
			(layer "B.Fab")
			(effects
				(font
					(size 0.635 0.4064)
					(thickness 0.1524)
				)
				(justify mirror)
			)
		)
		(fp_text user "15"
			(at -2.8956 3.126232 0)
			(unlocked yes)
			(layer "B.Fab")
			(effects
				(font
					(size 0.635 0.4064)
					(thickness 0.1524)
				)
				(justify mirror)
			)
		)
		(fp_text user "19"
			(at -2.8448 -3.096768 0)
			(unlocked yes)
			(layer "B.Fab")
			(effects
				(font
					(size 0.635 0.4064)
					(thickness 0.1524)
				)
				(justify mirror)
			)
		)
		(fp_text user "4"
			(at 2.6416 3.151632 0)
			(unlocked yes)
			(layer "B.Fab")
			(effects
				(font
					(size 0.635 0.4064)
					(thickness 0.1524)
				)
				(justify mirror)
			)
		)
		(fp_text user "30"
			(at 2.9464 -3.045968 0)
			(unlocked yes)
			(layer "B.Fab")
			(effects
				(font
					(size 0.635 0.4064)
					(thickness 0.1524)
				)
				(justify mirror)
			)
		)
		(fp_text user "3"
			(at 3.299968 1.1938 270)
			(unlocked yes)
			(layer "B.Fab")
			(effects
				(font
					(size 0.635 0.4064)
					(thickness 0.1524)
				)
				(justify mirror)
			)
		)
		(pad "1" smd circle
			(at 1.599946 -1.199896 270)
			(size 0 0)
			(layers "B.Cu" "B.Mask" "B.Paste")
			(net "P52V_HSC")
		)
		(pad "2" smd rect
			(at 1.549908 0.40005 90)
			(size 0.3048 2.5146)
			(layers "B.Cu" "B.Mask" "B.Paste")
			(net "P52V_HSC")
		)
		(pad "3" smd rect
			(at 1.549908 1.199896 90)
			(size 0.3048 2.5146)
			(layers "B.Cu" "B.Mask" "B.Paste")
			(net "P52V_FAN_3")
		)
		(pad "4" smd circle
			(at 2.199894 2.350008)
			(size 0 0)
			(layers "B.Cu" "B.Mask" "B.Paste")
			(net "P52V_FAN_3")
		)
		(pad "5" smd rect
			(at 1.800098 2.350008 180)
			(size 0.1778 0.9144)
			(layers "B.Cu" "B.Mask" "B.Paste")
			(net "P52V_FAN_3")
		)
		(pad "6" smd rect
			(at 1.400048 2.350008 180)
			(size 0.1778 0.9144)
			(layers "B.Cu" "B.Mask" "B.Paste")
			(net "P52V_FAN_3")
		)
		(pad "7" smd rect
			(at 0.999998 2.350008 180)
			(size 0.1778 0.9144)
			(layers "B.Cu" "B.Mask" "B.Paste")
			(net "P52V_FAN_3")
		)
		(pad "8" smd rect
			(at 0.599948 2.350008 180)
			(size 0.1778 0.9144)
			(layers "B.Cu" "B.Mask" "B.Paste")
			(net "P52V_FAN_3")
		)
		(pad "9" smd rect
			(at 0.199898 2.350008 180)
			(size 0.1778 0.9144)
			(layers "B.Cu" "B.Mask" "B.Paste")
			(net "P52V_FAN_3")
		)
		(pad "10" smd rect
			(at -0.199898 2.350008 180)
			(size 0.1778 0.9144)
			(layers "B.Cu" "B.Mask" "B.Paste")
			(net "P52V_FAN_3")
		)
		(pad "11" smd rect
			(at -0.599948 2.350008 180)
			(size 0.1778 0.9144)
			(layers "B.Cu" "B.Mask" "B.Paste")
			(net "P52V_FAN_3")
		)
		(pad "12" smd rect
			(at -0.999998 2.350008 180)
			(size 0.1778 0.9144)
			(layers "B.Cu" "B.Mask" "B.Paste")
			(net "P52V_FAN_3")
		)
		(pad "13" smd rect
			(at -1.400048 2.350008 180)
			(size 0.1778 0.9144)
			(layers "B.Cu" "B.Mask" "B.Paste")
			(net "P52V_FAN_3")
		)
		(pad "14" smd rect
			(at -1.800098 2.350008 180)
			(size 0.1778 0.9144)
			(layers "B.Cu" "B.Mask" "B.Paste")
			(net "P52V_FAN_3")
		)
		(pad "15" smd circle
			(at -2.199894 2.350008)
			(size 0 0)
			(layers "B.Cu" "B.Mask" "B.Paste")
			(net "P52V_FAN_3")
		)
		(pad "16" smd rect
			(at -1.549908 1.199896 90)
			(size 0.3048 2.5146)
			(layers "B.Cu" "B.Mask" "B.Paste")
			(net "P52V_FAN_3")
		)
		(pad "17" smd rect
			(at -1.549908 -0.40005 90)
			(size 0.3048 2.5146)
			(layers "B.Cu" "B.Mask" "B.Paste")
			(net "P52V_FAN_3")
		)
		(pad "18" smd rect
			(at -1.549908 -1.199896 90)
			(size 0.3048 2.5146)
			(layers "B.Cu" "B.Mask" "B.Paste")
			(net "P52V_HSC")
		)
		(pad "19" smd circle
			(at -2.199894 -2.350008 180)
			(size 0 0)
			(layers "B.Cu" "B.Mask" "B.Paste")
			(net "FAN_3_CS")
		)
		(pad "20" smd rect
			(at -1.800098 -2.350008 180)
			(size 0.1778 0.9144)
			(layers "B.Cu" "B.Mask" "B.Paste")
			(net "FAN_3_IMON")
		)
		(pad "21" smd rect
			(at -1.400048 -2.350008 180)
			(size 0.1778 0.9144)
			(layers "B.Cu" "B.Mask" "B.Paste")
			(net "FAN_3_SS")
		)
		(pad "22" smd rect
			(at -0.999998 -2.350008 180)
			(size 0.1778 0.9144)
			(layers "B.Cu" "B.Mask" "B.Paste")
			(net "FAN_3_FAULT")
		)
		(pad "23" smd rect
			(at -0.599948 -2.350008 180)
			(size 0.1778 0.9144)
			(layers "B.Cu" "B.Mask" "B.Paste")
			(net "FAN_3_TIMER")
		)
		(pad "24" smd rect
			(at -0.199898 -2.350008 180)
			(size 0.1778 0.9144)
			(layers "B.Cu" "B.Mask" "B.Paste")
			(net "FAN_3_CLREF")
		)
		(pad "25" smd rect
			(at 0.199898 -2.350008 180)
			(size 0.1778 0.9144)
			(layers "B.Cu" "B.Mask" "B.Paste")
			(net "GND")
		)
		(pad "26" smd rect
			(at 0.599948 -2.350008 180)
			(size 0.1778 0.9144)
			(layers "B.Cu" "B.Mask" "B.Paste")
			(net "FAN_3_ON")
		)
		(pad "27" smd rect
			(at 0.999998 -2.350008 180)
			(size 0.1778 0.9144)
			(layers "B.Cu" "B.Mask" "B.Paste")
			(net "FAN_3_P3V_R")
		)
		(pad "28" smd rect
			(at 1.400048 -2.350008 180)
			(size 0.1778 0.9144)
			(layers "B.Cu" "B.Mask" "B.Paste")
			(net "FAN_3_P5V")
		)
		(pad "29" smd rect
			(at 1.800098 -2.350008 180)
			(size 0.1778 0.9144)
			(layers "B.Cu" "B.Mask" "B.Paste")
			(net "FAN_3_TEMP")
		)
		(pad "30" smd circle
			(at 2.199894 -2.350008 180)
			(size 0 0)
			(layers "B.Cu" "B.Mask" "B.Paste")
			(net "FAN_3_MODE")
		)
	)
	(footprint ""
		(layer "B.Cu")
		(at 35.1536 -88.399112)
		(property "Reference" "C2102"
			(at 0 0 0)
			(layer "B.SilkS")
			(hide yes)
			(effects
				(font
					(size 1.27 1.27)
				)
				(justify mirror)
			)
		)
		(property "Value" ""
			(at 0 0 0)
			(layer "B.Fab")
			(effects
				(font
					(size 1.27 1.27)
				)
				(justify mirror)
			)
		)
		(duplicate_pad_numbers_are_jumpers no)
		(fp_line
			(start -2.2098 -0.9398)
			(end -2.2098 0.9398)
			(stroke
				(width 0.1524)
				(type default)
			)
			(layer "B.SilkS")
		)
		(fp_line
			(start -2.2098 0.9398)
			(end 2.2098 0.9398)
			(stroke
				(width 0.1524)
				(type default)
			)
			(layer "B.SilkS")
		)
		(fp_line
			(start 2.2098 -0.9398)
			(end -2.2098 -0.9398)
			(stroke
				(width 0.1524)
				(type default)
			)
			(layer "B.SilkS")
		)
		(fp_line
			(start 2.2098 0.9398)
			(end 2.2098 -0.9398)
			(stroke
				(width 0.1524)
				(type default)
			)
			(layer "B.SilkS")
		)
		(fp_line
			(start -1.700022 -0.899922)
			(end -1.700022 0.899922)
			(stroke
				(width 0.1)
				(type default)
			)
			(layer "B.Fab")
		)
		(fp_line
			(start -1.700022 0.899922)
			(end 1.700022 0.899922)
			(stroke
				(width 0.1)
				(type default)
			)
			(layer "B.Fab")
		)
		(fp_line
			(start 1.700022 -0.899922)
			(end -1.700022 -0.899922)
			(stroke
				(width 0.1)
				(type default)
			)
			(layer "B.Fab")
		)
		(fp_line
			(start 1.700022 0.899922)
			(end 1.700022 -0.899922)
			(stroke
				(width 0.1)
				(type default)
			)
			(layer "B.Fab")
		)
		(pad "1" smd rect
			(at 1.4732 0)
			(size 1.1684 1.5748)
			(layers "B.Cu" "B.Mask" "B.Paste")
			(net "P52V_FAN_2")
		)
		(pad "2" smd rect
			(at -1.4732 0)
			(size 1.1684 1.5748)
			(layers "B.Cu" "B.Mask" "B.Paste")
			(net "GND")
		)
	)
	(footprint ""
		(layer "B.Cu")
		(at 34.163 -250.23699 -90)
		(property "Reference" "PC27"
			(at 0 0 90)
			(layer "B.SilkS")
			(hide yes)
			(effects
				(font
					(size 1.27 1.27)
				)
				(justify mirror)
			)
		)
		(property "Value" ""
			(at 0 0 90)
			(layer "B.Fab")
			(effects
				(font
					(size 1.27 1.27)
				)
				(justify mirror)
			)
		)
		(duplicate_pad_numbers_are_jumpers no)
		(fp_line
			(start -0.7874 0.4064)
			(end 0.7874 0.4064)
			(stroke
				(width 0.1524)
				(type default)
			)
			(layer "B.SilkS")
		)
		(fp_line
			(start 0.7874 0.4064)
			(end 0.7874 -0.4064)
			(stroke
				(width 0.1524)
				(type default)
			)
			(layer "B.SilkS")
		)
		(fp_line
			(start -0.7874 -0.4064)
			(end -0.7874 0.4064)
			(stroke
				(width 0.1524)
				(type default)
			)
			(layer "B.SilkS")
		)
		(fp_line
			(start 0.7874 -0.4064)
			(end -0.7874 -0.4064)
			(stroke
				(width 0.1524)
				(type default)
			)
			(layer "B.SilkS")
		)
		(fp_line
			(start -0.67945 0.3048)
			(end -0.120396 0.3048)
			(stroke
				(width 0.1)
				(type default)
			)
			(layer "B.Fab")
		)
		(fp_line
			(start -0.120396 0.3048)
			(end -0.120396 0.2794)
			(stroke
				(width 0.1)
				(type default)
			)
			(layer "B.Fab")
		)
		(fp_line
			(start 0.12065 0.3048)
			(end 0.67945 0.3048)
			(stroke
				(width 0.1)
				(type default)
			)
			(layer "B.Fab")
		)
		(fp_line
			(start 0.67945 0.3048)
			(end 0.67945 -0.305054)
			(stroke
				(width 0.1)
				(type default)
			)
			(layer "B.Fab")
		)
		(fp_line
			(start -0.120396 0.2794)
			(end 0.12065 0.2794)
			(stroke
				(width 0.1)
				(type default)
			)
			(layer "B.Fab")
		)
		(fp_line
			(start 0.12065 0.2794)
			(end 0.12065 0.3048)
			(stroke
				(width 0.1)
				(type default)
			)
			(layer "B.Fab")
		)
		(fp_line
			(start -0.12065 -0.2794)
			(end -0.12065 -0.3048)
			(stroke
				(width 0.1)
				(type default)
			)
			(layer "B.Fab")
		)
		(fp_line
			(start 0.12065 -0.2794)
			(end -0.12065 -0.2794)
			(stroke
				(width 0.1)
				(type default)
			)
			(layer "B.Fab")
		)
		(fp_line
			(start -0.67945 -0.3048)
			(end -0.67945 0.3048)
			(stroke
				(width 0.1)
				(type default)
			)
			(layer "B.Fab")
		)
		(fp_line
			(start -0.12065 -0.3048)
			(end -0.67945 -0.3048)
			(stroke
				(width 0.1)
				(type default)
			)
			(layer "B.Fab")
		)
		(fp_line
			(start 0.12065 -0.305054)
			(end 0.12065 -0.2794)
			(stroke
				(width 0.1)
				(type default)
			)
			(layer "B.Fab")
		)
		(fp_line
			(start 0.67945 -0.305054)
			(end 0.12065 -0.305054)
			(stroke
				(width 0.1)
				(type default)
			)
			(layer "B.Fab")
		)
		(pad "1" smd circle
			(at 0.40005 0 90)
			(size 0 0)
			(layers "B.Cu" "B.Mask" "B.Paste")
			(net "FAN_1_SS")
		)
		(pad "2" smd circle
			(at -0.40005 0 90)
			(size 0 0)
			(layers "B.Cu" "B.Mask" "B.Paste")
			(net "GND")
		)
	)
	(footprint ""
		(layer "B.Cu")
		(at 35.1536 -90.939112)
		(property "Reference" "C2104"
			(at 0 0 0)
			(layer "B.SilkS")
			(hide yes)
			(effects
				(font
					(size 1.27 1.27)
				)
				(justify mirror)
			)
		)
		(property "Value" ""
			(at 0 0 0)
			(layer "B.Fab")
			(effects
				(font
					(size 1.27 1.27)
				)
				(justify mirror)
			)
		)
		(duplicate_pad_numbers_are_jumpers no)
		(fp_line
			(start -2.2098 -0.9398)
			(end -2.2098 0.9398)
			(stroke
				(width 0.1524)
				(type default)
			)
			(layer "B.SilkS")
		)
		(fp_line
			(start -2.2098 0.9398)
			(end 2.2098 0.9398)
			(stroke
				(width 0.1524)
				(type default)
			)
			(layer "B.SilkS")
		)
		(fp_line
			(start 2.2098 -0.9398)
			(end -2.2098 -0.9398)
			(stroke
				(width 0.1524)
				(type default)
			)
			(layer "B.SilkS")
		)
		(fp_line
			(start 2.2098 0.9398)
			(end 2.2098 -0.9398)
			(stroke
				(width 0.1524)
				(type default)
			)
			(layer "B.SilkS")
		)
		(fp_line
			(start -1.700022 -0.899922)
			(end -1.700022 0.899922)
			(stroke
				(width 0.1)
				(type default)
			)
			(layer "B.Fab")
		)
		(fp_line
			(start -1.700022 0.899922)
			(end 1.700022 0.899922)
			(stroke
				(width 0.1)
				(type default)
			)
			(layer "B.Fab")
		)
		(fp_line
			(start 1.700022 -0.899922)
			(end -1.700022 -0.899922)
			(stroke
				(width 0.1)
				(type default)
			)
			(layer "B.Fab")
		)
		(fp_line
			(start 1.700022 0.899922)
			(end 1.700022 -0.899922)
			(stroke
				(width 0.1)
				(type default)
			)
			(layer "B.Fab")
		)
		(pad "1" smd rect
			(at 1.4732 0)
			(size 1.1684 1.5748)
			(layers "B.Cu" "B.Mask" "B.Paste")
			(net "P52V_FAN_2")
		)
		(pad "2" smd rect
			(at -1.4732 0)
			(size 1.1684 1.5748)
			(layers "B.Cu" "B.Mask" "B.Paste")
			(net "GND")
		)
	)
	(footprint ""
		(layer "B.Cu")
		(at 7.747 -249.428 -90)
		(property "Reference" "PC50"
			(at 0 0 90)
			(layer "B.SilkS")
			(hide yes)
			(effects
				(font
					(size 1.27 1.27)
				)
				(justify mirror)
			)
		)
		(property "Value" ""
			(at 0 0 90)
			(layer "B.Fab")
			(effects
				(font
					(size 1.27 1.27)
				)
				(justify mirror)
			)
		)
		(duplicate_pad_numbers_are_jumpers no)
		(fp_line
			(start -0.7874 0.4064)
			(end 0.7874 0.4064)
			(stroke
				(width 0.1524)
				(type default)
			)
			(layer "B.SilkS")
		)
		(fp_line
			(start 0.7874 0.4064)
			(end 0.7874 -0.4064)
			(stroke
				(width 0.1524)
				(type default)
			)
			(layer "B.SilkS")
		)
		(fp_line
			(start -0.7874 -0.4064)
			(end -0.7874 0.4064)
			(stroke
				(width 0.1524)
				(type default)
			)
			(layer "B.SilkS")
		)
		(fp_line
			(start 0.7874 -0.4064)
			(end -0.7874 -0.4064)
			(stroke
				(width 0.1524)
				(type default)
			)
			(layer "B.SilkS")
		)
		(fp_line
			(start -0.67945 0.3048)
			(end -0.120396 0.3048)
			(stroke
				(width 0.1)
				(type default)
			)
			(layer "B.Fab")
		)
		(fp_line
			(start -0.120396 0.3048)
			(end -0.120396 0.2794)
			(stroke
				(width 0.1)
				(type default)
			)
			(layer "B.Fab")
		)
		(fp_line
			(start 0.12065 0.3048)
			(end 0.67945 0.3048)
			(stroke
				(width 0.1)
				(type default)
			)
			(layer "B.Fab")
		)
		(fp_line
			(start 0.67945 0.3048)
			(end 0.67945 -0.305054)
			(stroke
				(width 0.1)
				(type default)
			)
			(layer "B.Fab")
		)
		(fp_line
			(start -0.120396 0.2794)
			(end 0.12065 0.2794)
			(stroke
				(width 0.1)
				(type default)
			)
			(layer "B.Fab")
		)
		(fp_line
			(start 0.12065 0.2794)
			(end 0.12065 0.3048)
			(stroke
				(width 0.1)
				(type default)
			)
			(layer "B.Fab")
		)
		(fp_line
			(start -0.12065 -0.2794)
			(end -0.12065 -0.3048)
			(stroke
				(width 0.1)
				(type default)
			)
			(layer "B.Fab")
		)
		(fp_line
			(start 0.12065 -0.2794)
			(end -0.12065 -0.2794)
			(stroke
				(width 0.1)
				(type default)
			)
			(layer "B.Fab")
		)
		(fp_line
			(start -0.67945 -0.3048)
			(end -0.67945 0.3048)
			(stroke
				(width 0.1)
				(type default)
			)
			(layer "B.Fab")
		)
		(fp_line
			(start -0.12065 -0.3048)
			(end -0.67945 -0.3048)
			(stroke
				(width 0.1)
				(type default)
			)
			(layer "B.Fab")
		)
		(fp_line
			(start 0.12065 -0.305054)
			(end 0.12065 -0.2794)
			(stroke
				(width 0.1)
				(type default)
			)
			(layer "B.Fab")
		)
		(fp_line
			(start 0.67945 -0.305054)
			(end 0.12065 -0.305054)
			(stroke
				(width 0.1)
				(type default)
			)
			(layer "B.Fab")
		)
		(pad "1" smd circle
			(at 0.40005 0 90)
			(size 0 0)
			(layers "B.Cu" "B.Mask" "B.Paste")
			(net "FAN_6_P3V_R")
		)
		(pad "2" smd circle
			(at -0.40005 0 90)
			(size 0 0)
			(layers "B.Cu" "B.Mask" "B.Paste")
			(net "GND")
		)
	)
	(footprint ""
		(layer "B.Cu")
		(at 44.069 -258.572 90)
		(property "Reference" "PC6"
			(at 0 0 90)
			(layer "B.SilkS")
			(hide yes)
			(effects
				(font
					(size 1.27 1.27)
				)
				(justify mirror)
			)
		)
		(property "Value" ""
			(at 0 0 90)
			(layer "B.Fab")
			(effects
				(font
					(size 1.27 1.27)
				)
				(justify mirror)
			)
		)
		(duplicate_pad_numbers_are_jumpers no)
		(fp_line
			(start 0.7874 -0.4064)
			(end -0.7874 -0.4064)
			(stroke
				(width 0.1524)
				(type default)
			)
			(layer "B.SilkS")
		)
		(fp_line
			(start -0.7874 -0.4064)
			(end -0.7874 0.4064)
			(stroke
				(width 0.1524)
				(type default)
			)
			(layer "B.SilkS")
		)
		(fp_line
			(start 0.7874 0.4064)
			(end 0.7874 -0.4064)
			(stroke
				(width 0.1524)
				(type default)
			)
			(layer "B.SilkS")
		)
		(fp_line
			(start -0.7874 0.4064)
			(end 0.7874 0.4064)
			(stroke
				(width 0.1524)
				(type default)
			)
			(layer "B.SilkS")
		)
		(fp_line
			(start 0.67945 -0.305054)
			(end 0.12065 -0.305054)
			(stroke
				(width 0.1)
				(type default)
			)
			(layer "B.Fab")
		)
		(fp_line
			(start 0.12065 -0.305054)
			(end 0.12065 -0.2794)
			(stroke
				(width 0.1)
				(type default)
			)
			(layer "B.Fab")
		)
		(fp_line
			(start -0.12065 -0.3048)
			(end -0.67945 -0.3048)
			(stroke
				(width 0.1)
				(type default)
			)
			(layer "B.Fab")
		)
		(fp_line
			(start -0.67945 -0.3048)
			(end -0.67945 0.3048)
			(stroke
				(width 0.1)
				(type default)
			)
			(layer "B.Fab")
		)
		(fp_line
			(start 0.12065 -0.2794)
			(end -0.12065 -0.2794)
			(stroke
				(width 0.1)
				(type default)
			)
			(layer "B.Fab")
		)
		(fp_line
			(start -0.12065 -0.2794)
			(end -0.12065 -0.3048)
			(stroke
				(width 0.1)
				(type default)
			)
			(layer "B.Fab")
		)
		(fp_line
			(start 0.12065 0.2794)
			(end 0.12065 0.3048)
			(stroke
				(width 0.1)
				(type default)
			)
			(layer "B.Fab")
		)
		(fp_line
			(start -0.120396 0.2794)
			(end 0.12065 0.2794)
			(stroke
				(width 0.1)
				(type default)
			)
			(layer "B.Fab")
		)
		(fp_line
			(start 0.67945 0.3048)
			(end 0.67945 -0.305054)
			(stroke
				(width 0.1)
				(type default)
			)
			(layer "B.Fab")
		)
		(fp_line
			(start 0.12065 0.3048)
			(end 0.67945 0.3048)
			(stroke
				(width 0.1)
				(type default)
			)
			(layer "B.Fab")
		)
		(fp_line
			(start -0.120396 0.3048)
			(end -0.120396 0.2794)
			(stroke
				(width 0.1)
				(type default)
			)
			(layer "B.Fab")
		)
		(fp_line
			(start -0.67945 0.3048)
			(end -0.120396 0.3048)
			(stroke
				(width 0.1)
				(type default)
			)
			(layer "B.Fab")
		)
		(pad "1" smd circle
			(at 0.40005 0 270)
			(size 0 0)
			(layers "B.Cu" "B.Mask" "B.Paste")
			(net "FAN_0_TIMER")
		)
		(pad "2" smd circle
			(at -0.40005 0 270)
			(size 0 0)
			(layers "B.Cu" "B.Mask" "B.Paste")
			(net "GND")
		)
	)
	(footprint ""
		(layer "B.Cu")
		(at 6.700012 -104.709976 180)
		(property "Reference" "J6"
			(at 2.001012 19.215354 0)
			(unlocked yes)
			(layer "B.SilkS")
			(effects
				(font
					(size 0.7874 0.5842)
					(thickness 0.1524)
				)
				(justify left mirror)
			)
		)
		(property "Value" ""
			(at 0 0 0)
			(layer "B.Fab")
			(effects
				(font
					(size 1.27 1.27)
				)
				(justify mirror)
			)
		)
		(duplicate_pad_numbers_are_jumpers no)
		(fp_line
			(start 4.350004 18.524982)
			(end -6.35 18.524982)
			(stroke
				(width 0.1524)
				(type default)
			)
			(layer "B.SilkS")
		)
		(fp_line
			(start 4.350004 -4.52501)
			(end 4.350004 18.524982)
			(stroke
				(width 0.1524)
				(type default)
			)
			(layer "B.SilkS")
		)
		(fp_line
			(start 1.249934 15.424912)
			(end -3.24993 15.424912)
			(stroke
				(width 0.1524)
				(type default)
			)
			(layer "B.SilkS")
		)
		(fp_line
			(start 1.249934 8.200136)
			(end 4.350004 8.200136)
			(stroke
				(width 0.1524)
				(type default)
			)
			(layer "B.SilkS")
		)
		(fp_line
			(start 1.249934 8.200136)
			(end 1.249934 15.424912)
			(stroke
				(width 0.1524)
				(type default)
			)
			(layer "B.SilkS")
		)
		(fp_line
			(start 1.249934 5.799836)
			(end 4.350004 5.799836)
			(stroke
				(width 0.1524)
				(type default)
			)
			(layer "B.SilkS")
		)
		(fp_line
			(start 1.249934 -1.42494)
			(end 1.249934 5.799836)
			(stroke
				(width 0.1524)
				(type default)
			)
			(layer "B.SilkS")
		)
		(fp_line
			(start -0.029972 -1.42494)
			(end 1.249934 -1.42494)
			(stroke
				(width 0.1524)
				(type default)
			)
			(layer "B.SilkS")
		)
		(fp_line
			(start -3.24993 15.424912)
			(end -3.24993 -1.42494)
			(stroke
				(width 0.1524)
				(type default)
			)
			(layer "B.SilkS")
		)
		(fp_line
			(start -3.24993 -1.42494)
			(end -1.96977 -1.42494)
			(stroke
				(width 0.1524)
				(type default)
			)
			(layer "B.SilkS")
		)
		(fp_line
			(start -6.35 18.524982)
			(end -6.35 -4.52501)
			(stroke
				(width 0.1524)
				(type default)
			)
			(layer "B.SilkS")
		)
		(fp_line
			(start -6.35 -4.52501)
			(end 4.350004 -4.52501)
			(stroke
				(width 0.1524)
				(type default)
			)
			(layer "B.SilkS")
		)
		(fp_poly
			(pts
				(xy 5.527802 -0.508) (xy 5.527802 0.508) (xy 4.511802 0)
			)
			(stroke
				(width 0)
				(type default)
			)
			(fill yes)
			(layer "B.SilkS")
		)
		(fp_line
			(start 4.350004 18.524982)
			(end -6.35 18.524982)
			(stroke
				(width 0.1)
				(type default)
			)
			(layer "B.Fab")
		)
		(fp_line
			(start 4.350004 -4.52501)
			(end 4.350004 18.524982)
			(stroke
				(width 0.1)
				(type default)
			)
			(layer "B.Fab")
		)
		(fp_line
			(start -6.35 18.524982)
			(end -6.35 -4.52501)
			(stroke
				(width 0.1)
				(type default)
			)
			(layer "B.Fab")
		)
		(fp_line
			(start -6.35 -4.52501)
			(end 4.350004 -4.52501)
			(stroke
				(width 0.1)
				(type default)
			)
			(layer "B.Fab")
		)
		(fp_poly
			(pts
				(xy 5.527802 -0.508) (xy 5.527802 0.508) (xy 4.511802 0)
			)
			(stroke
				(width 0)
				(type default)
			)
			(fill yes)
			(layer "B.Fab")
		)
		(pad "" np_thru_hole circle
			(at -0.999998 -1.89992 90)
			(size 1.4986 1.4986)
			(drill 1.4986)
			(layers "*.Cu" "*.Mask")
			(clearance 0.381)
			(thermal_gap 0.381)
		)
		(pad "1" thru_hole rect
			(at 0 0 90)
			(size 1.3716 1.3716)
			(drill 0.9652)
			(layers "*.Cu" "*.Mask")
			(remove_unused_layers no)
			(net "FAN_5_TACH_IL_D")
			(clearance 0.0508)
			(padstack
				(mode front_inner_back)
				(layer "Inner"
					(shape circle)
					(size 1.3716 1.3716)
					(clearance 0.0508)
				)
				(layer "B.Cu"
					(shape rect)
					(size 1.3716 1.3716)
					(thermal_gap 0.0508)
					(clearance 0.0508)
				)
			)
		)
		(pad "2" thru_hole circle
			(at -1.999996 0 90)
			(size 1.3716 1.3716)
			(drill 0.9652)
			(layers "*.Cu" "*.Mask")
			(remove_unused_layers no)
			(net "FAN_5_PWM_OL_R")
			(clearance 0.0508)
			(thermal_gap 0.0508)
		)
		(pad "3" thru_hole circle
			(at 0 1.999996 90)
			(size 1.3716 1.3716)
			(drill 0.9652)
			(layers "*.Cu" "*.Mask")
			(remove_unused_layers no)
			(net "FAN_5_PWM_IL_R")
			(clearance 0.0508)
			(thermal_gap 0.0508)
		)
		(pad "4" thru_hole circle
			(at -1.999996 1.999996 90)
			(size 1.3716 1.3716)
			(drill 0.9652)
			(layers "*.Cu" "*.Mask")
			(remove_unused_layers no)
			(net "FAN_5_PRESENT_R_N")
			(clearance 0.0508)
			(thermal_gap 0.0508)
		)
		(pad "5" thru_hole circle
			(at 0 3.999992 90)
			(size 1.3716 1.3716)
			(drill 0.9652)
			(layers "*.Cu" "*.Mask")
			(remove_unused_layers no)
			(net "P12V_LED_R1_FAN5")
			(clearance 0.0508)
			(thermal_gap 0.0508)
		)
		(pad "6" thru_hole circle
			(at -1.999996 3.999992 90)
			(size 1.3716 1.3716)
			(drill 0.9652)
			(layers "*.Cu" "*.Mask")
			(remove_unused_layers no)
			(net "SMB_FAN5_SCL_R")
			(clearance 0.0508)
			(thermal_gap 0.0508)
		)
		(pad "7" thru_hole circle
			(at 0 5.999988 90)
			(size 1.3716 1.3716)
			(drill 0.9652)
			(layers "*.Cu" "*.Mask")
			(remove_unused_layers no)
			(net "SMB_FAN5_SDA_R")
			(clearance 0.0508)
			(thermal_gap 0.0508)
		)
		(pad "8" thru_hole circle
			(at -1.999996 5.999988 90)
			(size 1.3716 1.3716)
			(drill 0.9652)
			(layers "*.Cu" "*.Mask")
			(remove_unused_layers no)
			(net "GND")
			(clearance 0.0508)
			(thermal_gap 0.0508)
		)
		(pad "9" thru_hole circle
			(at 0 7.999984 90)
			(size 1.3716 1.3716)
			(drill 0.9652)
			(layers "*.Cu" "*.Mask")
			(remove_unused_layers no)
			(net "GND")
			(clearance 0.0508)
			(thermal_gap 0.0508)
		)
		(pad "10" thru_hole circle
			(at -1.999996 7.999984 90)
			(size 1.3716 1.3716)
			(drill 0.9652)
			(layers "*.Cu" "*.Mask")
			(remove_unused_layers no)
			(net "P52V_FAN_5")
			(clearance 0.0508)
			(thermal_gap 0.0508)
		)
		(pad "11" thru_hole circle
			(at 0 9.99998 90)
			(size 1.3716 1.3716)
			(drill 0.9652)
			(layers "*.Cu" "*.Mask")
			(remove_unused_layers no)
			(net "P52V_FAN_5")
			(clearance 0.0508)
			(thermal_gap 0.0508)
		)
		(pad "12" thru_hole circle
			(at -1.999996 9.99998 90)
			(size 1.3716 1.3716)
			(drill 0.9652)
			(layers "*.Cu" "*.Mask")
			(remove_unused_layers no)
			(net "FAN_5_FAIL_R_LED_N")
			(clearance 0.0508)
			(thermal_gap 0.0508)
		)
		(pad "13" thru_hole circle
			(at 0 11.999976 90)
			(size 1.3716 1.3716)
			(drill 0.9652)
			(layers "*.Cu" "*.Mask")
			(remove_unused_layers no)
			(net "FAN_5_TACH_OL_D")
			(clearance 0.0508)
			(thermal_gap 0.0508)
		)
		(pad "14" thru_hole circle
			(at -1.999996 11.999976 90)
			(size 1.3716 1.3716)
			(drill 0.9652)
			(layers "*.Cu" "*.Mask")
			(remove_unused_layers no)
			(net "FAN_5_OK_R_LED_N")
			(clearance 0.0508)
			(thermal_gap 0.0508)
		)
		(pad "15" thru_hole circle
			(at 0 13.999972 90)
			(size 1.3716 1.3716)
			(drill 0.9652)
			(layers "*.Cu" "*.Mask")
			(remove_unused_layers no)
			(net "Net_603")
			(clearance 0.0508)
			(thermal_gap 0.0508)
		)
		(pad "16" thru_hole circle
			(at -1.999996 13.999972 90)
			(size 1.3716 1.3716)
			(drill 0.9652)
			(layers "*.Cu" "*.Mask")
			(remove_unused_layers no)
			(net "Net_602")
			(clearance 0.0508)
			(thermal_gap 0.0508)
		)
		(zone
			(layers "F.Cu" "B.Cu" "In1.Cu" "In2.Cu" "In3.Cu" "In4.Cu")
			(hatch none 0.5)
			(connect_pads
				(clearance 0)
			)
			(min_thickness 0.25)
			(keepout
				(tracks not_allowed)
				(vias allowed)
				(pads allowed)
				(copperpour not_allowed)
				(footprints allowed)
			)
			(placement
				(enabled no)
				(sheetname "")
			)
			(fill
				(thermal_gap 0.5)
				(thermal_bridge_width 0.5)
				(island_removal_mode 0)
			)
			(polygon
				(pts
					(arc
						(start 8.95731 -102.810056)
						(mid 6.44271 -102.810056)
						(end 8.95731 -102.810056)
					)
				)
			)
		)
	)
	(footprint ""
		(layer "B.Cu")
		(at 10.699242 -258.562856 90)
		(property "Reference" "PR76"
			(at 0 0 90)
			(layer "B.SilkS")
			(hide yes)
			(effects
				(font
					(size 1.27 1.27)
				)
				(justify mirror)
			)
		)
		(property "Value" ""
			(at 0 0 90)
			(layer "B.Fab")
			(effects
				(font
					(size 1.27 1.27)
				)
				(justify mirror)
			)
		)
		(duplicate_pad_numbers_are_jumpers no)
		(fp_line
			(start 0.7874 -0.4064)
			(end -0.7874 -0.4064)
			(stroke
				(width 0.1524)
				(type default)
			)
			(layer "B.SilkS")
		)
		(fp_line
			(start -0.7874 -0.4064)
			(end -0.7874 0.4064)
			(stroke
				(width 0.1524)
				(type default)
			)
			(layer "B.SilkS")
		)
		(fp_line
			(start 0.7874 0.4064)
			(end 0.7874 -0.4064)
			(stroke
				(width 0.1524)
				(type default)
			)
			(layer "B.SilkS")
		)
		(fp_line
			(start -0.7874 0.4064)
			(end 0.7874 0.4064)
			(stroke
				(width 0.1524)
				(type default)
			)
			(layer "B.SilkS")
		)
		(fp_line
			(start 0.67945 -0.305054)
			(end 0.12065 -0.305054)
			(stroke
				(width 0.1)
				(type default)
			)
			(layer "B.Fab")
		)
		(fp_line
			(start 0.12065 -0.305054)
			(end 0.12065 -0.2794)
			(stroke
				(width 0.1)
				(type default)
			)
			(layer "B.Fab")
		)
		(fp_line
			(start -0.12065 -0.3048)
			(end -0.67945 -0.3048)
			(stroke
				(width 0.1)
				(type default)
			)
			(layer "B.Fab")
		)
		(fp_line
			(start -0.67945 -0.3048)
			(end -0.67945 0.3048)
			(stroke
				(width 0.1)
				(type default)
			)
			(layer "B.Fab")
		)
		(fp_line
			(start 0.12065 -0.2794)
			(end -0.12065 -0.2794)
			(stroke
				(width 0.1)
				(type default)
			)
			(layer "B.Fab")
		)
		(fp_line
			(start -0.12065 -0.2794)
			(end -0.12065 -0.3048)
			(stroke
				(width 0.1)
				(type default)
			)
			(layer "B.Fab")
		)
		(fp_line
			(start 0.12065 0.2794)
			(end 0.12065 0.3048)
			(stroke
				(width 0.1)
				(type default)
			)
			(layer "B.Fab")
		)
		(fp_line
			(start -0.120396 0.2794)
			(end 0.12065 0.2794)
			(stroke
				(width 0.1)
				(type default)
			)
			(layer "B.Fab")
		)
		(fp_line
			(start 0.67945 0.3048)
			(end 0.67945 -0.305054)
			(stroke
				(width 0.1)
				(type default)
			)
			(layer "B.Fab")
		)
		(fp_line
			(start 0.12065 0.3048)
			(end 0.67945 0.3048)
			(stroke
				(width 0.1)
				(type default)
			)
			(layer "B.Fab")
		)
		(fp_line
			(start -0.120396 0.3048)
			(end -0.120396 0.2794)
			(stroke
				(width 0.1)
				(type default)
			)
			(layer "B.Fab")
		)
		(fp_line
			(start -0.67945 0.3048)
			(end -0.120396 0.3048)
			(stroke
				(width 0.1)
				(type default)
			)
			(layer "B.Fab")
		)
		(pad "1" smd circle
			(at 0.40005 0 270)
			(size 0 0)
			(layers "B.Cu" "B.Mask" "B.Paste")
			(net "FAN_7_TEMP")
		)
		(pad "2" smd circle
			(at -0.40005 0 270)
			(size 0 0)
			(layers "B.Cu" "B.Mask" "B.Paste")
			(net "GND")
		)
	)
	(footprint ""
		(layer "B.Cu")
		(at 16.2052 -90.989912 180)
		(property "Reference" "C2112"
			(at 0 0 0)
			(layer "B.SilkS")
			(hide yes)
			(effects
				(font
					(size 1.27 1.27)
				)
				(justify mirror)
			)
		)
		(property "Value" ""
			(at 0 0 0)
			(layer "B.Fab")
			(effects
				(font
					(size 1.27 1.27)
				)
				(justify mirror)
			)
		)
		(duplicate_pad_numbers_are_jumpers no)
		(fp_line
			(start 2.2098 0.9398)
			(end 2.2098 -0.9398)
			(stroke
				(width 0.1524)
				(type default)
			)
			(layer "B.SilkS")
		)
		(fp_line
			(start 2.2098 -0.9398)
			(end -2.2098 -0.9398)
			(stroke
				(width 0.1524)
				(type default)
			)
			(layer "B.SilkS")
		)
		(fp_line
			(start -2.2098 0.9398)
			(end 2.2098 0.9398)
			(stroke
				(width 0.1524)
				(type default)
			)
			(layer "B.SilkS")
		)
		(fp_line
			(start -2.2098 -0.9398)
			(end -2.2098 0.9398)
			(stroke
				(width 0.1524)
				(type default)
			)
			(layer "B.SilkS")
		)
		(fp_line
			(start 1.700022 0.899922)
			(end 1.700022 -0.899922)
			(stroke
				(width 0.1)
				(type default)
			)
			(layer "B.Fab")
		)
		(fp_line
			(start 1.700022 -0.899922)
			(end -1.700022 -0.899922)
			(stroke
				(width 0.1)
				(type default)
			)
			(layer "B.Fab")
		)
		(fp_line
			(start -1.700022 0.899922)
			(end 1.700022 0.899922)
			(stroke
				(width 0.1)
				(type default)
			)
			(layer "B.Fab")
		)
		(fp_line
			(start -1.700022 -0.899922)
			(end -1.700022 0.899922)
			(stroke
				(width 0.1)
				(type default)
			)
			(layer "B.Fab")
		)
		(pad "1" smd rect
			(at 1.4732 0 180)
			(size 1.1684 1.5748)
			(layers "B.Cu" "B.Mask" "B.Paste")
			(net "P52V_FAN_5")
		)
		(pad "2" smd rect
			(at -1.4732 0 180)
			(size 1.1684 1.5748)
			(layers "B.Cu" "B.Mask" "B.Paste")
			(net "GND")
		)
	)
	(footprint ""
		(layer "B.Cu")
		(at 9.779 -249.428 -90)
		(property "Reference" "PR68"
			(at 0 0 90)
			(layer "B.SilkS")
			(hide yes)
			(effects
				(font
					(size 1.27 1.27)
				)
				(justify mirror)
			)
		)
		(property "Value" ""
			(at 0 0 90)
			(layer "B.Fab")
			(effects
				(font
					(size 1.27 1.27)
				)
				(justify mirror)
			)
		)
		(duplicate_pad_numbers_are_jumpers no)
		(fp_line
			(start -0.7874 0.4064)
			(end 0.7874 0.4064)
			(stroke
				(width 0.1524)
				(type default)
			)
			(layer "B.SilkS")
		)
		(fp_line
			(start 0.7874 0.4064)
			(end 0.7874 -0.4064)
			(stroke
				(width 0.1524)
				(type default)
			)
			(layer "B.SilkS")
		)
		(fp_line
			(start -0.7874 -0.4064)
			(end -0.7874 0.4064)
			(stroke
				(width 0.1524)
				(type default)
			)
			(layer "B.SilkS")
		)
		(fp_line
			(start 0.7874 -0.4064)
			(end -0.7874 -0.4064)
			(stroke
				(width 0.1524)
				(type default)
			)
			(layer "B.SilkS")
		)
		(fp_line
			(start -0.67945 0.3048)
			(end -0.120396 0.3048)
			(stroke
				(width 0.1)
				(type default)
			)
			(layer "B.Fab")
		)
		(fp_line
			(start -0.120396 0.3048)
			(end -0.120396 0.2794)
			(stroke
				(width 0.1)
				(type default)
			)
			(layer "B.Fab")
		)
		(fp_line
			(start 0.12065 0.3048)
			(end 0.67945 0.3048)
			(stroke
				(width 0.1)
				(type default)
			)
			(layer "B.Fab")
		)
		(fp_line
			(start 0.67945 0.3048)
			(end 0.67945 -0.305054)
			(stroke
				(width 0.1)
				(type default)
			)
			(layer "B.Fab")
		)
		(fp_line
			(start -0.120396 0.2794)
			(end 0.12065 0.2794)
			(stroke
				(width 0.1)
				(type default)
			)
			(layer "B.Fab")
		)
		(fp_line
			(start 0.12065 0.2794)
			(end 0.12065 0.3048)
			(stroke
				(width 0.1)
				(type default)
			)
			(layer "B.Fab")
		)
		(fp_line
			(start -0.12065 -0.2794)
			(end -0.12065 -0.3048)
			(stroke
				(width 0.1)
				(type default)
			)
			(layer "B.Fab")
		)
		(fp_line
			(start 0.12065 -0.2794)
			(end -0.12065 -0.2794)
			(stroke
				(width 0.1)
				(type default)
			)
			(layer "B.Fab")
		)
		(fp_line
			(start -0.67945 -0.3048)
			(end -0.67945 0.3048)
			(stroke
				(width 0.1)
				(type default)
			)
			(layer "B.Fab")
		)
		(fp_line
			(start -0.12065 -0.3048)
			(end -0.67945 -0.3048)
			(stroke
				(width 0.1)
				(type default)
			)
			(layer "B.Fab")
		)
		(fp_line
			(start 0.12065 -0.305054)
			(end 0.12065 -0.2794)
			(stroke
				(width 0.1)
				(type default)
			)
			(layer "B.Fab")
		)
		(fp_line
			(start 0.67945 -0.305054)
			(end 0.12065 -0.305054)
			(stroke
				(width 0.1)
				(type default)
			)
			(layer "B.Fab")
		)
		(pad "1" smd circle
			(at 0.40005 0 90)
			(size 0 0)
			(layers "B.Cu" "B.Mask" "B.Paste")
			(net "FAN_6_TEMP")
		)
		(pad "2" smd circle
			(at -0.40005 0 90)
			(size 0 0)
			(layers "B.Cu" "B.Mask" "B.Paste")
			(net "GND")
		)
	)
	(footprint ""
		(layer "B.Cu")
		(at 3.81 -252.73 90)
		(property "Reference" "U397"
			(at 2.00533 2.54 0)
			(unlocked yes)
			(layer "B.SilkS")
			(effects
				(font
					(size 0.7874 0.5842)
					(thickness 0.1524)
				)
				(justify left mirror)
			)
		)
		(property "Value" ""
			(at 0 0 90)
			(layer "B.Fab")
			(effects
				(font
					(size 1.27 1.27)
				)
				(justify mirror)
			)
		)
		(duplicate_pad_numbers_are_jumpers no)
		(fp_line
			(start 1.3462 -1.1938)
			(end 1.3462 1.1684)
			(stroke
				(width 0.1524)
				(type default)
			)
			(layer "B.SilkS")
		)
		(fp_line
			(start -1.3462 -1.1938)
			(end 1.3462 -1.1938)
			(stroke
				(width 0.1524)
				(type default)
			)
			(layer "B.SilkS")
		)
		(fp_line
			(start 1.3462 1.1938)
			(end -1.3462 1.1938)
			(stroke
				(width 0.1524)
				(type default)
			)
			(layer "B.SilkS")
		)
		(fp_line
			(start -1.3462 1.1938)
			(end -1.3462 -1.1938)
			(stroke
				(width 0.1524)
				(type default)
			)
			(layer "B.SilkS")
		)
		(fp_poly
			(pts
				(xy 1.418082 -1.288796) (xy 2.059686 -1.502918) (xy 1.63195 -1.930654)
			)
			(stroke
				(width 0)
				(type default)
			)
			(fill yes)
			(layer "B.SilkS")
		)
		(fp_line
			(start 0.674878 -1.124966)
			(end 0.674878 1.124966)
			(stroke
				(width 0.1)
				(type default)
			)
			(layer "B.Fab")
		)
		(fp_line
			(start -0.674878 -1.124966)
			(end 0.674878 -1.124966)
			(stroke
				(width 0.1)
				(type default)
			)
			(layer "B.Fab")
		)
		(fp_line
			(start 0.674878 1.124966)
			(end -0.674878 1.124966)
			(stroke
				(width 0.1)
				(type default)
			)
			(layer "B.Fab")
		)
		(fp_line
			(start -0.674878 1.124966)
			(end -0.674878 -1.124966)
			(stroke
				(width 0.1)
				(type default)
			)
			(layer "B.Fab")
		)
		(fp_poly
			(pts
				(xy 1.447038 -0.760476) (xy 2.052066 -0.457962) (xy 2.052066 -1.06299)
			)
			(stroke
				(width 0)
				(type default)
			)
			(fill yes)
			(layer "B.Fab")
		)
		(pad "1" smd rect
			(at 0.899922 -0.750062 270)
			(size 0.6096 0.6096)
			(layers "B.Cu" "B.Mask" "B.Paste")
			(net "NC_U397_P1")
		)
		(pad "2" smd rect
			(at 0.899922 0 180)
			(size 0.4064 0.6096)
			(layers "B.Cu" "B.Mask" "B.Paste")
			(net "FAN_6_PRSNT_BUF_N")
		)
		(pad "3" smd rect
			(at 0.899922 0.750062 270)
			(size 0.6096 0.6096)
			(layers "B.Cu" "B.Mask" "B.Paste")
			(net "GND")
		)
		(pad "4" smd rect
			(at -0.899922 0.750062 270)
			(size 0.6096 0.6096)
			(layers "B.Cu" "B.Mask" "B.Paste")
			(net "FAN_6_PRESENT")
		)
		(pad "5" smd rect
			(at -0.899922 -0.750062 270)
			(size 0.6096 0.6096)
			(layers "B.Cu" "B.Mask" "B.Paste")
			(net "P3V3_AUX")
		)
	)
	(footprint ""
		(layer "B.Cu")
		(at 18.430494 -258.572 -90)
		(property "Reference" "PR78"
			(at 0 0 90)
			(layer "B.SilkS")
			(hide yes)
			(effects
				(font
					(size 1.27 1.27)
				)
				(justify mirror)
			)
		)
		(property "Value" ""
			(at 0 0 90)
			(layer "B.Fab")
			(effects
				(font
					(size 1.27 1.27)
				)
				(justify mirror)
			)
		)
		(duplicate_pad_numbers_are_jumpers no)
		(fp_line
			(start -0.7874 0.4064)
			(end 0.7874 0.4064)
			(stroke
				(width 0.1524)
				(type default)
			)
			(layer "B.SilkS")
		)
		(fp_line
			(start 0.7874 0.4064)
			(end 0.7874 -0.4064)
			(stroke
				(width 0.1524)
				(type default)
			)
			(layer "B.SilkS")
		)
		(fp_line
			(start -0.7874 -0.4064)
			(end -0.7874 0.4064)
			(stroke
				(width 0.1524)
				(type default)
			)
			(layer "B.SilkS")
		)
		(fp_line
			(start 0.7874 -0.4064)
			(end -0.7874 -0.4064)
			(stroke
				(width 0.1524)
				(type default)
			)
			(layer "B.SilkS")
		)
		(fp_line
			(start -0.67945 0.3048)
			(end -0.120396 0.3048)
			(stroke
				(width 0.1)
				(type default)
			)
			(layer "B.Fab")
		)
		(fp_line
			(start -0.120396 0.3048)
			(end -0.120396 0.2794)
			(stroke
				(width 0.1)
				(type default)
			)
			(layer "B.Fab")
		)
		(fp_line
			(start 0.12065 0.3048)
			(end 0.67945 0.3048)
			(stroke
				(width 0.1)
				(type default)
			)
			(layer "B.Fab")
		)
		(fp_line
			(start 0.67945 0.3048)
			(end 0.67945 -0.305054)
			(stroke
				(width 0.1)
				(type default)
			)
			(layer "B.Fab")
		)
		(fp_line
			(start -0.120396 0.2794)
			(end 0.12065 0.2794)
			(stroke
				(width 0.1)
				(type default)
			)
			(layer "B.Fab")
		)
		(fp_line
			(start 0.12065 0.2794)
			(end 0.12065 0.3048)
			(stroke
				(width 0.1)
				(type default)
			)
			(layer "B.Fab")
		)
		(fp_line
			(start -0.12065 -0.2794)
			(end -0.12065 -0.3048)
			(stroke
				(width 0.1)
				(type default)
			)
			(layer "B.Fab")
		)
		(fp_line
			(start 0.12065 -0.2794)
			(end -0.12065 -0.2794)
			(stroke
				(width 0.1)
				(type default)
			)
			(layer "B.Fab")
		)
		(fp_line
			(start -0.67945 -0.3048)
			(end -0.67945 0.3048)
			(stroke
				(width 0.1)
				(type default)
			)
			(layer "B.Fab")
		)
		(fp_line
			(start -0.12065 -0.3048)
			(end -0.67945 -0.3048)
			(stroke
				(width 0.1)
				(type default)
			)
			(layer "B.Fab")
		)
		(fp_line
			(start 0.12065 -0.305054)
			(end 0.12065 -0.2794)
			(stroke
				(width 0.1)
				(type default)
			)
			(layer "B.Fab")
		)
		(fp_line
			(start 0.67945 -0.305054)
			(end 0.12065 -0.305054)
			(stroke
				(width 0.1)
				(type default)
			)
			(layer "B.Fab")
		)
		(pad "1" smd circle
			(at 0.40005 0 90)
			(size 0 0)
			(layers "B.Cu" "B.Mask" "B.Paste")
			(net "GND")
		)
		(pad "2" smd circle
			(at -0.40005 0 90)
			(size 0 0)
			(layers "B.Cu" "B.Mask" "B.Paste")
			(net "FAN_7_IMON")
		)
	)
	(footprint ""
		(layer "B.Cu")
		(at 17.653 -130.81 180)
		(property "Reference" "R5438"
			(at 0 0 0)
			(layer "B.SilkS")
			(hide yes)
			(effects
				(font
					(size 1.27 1.27)
				)
				(justify mirror)
			)
		)
		(property "Value" ""
			(at 0 0 0)
			(layer "B.Fab")
			(effects
				(font
					(size 1.27 1.27)
				)
				(justify mirror)
			)
		)
		(duplicate_pad_numbers_are_jumpers no)
		(fp_line
			(start 0.7874 0.4064)
			(end 0.7874 -0.4064)
			(stroke
				(width 0.1524)
				(type default)
			)
			(layer "B.SilkS")
		)
		(fp_line
			(start 0.7874 -0.4064)
			(end -0.7874 -0.4064)
			(stroke
				(width 0.1524)
				(type default)
			)
			(layer "B.SilkS")
		)
		(fp_line
			(start -0.7874 0.4064)
			(end 0.7874 0.4064)
			(stroke
				(width 0.1524)
				(type default)
			)
			(layer "B.SilkS")
		)
		(fp_line
			(start -0.7874 -0.4064)
			(end -0.7874 0.4064)
			(stroke
				(width 0.1524)
				(type default)
			)
			(layer "B.SilkS")
		)
		(fp_line
			(start 0.67945 0.3048)
			(end 0.67945 -0.305054)
			(stroke
				(width 0.1)
				(type default)
			)
			(layer "B.Fab")
		)
		(fp_line
			(start 0.67945 -0.305054)
			(end 0.12065 -0.305054)
			(stroke
				(width 0.1)
				(type default)
			)
			(layer "B.Fab")
		)
		(fp_line
			(start 0.12065 0.3048)
			(end 0.67945 0.3048)
			(stroke
				(width 0.1)
				(type default)
			)
			(layer "B.Fab")
		)
		(fp_line
			(start 0.12065 0.2794)
			(end 0.12065 0.3048)
			(stroke
				(width 0.1)
				(type default)
			)
			(layer "B.Fab")
		)
		(fp_line
			(start 0.12065 -0.2794)
			(end -0.12065 -0.2794)
			(stroke
				(width 0.1)
				(type default)
			)
			(layer "B.Fab")
		)
		(fp_line
			(start 0.12065 -0.305054)
			(end 0.12065 -0.2794)
			(stroke
				(width 0.1)
				(type default)
			)
			(layer "B.Fab")
		)
		(fp_line
			(start -0.120396 0.3048)
			(end -0.120396 0.2794)
			(stroke
				(width 0.1)
				(type default)
			)
			(layer "B.Fab")
		)
		(fp_line
			(start -0.120396 0.2794)
			(end 0.12065 0.2794)
			(stroke
				(width 0.1)
				(type default)
			)
			(layer "B.Fab")
		)
		(fp_line
			(start -0.12065 -0.2794)
			(end -0.12065 -0.3048)
			(stroke
				(width 0.1)
				(type default)
			)
			(layer "B.Fab")
		)
		(fp_line
			(start -0.12065 -0.3048)
			(end -0.67945 -0.3048)
			(stroke
				(width 0.1)
				(type default)
			)
			(layer "B.Fab")
		)
		(fp_line
			(start -0.67945 0.3048)
			(end -0.120396 0.3048)
			(stroke
				(width 0.1)
				(type default)
			)
			(layer "B.Fab")
		)
		(fp_line
			(start -0.67945 -0.3048)
			(end -0.67945 0.3048)
			(stroke
				(width 0.1)
				(type default)
			)
			(layer "B.Fab")
		)
		(pad "1" smd rect
			(at 0.40005 0 180)
			(size 0.4572 0.508)
			(layers "B.Cu" "B.Mask" "B.Paste")
			(net "FAN_6_TACH_IL")
		)
		(pad "2" smd rect
			(at -0.40005 0 180)
			(size 0.4572 0.508)
			(layers "B.Cu" "B.Mask" "B.Paste")
			(net "GND")
		)
	)
	(footprint ""
		(layer "B.Cu")
		(at 19.446494 -258.572 90)
		(property "Reference" "PR74"
			(at 0 0 90)
			(layer "B.SilkS")
			(hide yes)
			(effects
				(font
					(size 1.27 1.27)
				)
				(justify mirror)
			)
		)
		(property "Value" ""
			(at 0 0 90)
			(layer "B.Fab")
			(effects
				(font
					(size 1.27 1.27)
				)
				(justify mirror)
			)
		)
		(duplicate_pad_numbers_are_jumpers no)
		(fp_line
			(start 0.7874 -0.4064)
			(end -0.7874 -0.4064)
			(stroke
				(width 0.1524)
				(type default)
			)
			(layer "B.SilkS")
		)
		(fp_line
			(start -0.7874 -0.4064)
			(end -0.7874 0.4064)
			(stroke
				(width 0.1524)
				(type default)
			)
			(layer "B.SilkS")
		)
		(fp_line
			(start 0.7874 0.4064)
			(end 0.7874 -0.4064)
			(stroke
				(width 0.1524)
				(type default)
			)
			(layer "B.SilkS")
		)
		(fp_line
			(start -0.7874 0.4064)
			(end 0.7874 0.4064)
			(stroke
				(width 0.1524)
				(type default)
			)
			(layer "B.SilkS")
		)
		(fp_line
			(start 0.67945 -0.305054)
			(end 0.12065 -0.305054)
			(stroke
				(width 0.1)
				(type default)
			)
			(layer "B.Fab")
		)
		(fp_line
			(start 0.12065 -0.305054)
			(end 0.12065 -0.2794)
			(stroke
				(width 0.1)
				(type default)
			)
			(layer "B.Fab")
		)
		(fp_line
			(start -0.12065 -0.3048)
			(end -0.67945 -0.3048)
			(stroke
				(width 0.1)
				(type default)
			)
			(layer "B.Fab")
		)
		(fp_line
			(start -0.67945 -0.3048)
			(end -0.67945 0.3048)
			(stroke
				(width 0.1)
				(type default)
			)
			(layer "B.Fab")
		)
		(fp_line
			(start 0.12065 -0.2794)
			(end -0.12065 -0.2794)
			(stroke
				(width 0.1)
				(type default)
			)
			(layer "B.Fab")
		)
		(fp_line
			(start -0.12065 -0.2794)
			(end -0.12065 -0.3048)
			(stroke
				(width 0.1)
				(type default)
			)
			(layer "B.Fab")
		)
		(fp_line
			(start 0.12065 0.2794)
			(end 0.12065 0.3048)
			(stroke
				(width 0.1)
				(type default)
			)
			(layer "B.Fab")
		)
		(fp_line
			(start -0.120396 0.2794)
			(end 0.12065 0.2794)
			(stroke
				(width 0.1)
				(type default)
			)
			(layer "B.Fab")
		)
		(fp_line
			(start 0.67945 0.3048)
			(end 0.67945 -0.305054)
			(stroke
				(width 0.1)
				(type default)
			)
			(layer "B.Fab")
		)
		(fp_line
			(start 0.12065 0.3048)
			(end 0.67945 0.3048)
			(stroke
				(width 0.1)
				(type default)
			)
			(layer "B.Fab")
		)
		(fp_line
			(start -0.120396 0.3048)
			(end -0.120396 0.2794)
			(stroke
				(width 0.1)
				(type default)
			)
			(layer "B.Fab")
		)
		(fp_line
			(start -0.67945 0.3048)
			(end -0.120396 0.3048)
			(stroke
				(width 0.1)
				(type default)
			)
			(layer "B.Fab")
		)
		(pad "1" smd circle
			(at 0.40005 0 270)
			(size 0 0)
			(layers "B.Cu" "B.Mask" "B.Paste")
			(net "FAN_7_CS")
		)
		(pad "2" smd circle
			(at -0.40005 0 270)
			(size 0 0)
			(layers "B.Cu" "B.Mask" "B.Paste")
			(net "GND")
		)
	)
	(footprint ""
		(layer "B.Cu")
		(at 33.4518 -273.7104)
		(property "Reference" "C2097"
			(at 0 0 0)
			(layer "B.SilkS")
			(hide yes)
			(effects
				(font
					(size 1.27 1.27)
				)
				(justify mirror)
			)
		)
		(property "Value" ""
			(at 0 0 0)
			(layer "B.Fab")
			(effects
				(font
					(size 1.27 1.27)
				)
				(justify mirror)
			)
		)
		(duplicate_pad_numbers_are_jumpers no)
		(fp_line
			(start -2.2098 -0.9398)
			(end -2.2098 0.9398)
			(stroke
				(width 0.1524)
				(type default)
			)
			(layer "B.SilkS")
		)
		(fp_line
			(start -2.2098 0.9398)
			(end 2.2098 0.9398)
			(stroke
				(width 0.1524)
				(type default)
			)
			(layer "B.SilkS")
		)
		(fp_line
			(start 2.2098 -0.9398)
			(end -2.2098 -0.9398)
			(stroke
				(width 0.1524)
				(type default)
			)
			(layer "B.SilkS")
		)
		(fp_line
			(start 2.2098 0.9398)
			(end 2.2098 -0.9398)
			(stroke
				(width 0.1524)
				(type default)
			)
			(layer "B.SilkS")
		)
		(fp_line
			(start -1.700022 -0.899922)
			(end -1.700022 0.899922)
			(stroke
				(width 0.1)
				(type default)
			)
			(layer "B.Fab")
		)
		(fp_line
			(start -1.700022 0.899922)
			(end 1.700022 0.899922)
			(stroke
				(width 0.1)
				(type default)
			)
			(layer "B.Fab")
		)
		(fp_line
			(start 1.700022 -0.899922)
			(end -1.700022 -0.899922)
			(stroke
				(width 0.1)
				(type default)
			)
			(layer "B.Fab")
		)
		(fp_line
			(start 1.700022 0.899922)
			(end 1.700022 -0.899922)
			(stroke
				(width 0.1)
				(type default)
			)
			(layer "B.Fab")
		)
		(pad "1" smd rect
			(at 1.4732 0)
			(size 1.1684 1.5748)
			(layers "B.Cu" "B.Mask" "B.Paste")
			(net "P52V_FAN_0")
		)
		(pad "2" smd rect
			(at -1.4732 0)
			(size 1.1684 1.5748)
			(layers "B.Cu" "B.Mask" "B.Paste")
			(net "GND")
		)
	)
	(footprint ""
		(layer "B.Cu")
		(at 41.25468 -64.837056 -90)
		(property "Reference" "PR44"
			(at 0 0 90)
			(layer "B.SilkS")
			(hide yes)
			(effects
				(font
					(size 1.27 1.27)
				)
				(justify mirror)
			)
		)
		(property "Value" ""
			(at 0 0 90)
			(layer "B.Fab")
			(effects
				(font
					(size 1.27 1.27)
				)
				(justify mirror)
			)
		)
		(duplicate_pad_numbers_are_jumpers no)
		(fp_line
			(start -0.7874 0.4064)
			(end 0.7874 0.4064)
			(stroke
				(width 0.1524)
				(type default)
			)
			(layer "B.SilkS")
		)
		(fp_line
			(start 0.7874 0.4064)
			(end 0.7874 -0.4064)
			(stroke
				(width 0.1524)
				(type default)
			)
			(layer "B.SilkS")
		)
		(fp_line
			(start -0.7874 -0.4064)
			(end -0.7874 0.4064)
			(stroke
				(width 0.1524)
				(type default)
			)
			(layer "B.SilkS")
		)
		(fp_line
			(start 0.7874 -0.4064)
			(end -0.7874 -0.4064)
			(stroke
				(width 0.1524)
				(type default)
			)
			(layer "B.SilkS")
		)
		(fp_line
			(start -0.67945 0.3048)
			(end -0.120396 0.3048)
			(stroke
				(width 0.1)
				(type default)
			)
			(layer "B.Fab")
		)
		(fp_line
			(start -0.120396 0.3048)
			(end -0.120396 0.2794)
			(stroke
				(width 0.1)
				(type default)
			)
			(layer "B.Fab")
		)
		(fp_line
			(start 0.12065 0.3048)
			(end 0.67945 0.3048)
			(stroke
				(width 0.1)
				(type default)
			)
			(layer "B.Fab")
		)
		(fp_line
			(start 0.67945 0.3048)
			(end 0.67945 -0.305054)
			(stroke
				(width 0.1)
				(type default)
			)
			(layer "B.Fab")
		)
		(fp_line
			(start -0.120396 0.2794)
			(end 0.12065 0.2794)
			(stroke
				(width 0.1)
				(type default)
			)
			(layer "B.Fab")
		)
		(fp_line
			(start 0.12065 0.2794)
			(end 0.12065 0.3048)
			(stroke
				(width 0.1)
				(type default)
			)
			(layer "B.Fab")
		)
		(fp_line
			(start -0.12065 -0.2794)
			(end -0.12065 -0.3048)
			(stroke
				(width 0.1)
				(type default)
			)
			(layer "B.Fab")
		)
		(fp_line
			(start 0.12065 -0.2794)
			(end -0.12065 -0.2794)
			(stroke
				(width 0.1)
				(type default)
			)
			(layer "B.Fab")
		)
		(fp_line
			(start -0.67945 -0.3048)
			(end -0.67945 0.3048)
			(stroke
				(width 0.1)
				(type default)
			)
			(layer "B.Fab")
		)
		(fp_line
			(start -0.12065 -0.3048)
			(end -0.67945 -0.3048)
			(stroke
				(width 0.1)
				(type default)
			)
			(layer "B.Fab")
		)
		(fp_line
			(start 0.12065 -0.305054)
			(end 0.12065 -0.2794)
			(stroke
				(width 0.1)
				(type default)
			)
			(layer "B.Fab")
		)
		(fp_line
			(start 0.67945 -0.305054)
			(end 0.12065 -0.305054)
			(stroke
				(width 0.1)
				(type default)
			)
			(layer "B.Fab")
		)
		(pad "1" smd circle
			(at 0.40005 0 90)
			(size 0 0)
			(layers "B.Cu" "B.Mask" "B.Paste")
			(net "FAN_3_TEMP")
		)
		(pad "2" smd circle
			(at -0.40005 0 90)
			(size 0 0)
			(layers "B.Cu" "B.Mask" "B.Paste")
			(net "GND")
		)
	)
	(footprint ""
		(layer "B.Cu")
		(at 44.99991 -26.409904)
		(property "Reference" "J4"
			(at 4.384802 -5.317744 0)
			(unlocked yes)
			(layer "B.SilkS")
			(effects
				(font
					(size 0.7874 0.5842)
					(thickness 0.1524)
				)
				(justify left mirror)
			)
		)
		(property "Value" ""
			(at 0 0 0)
			(layer "B.Fab")
			(effects
				(font
					(size 1.27 1.27)
				)
				(justify mirror)
			)
		)
		(duplicate_pad_numbers_are_jumpers no)
		(fp_line
			(start -6.35 -4.52501)
			(end 4.350004 -4.52501)
			(stroke
				(width 0.1524)
				(type default)
			)
			(layer "B.SilkS")
		)
		(fp_line
			(start -6.35 18.524982)
			(end -6.35 -4.52501)
			(stroke
				(width 0.1524)
				(type default)
			)
			(layer "B.SilkS")
		)
		(fp_line
			(start -3.24993 -1.42494)
			(end -1.96977 -1.42494)
			(stroke
				(width 0.1524)
				(type default)
			)
			(layer "B.SilkS")
		)
		(fp_line
			(start -3.24993 15.424912)
			(end -3.24993 -1.42494)
			(stroke
				(width 0.1524)
				(type default)
			)
			(layer "B.SilkS")
		)
		(fp_line
			(start -0.029972 -1.42494)
			(end 1.249934 -1.42494)
			(stroke
				(width 0.1524)
				(type default)
			)
			(layer "B.SilkS")
		)
		(fp_line
			(start 1.249934 -1.42494)
			(end 1.249934 5.799836)
			(stroke
				(width 0.1524)
				(type default)
			)
			(layer "B.SilkS")
		)
		(fp_line
			(start 1.249934 5.799836)
			(end 4.350004 5.799836)
			(stroke
				(width 0.1524)
				(type default)
			)
			(layer "B.SilkS")
		)
		(fp_line
			(start 1.249934 8.200136)
			(end 1.249934 15.424912)
			(stroke
				(width 0.1524)
				(type default)
			)
			(layer "B.SilkS")
		)
		(fp_line
			(start 1.249934 8.200136)
			(end 4.350004 8.200136)
			(stroke
				(width 0.1524)
				(type default)
			)
			(layer "B.SilkS")
		)
		(fp_line
			(start 1.249934 15.424912)
			(end -3.24993 15.424912)
			(stroke
				(width 0.1524)
				(type default)
			)
			(layer "B.SilkS")
		)
		(fp_line
			(start 4.350004 -4.52501)
			(end 4.350004 18.524982)
			(stroke
				(width 0.1524)
				(type default)
			)
			(layer "B.SilkS")
		)
		(fp_line
			(start 4.350004 18.524982)
			(end -6.35 18.524982)
			(stroke
				(width 0.1524)
				(type default)
			)
			(layer "B.SilkS")
		)
		(fp_poly
			(pts
				(xy 5.527802 -0.508) (xy 5.527802 0.508) (xy 4.511802 0)
			)
			(stroke
				(width 0)
				(type default)
			)
			(fill yes)
			(layer "B.SilkS")
		)
		(fp_line
			(start -6.35 -4.52501)
			(end 4.350004 -4.52501)
			(stroke
				(width 0.1)
				(type default)
			)
			(layer "B.Fab")
		)
		(fp_line
			(start -6.35 18.524982)
			(end -6.35 -4.52501)
			(stroke
				(width 0.1)
				(type default)
			)
			(layer "B.Fab")
		)
		(fp_line
			(start 4.350004 -4.52501)
			(end 4.350004 18.524982)
			(stroke
				(width 0.1)
				(type default)
			)
			(layer "B.Fab")
		)
		(fp_line
			(start 4.350004 18.524982)
			(end -6.35 18.524982)
			(stroke
				(width 0.1)
				(type default)
			)
			(layer "B.Fab")
		)
		(fp_poly
			(pts
				(xy 5.527802 -0.508) (xy 5.527802 0.508) (xy 4.511802 0)
			)
			(stroke
				(width 0)
				(type default)
			)
			(fill yes)
			(layer "B.Fab")
		)
		(pad "" np_thru_hole circle
			(at -0.999998 -1.89992 270)
			(size 1.4986 1.4986)
			(drill 1.4986)
			(layers "*.Cu" "*.Mask")
			(clearance 0.381)
			(thermal_gap 0.381)
		)
		(pad "1" thru_hole rect
			(at 0 0 270)
			(size 1.3716 1.3716)
			(drill 0.9652)
			(layers "*.Cu" "*.Mask")
			(remove_unused_layers no)
			(net "FAN_3_TACH_IL_D")
			(clearance 0.0508)
			(padstack
				(mode front_inner_back)
				(layer "Inner"
					(shape circle)
					(size 1.3716 1.3716)
					(clearance 0.0508)
				)
				(layer "B.Cu"
					(shape rect)
					(size 1.3716 1.3716)
					(thermal_gap 0.0508)
					(clearance 0.0508)
				)
			)
		)
		(pad "2" thru_hole circle
			(at -1.999996 0 270)
			(size 1.3716 1.3716)
			(drill 0.9652)
			(layers "*.Cu" "*.Mask")
			(remove_unused_layers no)
			(net "FAN_3_PWM_OL_R")
			(clearance 0.0508)
			(thermal_gap 0.0508)
		)
		(pad "3" thru_hole circle
			(at 0 1.999996 270)
			(size 1.3716 1.3716)
			(drill 0.9652)
			(layers "*.Cu" "*.Mask")
			(remove_unused_layers no)
			(net "FAN_3_PWM_IL_R")
			(clearance 0.0508)
			(thermal_gap 0.0508)
		)
		(pad "4" thru_hole circle
			(at -1.999996 1.999996 270)
			(size 1.3716 1.3716)
			(drill 0.9652)
			(layers "*.Cu" "*.Mask")
			(remove_unused_layers no)
			(net "FAN_3_PRESENT_R_N")
			(clearance 0.0508)
			(thermal_gap 0.0508)
		)
		(pad "5" thru_hole circle
			(at 0 3.999992 270)
			(size 1.3716 1.3716)
			(drill 0.9652)
			(layers "*.Cu" "*.Mask")
			(remove_unused_layers no)
			(net "P12V_LED_R1_FAN3")
			(clearance 0.0508)
			(thermal_gap 0.0508)
		)
		(pad "6" thru_hole circle
			(at -1.999996 3.999992 270)
			(size 1.3716 1.3716)
			(drill 0.9652)
			(layers "*.Cu" "*.Mask")
			(remove_unused_layers no)
			(net "SMB_FAN3_SCL_R")
			(clearance 0.0508)
			(thermal_gap 0.0508)
		)
		(pad "7" thru_hole circle
			(at 0 5.999988 270)
			(size 1.3716 1.3716)
			(drill 0.9652)
			(layers "*.Cu" "*.Mask")
			(remove_unused_layers no)
			(net "SMB_FAN3_SDA_R")
			(clearance 0.0508)
			(thermal_gap 0.0508)
		)
		(pad "8" thru_hole circle
			(at -1.999996 5.999988 270)
			(size 1.3716 1.3716)
			(drill 0.9652)
			(layers "*.Cu" "*.Mask")
			(remove_unused_layers no)
			(net "GND")
			(clearance 0.0508)
			(thermal_gap 0.0508)
		)
		(pad "9" thru_hole circle
			(at 0 7.999984 270)
			(size 1.3716 1.3716)
			(drill 0.9652)
			(layers "*.Cu" "*.Mask")
			(remove_unused_layers no)
			(net "GND")
			(clearance 0.0508)
			(thermal_gap 0.0508)
		)
		(pad "10" thru_hole circle
			(at -1.999996 7.999984 270)
			(size 1.3716 1.3716)
			(drill 0.9652)
			(layers "*.Cu" "*.Mask")
			(remove_unused_layers no)
			(net "P52V_FAN_3")
			(clearance 0.0508)
			(thermal_gap 0.0508)
		)
		(pad "11" thru_hole circle
			(at 0 9.99998 270)
			(size 1.3716 1.3716)
			(drill 0.9652)
			(layers "*.Cu" "*.Mask")
			(remove_unused_layers no)
			(net "P52V_FAN_3")
			(clearance 0.0508)
			(thermal_gap 0.0508)
		)
		(pad "12" thru_hole circle
			(at -1.999996 9.99998 270)
			(size 1.3716 1.3716)
			(drill 0.9652)
			(layers "*.Cu" "*.Mask")
			(remove_unused_layers no)
			(net "FAN_3_FAIL_R_LED_N")
			(clearance 0.0508)
			(thermal_gap 0.0508)
		)
		(pad "13" thru_hole circle
			(at 0 11.999976 270)
			(size 1.3716 1.3716)
			(drill 0.9652)
			(layers "*.Cu" "*.Mask")
			(remove_unused_layers no)
			(net "FAN_3_TACH_OL_D")
			(clearance 0.0508)
			(thermal_gap 0.0508)
		)
		(pad "14" thru_hole circle
			(at -1.999996 11.999976 270)
			(size 1.3716 1.3716)
			(drill 0.9652)
			(layers "*.Cu" "*.Mask")
			(remove_unused_layers no)
			(net "FAN_3_OK_R_LED_N")
			(clearance 0.0508)
			(thermal_gap 0.0508)
		)
		(pad "15" thru_hole circle
			(at 0 13.999972 270)
			(size 1.3716 1.3716)
			(drill 0.9652)
			(layers "*.Cu" "*.Mask")
			(remove_unused_layers no)
			(net "Net_609")
			(clearance 0.0508)
			(thermal_gap 0.0508)
		)
		(pad "16" thru_hole circle
			(at -1.999996 13.999972 270)
			(size 1.3716 1.3716)
			(drill 0.9652)
			(layers "*.Cu" "*.Mask")
			(remove_unused_layers no)
			(net "Net_608")
			(clearance 0.0508)
			(thermal_gap 0.0508)
		)
		(zone
			(layers "F.Cu" "B.Cu" "In1.Cu" "In2.Cu" "In3.Cu" "In4.Cu")
			(hatch none 0.5)
			(connect_pads
				(clearance 0)
			)
			(min_thickness 0.25)
			(keepout
				(tracks not_allowed)
				(vias allowed)
				(pads allowed)
				(copperpour not_allowed)
				(footprints allowed)
			)
			(placement
				(enabled no)
				(sheetname "")
			)
			(fill
				(thermal_gap 0.5)
				(thermal_bridge_width 0.5)
				(island_removal_mode 0)
			)
			(polygon
				(pts
					(arc
						(start 45.257212 -28.309824)
						(mid 42.742612 -28.309824)
						(end 45.257212 -28.309824)
					)
				)
			)
		)
	)
	(footprint ""
		(layer "B.Cu")
		(at 7.62 -64.837056 -90)
		(property "Reference" "PC38"
			(at 0 0 90)
			(layer "B.SilkS")
			(hide yes)
			(effects
				(font
					(size 1.27 1.27)
				)
				(justify mirror)
			)
		)
		(property "Value" ""
			(at 0 0 90)
			(layer "B.Fab")
			(effects
				(font
					(size 1.27 1.27)
				)
				(justify mirror)
			)
		)
		(duplicate_pad_numbers_are_jumpers no)
		(fp_line
			(start -0.7874 0.4064)
			(end 0.7874 0.4064)
			(stroke
				(width 0.1524)
				(type default)
			)
			(layer "B.SilkS")
		)
		(fp_line
			(start 0.7874 0.4064)
			(end 0.7874 -0.4064)
			(stroke
				(width 0.1524)
				(type default)
			)
			(layer "B.SilkS")
		)
		(fp_line
			(start -0.7874 -0.4064)
			(end -0.7874 0.4064)
			(stroke
				(width 0.1524)
				(type default)
			)
			(layer "B.SilkS")
		)
		(fp_line
			(start 0.7874 -0.4064)
			(end -0.7874 -0.4064)
			(stroke
				(width 0.1524)
				(type default)
			)
			(layer "B.SilkS")
		)
		(fp_line
			(start -0.67945 0.3048)
			(end -0.120396 0.3048)
			(stroke
				(width 0.1)
				(type default)
			)
			(layer "B.Fab")
		)
		(fp_line
			(start -0.120396 0.3048)
			(end -0.120396 0.2794)
			(stroke
				(width 0.1)
				(type default)
			)
			(layer "B.Fab")
		)
		(fp_line
			(start 0.12065 0.3048)
			(end 0.67945 0.3048)
			(stroke
				(width 0.1)
				(type default)
			)
			(layer "B.Fab")
		)
		(fp_line
			(start 0.67945 0.3048)
			(end 0.67945 -0.305054)
			(stroke
				(width 0.1)
				(type default)
			)
			(layer "B.Fab")
		)
		(fp_line
			(start -0.120396 0.2794)
			(end 0.12065 0.2794)
			(stroke
				(width 0.1)
				(type default)
			)
			(layer "B.Fab")
		)
		(fp_line
			(start 0.12065 0.2794)
			(end 0.12065 0.3048)
			(stroke
				(width 0.1)
				(type default)
			)
			(layer "B.Fab")
		)
		(fp_line
			(start -0.12065 -0.2794)
			(end -0.12065 -0.3048)
			(stroke
				(width 0.1)
				(type default)
			)
			(layer "B.Fab")
		)
		(fp_line
			(start 0.12065 -0.2794)
			(end -0.12065 -0.2794)
			(stroke
				(width 0.1)
				(type default)
			)
			(layer "B.Fab")
		)
		(fp_line
			(start -0.67945 -0.3048)
			(end -0.67945 0.3048)
			(stroke
				(width 0.1)
				(type default)
			)
			(layer "B.Fab")
		)
		(fp_line
			(start -0.12065 -0.3048)
			(end -0.67945 -0.3048)
			(stroke
				(width 0.1)
				(type default)
			)
			(layer "B.Fab")
		)
		(fp_line
			(start 0.12065 -0.305054)
			(end 0.12065 -0.2794)
			(stroke
				(width 0.1)
				(type default)
			)
			(layer "B.Fab")
		)
		(fp_line
			(start 0.67945 -0.305054)
			(end 0.12065 -0.305054)
			(stroke
				(width 0.1)
				(type default)
			)
			(layer "B.Fab")
		)
		(pad "1" smd circle
			(at 0.40005 0 90)
			(size 0 0)
			(layers "B.Cu" "B.Mask" "B.Paste")
			(net "FAN_4_P3V_R")
		)
		(pad "2" smd circle
			(at -0.40005 0 90)
			(size 0 0)
			(layers "B.Cu" "B.Mask" "B.Paste")
			(net "GND")
		)
	)
	(footprint ""
		(layer "B.Cu")
		(at 37.211 -250.23699 90)
		(property "Reference" "PC3119"
			(at 0 0 90)
			(layer "B.SilkS")
			(hide yes)
			(effects
				(font
					(size 1.27 1.27)
				)
				(justify mirror)
			)
		)
		(property "Value" ""
			(at 0 0 90)
			(layer "B.Fab")
			(effects
				(font
					(size 1.27 1.27)
				)
				(justify mirror)
			)
		)
		(duplicate_pad_numbers_are_jumpers no)
		(fp_line
			(start 0.7874 -0.4064)
			(end -0.7874 -0.4064)
			(stroke
				(width 0.1524)
				(type default)
			)
			(layer "B.SilkS")
		)
		(fp_line
			(start -0.7874 -0.4064)
			(end -0.7874 0.4064)
			(stroke
				(width 0.1524)
				(type default)
			)
			(layer "B.SilkS")
		)
		(fp_line
			(start 0.7874 0.4064)
			(end 0.7874 -0.4064)
			(stroke
				(width 0.1524)
				(type default)
			)
			(layer "B.SilkS")
		)
		(fp_line
			(start -0.7874 0.4064)
			(end 0.7874 0.4064)
			(stroke
				(width 0.1524)
				(type default)
			)
			(layer "B.SilkS")
		)
		(fp_line
			(start 0.67945 -0.305054)
			(end 0.12065 -0.305054)
			(stroke
				(width 0.1)
				(type default)
			)
			(layer "B.Fab")
		)
		(fp_line
			(start 0.12065 -0.305054)
			(end 0.12065 -0.2794)
			(stroke
				(width 0.1)
				(type default)
			)
			(layer "B.Fab")
		)
		(fp_line
			(start -0.12065 -0.3048)
			(end -0.67945 -0.3048)
			(stroke
				(width 0.1)
				(type default)
			)
			(layer "B.Fab")
		)
		(fp_line
			(start -0.67945 -0.3048)
			(end -0.67945 0.3048)
			(stroke
				(width 0.1)
				(type default)
			)
			(layer "B.Fab")
		)
		(fp_line
			(start 0.12065 -0.2794)
			(end -0.12065 -0.2794)
			(stroke
				(width 0.1)
				(type default)
			)
			(layer "B.Fab")
		)
		(fp_line
			(start -0.12065 -0.2794)
			(end -0.12065 -0.3048)
			(stroke
				(width 0.1)
				(type default)
			)
			(layer "B.Fab")
		)
		(fp_line
			(start 0.12065 0.2794)
			(end 0.12065 0.3048)
			(stroke
				(width 0.1)
				(type default)
			)
			(layer "B.Fab")
		)
		(fp_line
			(start -0.120396 0.2794)
			(end 0.12065 0.2794)
			(stroke
				(width 0.1)
				(type default)
			)
			(layer "B.Fab")
		)
		(fp_line
			(start 0.67945 0.3048)
			(end 0.67945 -0.305054)
			(stroke
				(width 0.1)
				(type default)
			)
			(layer "B.Fab")
		)
		(fp_line
			(start 0.12065 0.3048)
			(end 0.67945 0.3048)
			(stroke
				(width 0.1)
				(type default)
			)
			(layer "B.Fab")
		)
		(fp_line
			(start -0.120396 0.3048)
			(end -0.120396 0.2794)
			(stroke
				(width 0.1)
				(type default)
			)
			(layer "B.Fab")
		)
		(fp_line
			(start -0.67945 0.3048)
			(end -0.120396 0.3048)
			(stroke
				(width 0.1)
				(type default)
			)
			(layer "B.Fab")
		)
		(pad "1" smd circle
			(at 0.40005 0 270)
			(size 0 0)
			(layers "B.Cu" "B.Mask" "B.Paste")
			(net "GND")
		)
		(pad "2" smd circle
			(at -0.40005 0 270)
			(size 0 0)
			(layers "B.Cu" "B.Mask" "B.Paste")
			(net "FAN_1_CLREF")
		)
	)
	(footprint ""
		(layer "B.Cu")
		(at 46.6852 -247.8278 90)
		(property "Reference" "PD4"
			(at -5.5372 3.88493 270)
			(unlocked yes)
			(layer "B.SilkS")
			(effects
				(font
					(size 0.7874 0.5842)
					(thickness 0.1524)
				)
				(justify left mirror)
			)
		)
		(property "Value" ""
			(at 0 0 90)
			(layer "B.Fab")
			(effects
				(font
					(size 1.27 1.27)
				)
				(justify mirror)
			)
		)
		(duplicate_pad_numbers_are_jumpers no)
		(fp_line
			(start 4.647184 -3.109976)
			(end 4.647184 3.109976)
			(stroke
				(width 0.1524)
				(type default)
			)
			(layer "B.SilkS")
		)
		(fp_line
			(start -5.536184 -3.109976)
			(end 4.647184 -3.109976)
			(stroke
				(width 0.1524)
				(type default)
			)
			(layer "B.SilkS")
		)
		(fp_line
			(start -0.762 -1.143)
			(end -0.762 0.889)
			(stroke
				(width 0.1524)
				(type default)
			)
			(layer "B.SilkS")
		)
		(fp_line
			(start 0.635 -0.889)
			(end 0.635 0.635)
			(stroke
				(width 0.1524)
				(type default)
			)
			(layer "B.SilkS")
		)
		(fp_line
			(start 1.397 -0.127)
			(end 0.635 -0.127)
			(stroke
				(width 0.1524)
				(type default)
			)
			(layer "B.SilkS")
		)
		(fp_line
			(start -0.635 -0.127)
			(end 0.635 -0.889)
			(stroke
				(width 0.1524)
				(type default)
			)
			(layer "B.SilkS")
		)
		(fp_line
			(start -0.635 -0.127)
			(end -1.397 -0.127)
			(stroke
				(width 0.1524)
				(type default)
			)
			(layer "B.SilkS")
		)
		(fp_line
			(start 0.635 0.635)
			(end -0.635 -0.127)
			(stroke
				(width 0.1524)
				(type default)
			)
			(layer "B.SilkS")
		)
		(fp_line
			(start 4.647184 3.109976)
			(end -5.536184 3.109976)
			(stroke
				(width 0.1524)
				(type default)
			)
			(layer "B.SilkS")
		)
		(fp_line
			(start -5.536184 3.109976)
			(end -5.536184 -3.109976)
			(stroke
				(width 0.1524)
				(type default)
			)
			(layer "B.SilkS")
		)
		(fp_poly
			(pts
				(xy -5.5118 -3.0988) (xy -5.5118 3.1496) (xy -4.572 3.1496) (xy -4.572 -3.0988)
			)
			(stroke
				(width 0)
				(type default)
			)
			(fill yes)
			(layer "B.SilkS")
		)
		(fp_line
			(start 3.554984 -3.109976)
			(end 3.554984 3.109976)
			(stroke
				(width 0.1)
				(type default)
			)
			(layer "B.Fab")
		)
		(fp_line
			(start -3.554984 -3.109976)
			(end 3.554984 -3.109976)
			(stroke
				(width 0.1)
				(type default)
			)
			(layer "B.Fab")
		)
		(fp_line
			(start 3.554984 3.109976)
			(end -3.554984 3.109976)
			(stroke
				(width 0.1)
				(type default)
			)
			(layer "B.Fab")
		)
		(fp_line
			(start -3.554984 3.109976)
			(end -3.554984 -3.109976)
			(stroke
				(width 0.1)
				(type default)
			)
			(layer "B.Fab")
		)
		(fp_text user "+"
			(at 6.0452 -1.94945 90)
			(unlocked yes)
			(layer "B.SilkS")
			(effects
				(font
					(size 1.905 1.4224)
					(thickness 0.1524)
				)
				(justify left mirror)
			)
		)
		(fp_text user "-"
			(at -5.5118 -1.56845 90)
			(unlocked yes)
			(layer "B.SilkS")
			(effects
				(font
					(size 1.905 1.4224)
					(thickness 0.1524)
				)
				(justify left mirror)
			)
		)
		(fp_text user "-"
			(at -5.334 -0.34925 90)
			(unlocked yes)
			(layer "B.Fab")
			(effects
				(font
					(size 1.905 1.4224)
					(thickness 0.1524)
				)
				(justify left mirror)
			)
		)
		(fp_text user "+"
			(at 6.1214 -0.32385 90)
			(unlocked yes)
			(layer "B.Fab")
			(effects
				(font
					(size 1.905 1.4224)
					(thickness 0.1524)
				)
				(justify left mirror)
			)
		)
		(pad "A" smd rect
			(at 3.299968 0 270)
			(size 2.413 3.302)
			(layers "B.Cu" "B.Mask" "B.Paste")
			(net "GND")
		)
		(pad "C" smd rect
			(at -3.299968 0 270)
			(size 2.413 3.302)
			(layers "B.Cu" "B.Mask" "B.Paste")
			(net "P52V_HSC")
		)
	)
	(footprint ""
		(layer "B.Cu")
		(at 5.38099 -78.416912 -90)
		(property "Reference" "PD16"
			(at -2.736088 -3.73634 270)
			(unlocked yes)
			(layer "B.SilkS")
			(effects
				(font
					(size 0.7874 0.5842)
					(thickness 0.1524)
				)
				(justify left mirror)
			)
		)
		(property "Value" ""
			(at 0 0 90)
			(layer "B.Fab")
			(effects
				(font
					(size 1.27 1.27)
				)
				(justify mirror)
			)
		)
		(duplicate_pad_numbers_are_jumpers no)
		(fp_line
			(start -5.536184 3.109976)
			(end -5.536184 -3.109976)
			(stroke
				(width 0.1524)
				(type default)
			)
			(layer "B.SilkS")
		)
		(fp_line
			(start 4.647184 3.109976)
			(end -5.536184 3.109976)
			(stroke
				(width 0.1524)
				(type default)
			)
			(layer "B.SilkS")
		)
		(fp_line
			(start 0.635 0.635)
			(end -0.635 -0.127)
			(stroke
				(width 0.1524)
				(type default)
			)
			(layer "B.SilkS")
		)
		(fp_line
			(start -0.635 -0.127)
			(end -1.397 -0.127)
			(stroke
				(width 0.1524)
				(type default)
			)
			(layer "B.SilkS")
		)
		(fp_line
			(start -0.635 -0.127)
			(end 0.635 -0.889)
			(stroke
				(width 0.1524)
				(type default)
			)
			(layer "B.SilkS")
		)
		(fp_line
			(start 1.397 -0.127)
			(end 0.635 -0.127)
			(stroke
				(width 0.1524)
				(type default)
			)
			(layer "B.SilkS")
		)
		(fp_line
			(start 0.635 -0.889)
			(end 0.635 0.635)
			(stroke
				(width 0.1524)
				(type default)
			)
			(layer "B.SilkS")
		)
		(fp_line
			(start -0.762 -1.143)
			(end -0.762 0.889)
			(stroke
				(width 0.1524)
				(type default)
			)
			(layer "B.SilkS")
		)
		(fp_line
			(start -5.536184 -3.109976)
			(end 4.647184 -3.109976)
			(stroke
				(width 0.1524)
				(type default)
			)
			(layer "B.SilkS")
		)
		(fp_line
			(start 4.647184 -3.109976)
			(end 4.647184 3.109976)
			(stroke
				(width 0.1524)
				(type default)
			)
			(layer "B.SilkS")
		)
		(fp_poly
			(pts
				(xy -5.5118 -3.0988) (xy -5.5118 3.1496) (xy -4.572 3.1496) (xy -4.572 -3.0988)
			)
			(stroke
				(width 0)
				(type default)
			)
			(fill yes)
			(layer "B.SilkS")
		)
		(fp_line
			(start -3.554984 3.109976)
			(end -3.554984 -3.109976)
			(stroke
				(width 0.1)
				(type default)
			)
			(layer "B.Fab")
		)
		(fp_line
			(start 3.554984 3.109976)
			(end -3.554984 3.109976)
			(stroke
				(width 0.1)
				(type default)
			)
			(layer "B.Fab")
		)
		(fp_line
			(start -3.554984 -3.109976)
			(end 3.554984 -3.109976)
			(stroke
				(width 0.1)
				(type default)
			)
			(layer "B.Fab")
		)
		(fp_line
			(start 3.554984 -3.109976)
			(end 3.554984 3.109976)
			(stroke
				(width 0.1)
				(type default)
			)
			(layer "B.Fab")
		)
		(fp_text user "-"
			(at -5.403088 2.36474 270)
			(unlocked yes)
			(layer "B.SilkS")
			(effects
				(font
					(size 1.905 1.4224)
					(thickness 0.1524)
				)
				(justify left mirror)
			)
		)
		(fp_text user "+"
			(at 7.169912 -0.55626 270)
			(unlocked yes)
			(layer "B.SilkS")
			(effects
				(font
					(size 1.905 1.4224)
					(thickness 0.1524)
				)
				(justify left mirror)
			)
		)
		(fp_text user "+"
			(at 6.1214 -0.32385 270)
			(unlocked yes)
			(layer "B.Fab")
			(effects
				(font
					(size 1.905 1.4224)
					(thickness 0.1524)
				)
				(justify left mirror)
			)
		)
		(fp_text user "-"
			(at -5.334 -0.34925 270)
			(unlocked yes)
			(layer "B.Fab")
			(effects
				(font
					(size 1.905 1.4224)
					(thickness 0.1524)
				)
				(justify left mirror)
			)
		)
		(pad "A" smd rect
			(at 3.299968 0 90)
			(size 2.413 3.302)
			(layers "B.Cu" "B.Mask" "B.Paste")
			(net "GND")
		)
		(pad "C" smd rect
			(at -3.299968 0 90)
			(size 2.413 3.302)
			(layers "B.Cu" "B.Mask" "B.Paste")
			(net "P52V_HSC")
		)
	)
	(footprint ""
		(layer "B.Cu")
		(at 3.683 -249.428 -90)
		(property "Reference" "PC52"
			(at 0 0 90)
			(layer "B.SilkS")
			(hide yes)
			(effects
				(font
					(size 1.27 1.27)
				)
				(justify mirror)
			)
		)
		(property "Value" ""
			(at 0 0 90)
			(layer "B.Fab")
			(effects
				(font
					(size 1.27 1.27)
				)
				(justify mirror)
			)
		)
		(duplicate_pad_numbers_are_jumpers no)
		(fp_line
			(start -0.7874 0.4064)
			(end 0.7874 0.4064)
			(stroke
				(width 0.1524)
				(type default)
			)
			(layer "B.SilkS")
		)
		(fp_line
			(start 0.7874 0.4064)
			(end 0.7874 -0.4064)
			(stroke
				(width 0.1524)
				(type default)
			)
			(layer "B.SilkS")
		)
		(fp_line
			(start -0.7874 -0.4064)
			(end -0.7874 0.4064)
			(stroke
				(width 0.1524)
				(type default)
			)
			(layer "B.SilkS")
		)
		(fp_line
			(start 0.7874 -0.4064)
			(end -0.7874 -0.4064)
			(stroke
				(width 0.1524)
				(type default)
			)
			(layer "B.SilkS")
		)
		(fp_line
			(start -0.67945 0.3048)
			(end -0.120396 0.3048)
			(stroke
				(width 0.1)
				(type default)
			)
			(layer "B.Fab")
		)
		(fp_line
			(start -0.120396 0.3048)
			(end -0.120396 0.2794)
			(stroke
				(width 0.1)
				(type default)
			)
			(layer "B.Fab")
		)
		(fp_line
			(start 0.12065 0.3048)
			(end 0.67945 0.3048)
			(stroke
				(width 0.1)
				(type default)
			)
			(layer "B.Fab")
		)
		(fp_line
			(start 0.67945 0.3048)
			(end 0.67945 -0.305054)
			(stroke
				(width 0.1)
				(type default)
			)
			(layer "B.Fab")
		)
		(fp_line
			(start -0.120396 0.2794)
			(end 0.12065 0.2794)
			(stroke
				(width 0.1)
				(type default)
			)
			(layer "B.Fab")
		)
		(fp_line
			(start 0.12065 0.2794)
			(end 0.12065 0.3048)
			(stroke
				(width 0.1)
				(type default)
			)
			(layer "B.Fab")
		)
		(fp_line
			(start -0.12065 -0.2794)
			(end -0.12065 -0.3048)
			(stroke
				(width 0.1)
				(type default)
			)
			(layer "B.Fab")
		)
		(fp_line
			(start 0.12065 -0.2794)
			(end -0.12065 -0.2794)
			(stroke
				(width 0.1)
				(type default)
			)
			(layer "B.Fab")
		)
		(fp_line
			(start -0.67945 -0.3048)
			(end -0.67945 0.3048)
			(stroke
				(width 0.1)
				(type default)
			)
			(layer "B.Fab")
		)
		(fp_line
			(start -0.12065 -0.3048)
			(end -0.67945 -0.3048)
			(stroke
				(width 0.1)
				(type default)
			)
			(layer "B.Fab")
		)
		(fp_line
			(start 0.12065 -0.305054)
			(end 0.12065 -0.2794)
			(stroke
				(width 0.1)
				(type default)
			)
			(layer "B.Fab")
		)
		(fp_line
			(start 0.67945 -0.305054)
			(end 0.12065 -0.305054)
			(stroke
				(width 0.1)
				(type default)
			)
			(layer "B.Fab")
		)
		(pad "1" smd circle
			(at 0.40005 0 90)
			(size 0 0)
			(layers "B.Cu" "B.Mask" "B.Paste")
			(net "FAN_6_SS")
		)
		(pad "2" smd circle
			(at -0.40005 0 90)
			(size 0 0)
			(layers "B.Cu" "B.Mask" "B.Paste")
			(net "GND")
		)
	)
	(footprint ""
		(layer "B.Cu")
		(at -14.841474 -209.296)
		(property "Reference" "J95"
			(at 3.5052 -5.552948 0)
			(unlocked yes)
			(layer "B.SilkS")
			(effects
				(font
					(size 0.7874 0.5842)
					(thickness 0.1524)
				)
				(justify left mirror)
			)
		)
		(property "Value" ""
			(at 0 0 0)
			(layer "B.Fab")
			(effects
				(font
					(size 1.27 1.27)
				)
				(justify mirror)
			)
		)
		(duplicate_pad_numbers_are_jumpers no)
		(fp_line
			(start -3.330702 -4.771136)
			(end 0 4.011168)
			(stroke
				(width 0.1524)
				(type default)
			)
			(layer "B.SilkS")
		)
		(fp_line
			(start 0 4.011168)
			(end 3.330702 -4.771136)
			(stroke
				(width 0.1524)
				(type default)
			)
			(layer "B.SilkS")
		)
		(fp_line
			(start 3.330702 -4.771136)
			(end -3.330702 -4.771136)
			(stroke
				(width 0.1524)
				(type default)
			)
			(layer "B.SilkS")
		)
		(fp_line
			(start -3.330702 -4.771136)
			(end 0 4.011168)
			(stroke
				(width 0.1)
				(type default)
			)
			(layer "B.Fab")
		)
		(fp_line
			(start 0 4.011168)
			(end 3.330702 -4.771136)
			(stroke
				(width 0.1)
				(type default)
			)
			(layer "B.Fab")
		)
		(fp_line
			(start 3.330702 -4.771136)
			(end -3.330702 -4.771136)
			(stroke
				(width 0.1)
				(type default)
			)
			(layer "B.Fab")
		)
		(pad "1" thru_hole circle
			(at 0 0 180)
			(size 2.159 2.159)
			(drill 1.7018)
			(layers "*.Cu" "*.Mask")
			(remove_unused_layers no)
			(net "GND2")
			(clearance 0.0254)
			(thermal_gap 0.0254)
		)
		(pad "2" thru_hole circle
			(at 1.27 -3.348736 180)
			(size 2.159 2.159)
			(drill 1.7018)
			(layers "*.Cu" "*.Mask")
			(remove_unused_layers no)
			(net "TDR_SE_50_OHM_BOT")
			(clearance 0.0254)
			(thermal_gap 0.0254)
		)
		(pad "3" thru_hole circle
			(at -1.27 -3.348736 180)
			(size 2.159 2.159)
			(drill 1.7018)
			(layers "*.Cu" "*.Mask")
			(remove_unused_layers no)
			(net "TDR_SE_50_OHM_BOT")
			(clearance 0.0254)
			(thermal_gap 0.0254)
		)
	)
	(footprint ""
		(layer "B.Cu")
		(at 16.383 -258.572 90)
		(property "Reference" "PC59"
			(at 0 0 90)
			(layer "B.SilkS")
			(hide yes)
			(effects
				(font
					(size 1.27 1.27)
				)
				(justify mirror)
			)
		)
		(property "Value" ""
			(at 0 0 90)
			(layer "B.Fab")
			(effects
				(font
					(size 1.27 1.27)
				)
				(justify mirror)
			)
		)
		(duplicate_pad_numbers_are_jumpers no)
		(fp_line
			(start 0.7874 -0.4064)
			(end -0.7874 -0.4064)
			(stroke
				(width 0.1524)
				(type default)
			)
			(layer "B.SilkS")
		)
		(fp_line
			(start -0.7874 -0.4064)
			(end -0.7874 0.4064)
			(stroke
				(width 0.1524)
				(type default)
			)
			(layer "B.SilkS")
		)
		(fp_line
			(start 0.7874 0.4064)
			(end 0.7874 -0.4064)
			(stroke
				(width 0.1524)
				(type default)
			)
			(layer "B.SilkS")
		)
		(fp_line
			(start -0.7874 0.4064)
			(end 0.7874 0.4064)
			(stroke
				(width 0.1524)
				(type default)
			)
			(layer "B.SilkS")
		)
		(fp_line
			(start 0.67945 -0.305054)
			(end 0.12065 -0.305054)
			(stroke
				(width 0.1)
				(type default)
			)
			(layer "B.Fab")
		)
		(fp_line
			(start 0.12065 -0.305054)
			(end 0.12065 -0.2794)
			(stroke
				(width 0.1)
				(type default)
			)
			(layer "B.Fab")
		)
		(fp_line
			(start -0.12065 -0.3048)
			(end -0.67945 -0.3048)
			(stroke
				(width 0.1)
				(type default)
			)
			(layer "B.Fab")
		)
		(fp_line
			(start -0.67945 -0.3048)
			(end -0.67945 0.3048)
			(stroke
				(width 0.1)
				(type default)
			)
			(layer "B.Fab")
		)
		(fp_line
			(start 0.12065 -0.2794)
			(end -0.12065 -0.2794)
			(stroke
				(width 0.1)
				(type default)
			)
			(layer "B.Fab")
		)
		(fp_line
			(start -0.12065 -0.2794)
			(end -0.12065 -0.3048)
			(stroke
				(width 0.1)
				(type default)
			)
			(layer "B.Fab")
		)
		(fp_line
			(start 0.12065 0.2794)
			(end 0.12065 0.3048)
			(stroke
				(width 0.1)
				(type default)
			)
			(layer "B.Fab")
		)
		(fp_line
			(start -0.120396 0.2794)
			(end 0.12065 0.2794)
			(stroke
				(width 0.1)
				(type default)
			)
			(layer "B.Fab")
		)
		(fp_line
			(start 0.67945 0.3048)
			(end 0.67945 -0.305054)
			(stroke
				(width 0.1)
				(type default)
			)
			(layer "B.Fab")
		)
		(fp_line
			(start 0.12065 0.3048)
			(end 0.67945 0.3048)
			(stroke
				(width 0.1)
				(type default)
			)
			(layer "B.Fab")
		)
		(fp_line
			(start -0.120396 0.3048)
			(end -0.120396 0.2794)
			(stroke
				(width 0.1)
				(type default)
			)
			(layer "B.Fab")
		)
		(fp_line
			(start -0.67945 0.3048)
			(end -0.120396 0.3048)
			(stroke
				(width 0.1)
				(type default)
			)
			(layer "B.Fab")
		)
		(pad "1" smd circle
			(at 0.40005 0 270)
			(size 0 0)
			(layers "B.Cu" "B.Mask" "B.Paste")
			(net "FAN_7_TIMER")
		)
		(pad "2" smd circle
			(at -0.40005 0 270)
			(size 0 0)
			(layers "B.Cu" "B.Mask" "B.Paste")
			(net "GND")
		)
	)
	(footprint ""
		(layer "B.Cu")
		(at 5.900166 -58.995056)
		(property "Reference" "PU6"
			(at 5.275834 2.252726 0)
			(unlocked yes)
			(layer "B.SilkS")
			(effects
				(font
					(size 0.7874 0.5842)
					(thickness 0.1524)
				)
				(justify left mirror)
			)
		)
		(property "Value" ""
			(at 0 0 0)
			(layer "B.Fab")
			(effects
				(font
					(size 1.27 1.27)
				)
				(justify mirror)
			)
		)
		(duplicate_pad_numbers_are_jumpers no)
		(fp_line
			(start -2.549906 -2.549906)
			(end -2.4384 -2.549906)
			(stroke
				(width 0.1524)
				(type default)
			)
			(layer "B.SilkS")
		)
		(fp_line
			(start -2.549906 -2.2352)
			(end -2.549906 -2.549906)
			(stroke
				(width 0.1524)
				(type default)
			)
			(layer "B.SilkS")
		)
		(fp_line
			(start -2.549906 -1.4986)
			(end -2.549906 -1.7526)
			(stroke
				(width 0.1524)
				(type default)
			)
			(layer "B.SilkS")
		)
		(fp_line
			(start -2.549906 -0.6858)
			(end -2.549906 -0.9144)
			(stroke
				(width 0.1524)
				(type default)
			)
			(layer "B.SilkS")
		)
		(fp_line
			(start -2.549906 0.9144)
			(end -2.549906 -0.1016)
			(stroke
				(width 0.1524)
				(type default)
			)
			(layer "B.SilkS")
		)
		(fp_line
			(start -2.549906 1.7526)
			(end -2.549906 1.4986)
			(stroke
				(width 0.1524)
				(type default)
			)
			(layer "B.SilkS")
		)
		(fp_line
			(start -2.549906 2.549906)
			(end -2.549906 2.2352)
			(stroke
				(width 0.1524)
				(type default)
			)
			(layer "B.SilkS")
		)
		(fp_line
			(start -2.4384 2.549906)
			(end -2.549906 2.549906)
			(stroke
				(width 0.1524)
				(type default)
			)
			(layer "B.SilkS")
		)
		(fp_line
			(start -2.199894 2.9464)
			(end -2.199894 3.4544)
			(stroke
				(width 0.1524)
				(type default)
			)
			(layer "B.SilkS")
		)
		(fp_line
			(start -1.800098 -3.9624)
			(end -1.800098 -2.9464)
			(stroke
				(width 0.1524)
				(type default)
			)
			(layer "B.SilkS")
		)
		(fp_line
			(start -0.199898 2.9464)
			(end -0.199898 3.9624)
			(stroke
				(width 0.1524)
				(type default)
			)
			(layer "B.SilkS")
		)
		(fp_line
			(start 0.199898 -3.4544)
			(end 0.199898 -2.9464)
			(stroke
				(width 0.1524)
				(type default)
			)
			(layer "B.SilkS")
		)
		(fp_line
			(start 1.800098 2.9464)
			(end 1.800098 3.4544)
			(stroke
				(width 0.1524)
				(type default)
			)
			(layer "B.SilkS")
		)
		(fp_line
			(start 2.199894 -3.9624)
			(end 2.199894 -2.9464)
			(stroke
				(width 0.1524)
				(type default)
			)
			(layer "B.SilkS")
		)
		(fp_line
			(start 2.4384 -2.549906)
			(end 2.549906 -2.549906)
			(stroke
				(width 0.1524)
				(type default)
			)
			(layer "B.SilkS")
		)
		(fp_line
			(start 2.549906 -2.549906)
			(end 2.549906 -2.2352)
			(stroke
				(width 0.1524)
				(type default)
			)
			(layer "B.SilkS")
		)
		(fp_line
			(start 2.549906 -1.7526)
			(end 2.549906 -1.4986)
			(stroke
				(width 0.1524)
				(type default)
			)
			(layer "B.SilkS")
		)
		(fp_line
			(start 2.549906 -0.9144)
			(end 2.549906 0.1016)
			(stroke
				(width 0.1524)
				(type default)
			)
			(layer "B.SilkS")
		)
		(fp_line
			(start 2.549906 0.6858)
			(end 2.549906 0.9144)
			(stroke
				(width 0.1524)
				(type default)
			)
			(layer "B.SilkS")
		)
		(fp_line
			(start 2.549906 1.4986)
			(end 2.549906 1.7526)
			(stroke
				(width 0.1524)
				(type default)
			)
			(layer "B.SilkS")
		)
		(fp_line
			(start 2.549906 2.2352)
			(end 2.549906 2.549906)
			(stroke
				(width 0.1524)
				(type default)
			)
			(layer "B.SilkS")
		)
		(fp_line
			(start 2.549906 2.549906)
			(end 2.4384 2.549906)
			(stroke
				(width 0.1524)
				(type default)
			)
			(layer "B.SilkS")
		)
		(fp_poly
			(pts
				(xy 3.488944 -1.474978) (xy 2.939034 -1.199896) (xy 3.488944 -0.925068)
			)
			(stroke
				(width 0)
				(type default)
			)
			(fill yes)
			(layer "B.SilkS")
		)
		(fp_line
			(start -2.549906 -2.549906)
			(end 2.549906 -2.549906)
			(stroke
				(width 0.1)
				(type default)
			)
			(layer "B.Fab")
		)
		(fp_line
			(start -2.549906 2.549906)
			(end -2.549906 -2.549906)
			(stroke
				(width 0.1)
				(type default)
			)
			(layer "B.Fab")
		)
		(fp_line
			(start -2.199894 2.9464)
			(end -2.199894 3.4544)
			(stroke
				(width 0.1)
				(type default)
			)
			(layer "B.Fab")
		)
		(fp_line
			(start -1.800098 -3.9624)
			(end -1.800098 -2.9464)
			(stroke
				(width 0.1)
				(type default)
			)
			(layer "B.Fab")
		)
		(fp_line
			(start -0.199898 2.9464)
			(end -0.199898 3.9624)
			(stroke
				(width 0.1)
				(type default)
			)
			(layer "B.Fab")
		)
		(fp_line
			(start 0.199898 -3.4544)
			(end 0.199898 -2.9464)
			(stroke
				(width 0.1)
				(type default)
			)
			(layer "B.Fab")
		)
		(fp_line
			(start 1.800098 2.9464)
			(end 1.800098 3.4544)
			(stroke
				(width 0.1)
				(type default)
			)
			(layer "B.Fab")
		)
		(fp_line
			(start 2.199894 -3.9624)
			(end 2.199894 -2.9464)
			(stroke
				(width 0.1)
				(type default)
			)
			(layer "B.Fab")
		)
		(fp_line
			(start 2.549906 -2.549906)
			(end 2.549906 2.549906)
			(stroke
				(width 0.1)
				(type default)
			)
			(layer "B.Fab")
		)
		(fp_line
			(start 2.549906 2.549906)
			(end -2.549906 2.549906)
			(stroke
				(width 0.1)
				(type default)
			)
			(layer "B.Fab")
		)
		(fp_poly
			(pts
				(xy 3.7084 -1.584706) (xy 2.939034 -1.199896) (xy 3.7084 -0.81534)
			)
			(stroke
				(width 0)
				(type default)
			)
			(fill yes)
			(layer "B.Fab")
		)
		(fp_text user "16"
			(at -3.329432 1.2192 270)
			(unlocked yes)
			(layer "B.SilkS")
			(effects
				(font
					(size 0.635 0.4064)
					(thickness 0.1524)
				)
				(justify mirror)
			)
		)
		(fp_text user "18"
			(at -3.304032 -1.2192 270)
			(unlocked yes)
			(layer "B.SilkS")
			(effects
				(font
					(size 0.635 0.4064)
					(thickness 0.1524)
				)
				(justify mirror)
			)
		)
		(fp_text user "15"
			(at -2.8956 3.126232 0)
			(unlocked yes)
			(layer "B.SilkS")
			(effects
				(font
					(size 0.635 0.4064)
					(thickness 0.1524)
				)
				(justify mirror)
			)
		)
		(fp_text user "19"
			(at -2.8448 -3.096768 0)
			(unlocked yes)
			(layer "B.SilkS")
			(effects
				(font
					(size 0.635 0.4064)
					(thickness 0.1524)
				)
				(justify mirror)
			)
		)
		(fp_text user "4"
			(at 2.6416 3.151632 0)
			(unlocked yes)
			(layer "B.SilkS")
			(effects
				(font
					(size 0.635 0.4064)
					(thickness 0.1524)
				)
				(justify mirror)
			)
		)
		(fp_text user "30"
			(at 2.9464 -3.045968 0)
			(unlocked yes)
			(layer "B.SilkS")
			(effects
				(font
					(size 0.635 0.4064)
					(thickness 0.1524)
				)
				(justify mirror)
			)
		)
		(fp_text user "3"
			(at 3.299968 1.1938 270)
			(unlocked yes)
			(layer "B.SilkS")
			(effects
				(font
					(size 0.635 0.4064)
					(thickness 0.1524)
				)
				(justify mirror)
			)
		)
		(fp_text user "16"
			(at -3.329432 1.2192 270)
			(unlocked yes)
			(layer "B.Fab")
			(effects
				(font
					(size 0.635 0.4064)
					(thickness 0.1524)
				)
				(justify mirror)
			)
		)
		(fp_text user "18"
			(at -3.304032 -1.2192 270)
			(unlocked yes)
			(layer "B.Fab")
			(effects
				(font
					(size 0.635 0.4064)
					(thickness 0.1524)
				)
				(justify mirror)
			)
		)
		(fp_text user "15"
			(at -2.8956 3.126232 0)
			(unlocked yes)
			(layer "B.Fab")
			(effects
				(font
					(size 0.635 0.4064)
					(thickness 0.1524)
				)
				(justify mirror)
			)
		)
		(fp_text user "19"
			(at -2.8448 -3.096768 0)
			(unlocked yes)
			(layer "B.Fab")
			(effects
				(font
					(size 0.635 0.4064)
					(thickness 0.1524)
				)
				(justify mirror)
			)
		)
		(fp_text user "4"
			(at 2.6416 3.151632 0)
			(unlocked yes)
			(layer "B.Fab")
			(effects
				(font
					(size 0.635 0.4064)
					(thickness 0.1524)
				)
				(justify mirror)
			)
		)
		(fp_text user "30"
			(at 2.9464 -3.045968 0)
			(unlocked yes)
			(layer "B.Fab")
			(effects
				(font
					(size 0.635 0.4064)
					(thickness 0.1524)
				)
				(justify mirror)
			)
		)
		(fp_text user "3"
			(at 3.299968 1.1938 270)
			(unlocked yes)
			(layer "B.Fab")
			(effects
				(font
					(size 0.635 0.4064)
					(thickness 0.1524)
				)
				(justify mirror)
			)
		)
		(pad "1" smd circle
			(at 1.599946 -1.199896 270)
			(size 0 0)
			(layers "B.Cu" "B.Mask" "B.Paste")
			(net "P52V_HSC")
		)
		(pad "2" smd rect
			(at 1.549908 0.40005 90)
			(size 0.3048 2.5146)
			(layers "B.Cu" "B.Mask" "B.Paste")
			(net "P52V_HSC")
		)
		(pad "3" smd rect
			(at 1.549908 1.199896 90)
			(size 0.3048 2.5146)
			(layers "B.Cu" "B.Mask" "B.Paste")
			(net "P52V_FAN_4")
		)
		(pad "4" smd circle
			(at 2.199894 2.350008)
			(size 0 0)
			(layers "B.Cu" "B.Mask" "B.Paste")
			(net "P52V_FAN_4")
		)
		(pad "5" smd rect
			(at 1.800098 2.350008 180)
			(size 0.1778 0.9144)
			(layers "B.Cu" "B.Mask" "B.Paste")
			(net "P52V_FAN_4")
		)
		(pad "6" smd rect
			(at 1.400048 2.350008 180)
			(size 0.1778 0.9144)
			(layers "B.Cu" "B.Mask" "B.Paste")
			(net "P52V_FAN_4")
		)
		(pad "7" smd rect
			(at 0.999998 2.350008 180)
			(size 0.1778 0.9144)
			(layers "B.Cu" "B.Mask" "B.Paste")
			(net "P52V_FAN_4")
		)
		(pad "8" smd rect
			(at 0.599948 2.350008 180)
			(size 0.1778 0.9144)
			(layers "B.Cu" "B.Mask" "B.Paste")
			(net "P52V_FAN_4")
		)
		(pad "9" smd rect
			(at 0.199898 2.350008 180)
			(size 0.1778 0.9144)
			(layers "B.Cu" "B.Mask" "B.Paste")
			(net "P52V_FAN_4")
		)
		(pad "10" smd rect
			(at -0.199898 2.350008 180)
			(size 0.1778 0.9144)
			(layers "B.Cu" "B.Mask" "B.Paste")
			(net "P52V_FAN_4")
		)
		(pad "11" smd rect
			(at -0.599948 2.350008 180)
			(size 0.1778 0.9144)
			(layers "B.Cu" "B.Mask" "B.Paste")
			(net "P52V_FAN_4")
		)
		(pad "12" smd rect
			(at -0.999998 2.350008 180)
			(size 0.1778 0.9144)
			(layers "B.Cu" "B.Mask" "B.Paste")
			(net "P52V_FAN_4")
		)
		(pad "13" smd rect
			(at -1.400048 2.350008 180)
			(size 0.1778 0.9144)
			(layers "B.Cu" "B.Mask" "B.Paste")
			(net "P52V_FAN_4")
		)
		(pad "14" smd rect
			(at -1.800098 2.350008 180)
			(size 0.1778 0.9144)
			(layers "B.Cu" "B.Mask" "B.Paste")
			(net "P52V_FAN_4")
		)
		(pad "15" smd circle
			(at -2.199894 2.350008)
			(size 0 0)
			(layers "B.Cu" "B.Mask" "B.Paste")
			(net "P52V_FAN_4")
		)
		(pad "16" smd rect
			(at -1.549908 1.199896 90)
			(size 0.3048 2.5146)
			(layers "B.Cu" "B.Mask" "B.Paste")
			(net "P52V_FAN_4")
		)
		(pad "17" smd rect
			(at -1.549908 -0.40005 90)
			(size 0.3048 2.5146)
			(layers "B.Cu" "B.Mask" "B.Paste")
			(net "P52V_FAN_4")
		)
		(pad "18" smd rect
			(at -1.549908 -1.199896 90)
			(size 0.3048 2.5146)
			(layers "B.Cu" "B.Mask" "B.Paste")
			(net "P52V_HSC")
		)
		(pad "19" smd circle
			(at -2.199894 -2.350008 180)
			(size 0 0)
			(layers "B.Cu" "B.Mask" "B.Paste")
			(net "FAN_4_CS")
		)
		(pad "20" smd rect
			(at -1.800098 -2.350008 180)
			(size 0.1778 0.9144)
			(layers "B.Cu" "B.Mask" "B.Paste")
			(net "FAN_4_IMON")
		)
		(pad "21" smd rect
			(at -1.400048 -2.350008 180)
			(size 0.1778 0.9144)
			(layers "B.Cu" "B.Mask" "B.Paste")
			(net "FAN_4_SS")
		)
		(pad "22" smd rect
			(at -0.999998 -2.350008 180)
			(size 0.1778 0.9144)
			(layers "B.Cu" "B.Mask" "B.Paste")
			(net "FAN_4_FAULT")
		)
		(pad "23" smd rect
			(at -0.599948 -2.350008 180)
			(size 0.1778 0.9144)
			(layers "B.Cu" "B.Mask" "B.Paste")
			(net "FAN_4_TIMER")
		)
		(pad "24" smd rect
			(at -0.199898 -2.350008 180)
			(size 0.1778 0.9144)
			(layers "B.Cu" "B.Mask" "B.Paste")
			(net "FAN_4_CLREF")
		)
		(pad "25" smd rect
			(at 0.199898 -2.350008 180)
			(size 0.1778 0.9144)
			(layers "B.Cu" "B.Mask" "B.Paste")
			(net "GND")
		)
		(pad "26" smd rect
			(at 0.599948 -2.350008 180)
			(size 0.1778 0.9144)
			(layers "B.Cu" "B.Mask" "B.Paste")
			(net "FAN_4_ON")
		)
		(pad "27" smd rect
			(at 0.999998 -2.350008 180)
			(size 0.1778 0.9144)
			(layers "B.Cu" "B.Mask" "B.Paste")
			(net "FAN_4_P3V_R")
		)
		(pad "28" smd rect
			(at 1.400048 -2.350008 180)
			(size 0.1778 0.9144)
			(layers "B.Cu" "B.Mask" "B.Paste")
			(net "FAN_4_P5V")
		)
		(pad "29" smd rect
			(at 1.800098 -2.350008 180)
			(size 0.1778 0.9144)
			(layers "B.Cu" "B.Mask" "B.Paste")
			(net "FAN_4_TEMP")
		)
		(pad "30" smd circle
			(at 2.199894 -2.350008 180)
			(size 0 0)
			(layers "B.Cu" "B.Mask" "B.Paste")
			(net "FAN_4_MODE")
		)
	)
	(footprint ""
		(layer "B.Cu")
		(at 33.142428 -78.416912 -90)
		(property "Reference" "PD6"
			(at 4.756912 3.959098 270)
			(unlocked yes)
			(layer "B.SilkS")
			(effects
				(font
					(size 0.7874 0.5842)
					(thickness 0.1524)
				)
				(justify left mirror)
			)
		)
		(property "Value" ""
			(at 0 0 90)
			(layer "B.Fab")
			(effects
				(font
					(size 1.27 1.27)
				)
				(justify mirror)
			)
		)
		(duplicate_pad_numbers_are_jumpers no)
		(fp_line
			(start -5.536184 3.109976)
			(end -5.536184 -3.109976)
			(stroke
				(width 0.1524)
				(type default)
			)
			(layer "B.SilkS")
		)
		(fp_line
			(start 4.647184 3.109976)
			(end -5.536184 3.109976)
			(stroke
				(width 0.1524)
				(type default)
			)
			(layer "B.SilkS")
		)
		(fp_line
			(start 0.635 0.635)
			(end -0.635 -0.127)
			(stroke
				(width 0.1524)
				(type default)
			)
			(layer "B.SilkS")
		)
		(fp_line
			(start -0.635 -0.127)
			(end -1.397 -0.127)
			(stroke
				(width 0.1524)
				(type default)
			)
			(layer "B.SilkS")
		)
		(fp_line
			(start -0.635 -0.127)
			(end 0.635 -0.889)
			(stroke
				(width 0.1524)
				(type default)
			)
			(layer "B.SilkS")
		)
		(fp_line
			(start 1.397 -0.127)
			(end 0.635 -0.127)
			(stroke
				(width 0.1524)
				(type default)
			)
			(layer "B.SilkS")
		)
		(fp_line
			(start 0.635 -0.889)
			(end 0.635 0.635)
			(stroke
				(width 0.1524)
				(type default)
			)
			(layer "B.SilkS")
		)
		(fp_line
			(start -0.762 -1.143)
			(end -0.762 0.889)
			(stroke
				(width 0.1524)
				(type default)
			)
			(layer "B.SilkS")
		)
		(fp_line
			(start -5.536184 -3.109976)
			(end 4.647184 -3.109976)
			(stroke
				(width 0.1524)
				(type default)
			)
			(layer "B.SilkS")
		)
		(fp_line
			(start 4.647184 -3.109976)
			(end 4.647184 3.109976)
			(stroke
				(width 0.1524)
				(type default)
			)
			(layer "B.SilkS")
		)
		(fp_poly
			(pts
				(xy -5.5118 -3.0988) (xy -5.5118 3.1496) (xy -4.572 3.1496) (xy -4.572 -3.0988)
			)
			(stroke
				(width 0)
				(type default)
			)
			(fill yes)
			(layer "B.SilkS")
		)
		(fp_line
			(start -3.554984 3.109976)
			(end -3.554984 -3.109976)
			(stroke
				(width 0.1)
				(type default)
			)
			(layer "B.Fab")
		)
		(fp_line
			(start 3.554984 3.109976)
			(end -3.554984 3.109976)
			(stroke
				(width 0.1)
				(type default)
			)
			(layer "B.Fab")
		)
		(fp_line
			(start -3.554984 -3.109976)
			(end 3.554984 -3.109976)
			(stroke
				(width 0.1)
				(type default)
			)
			(layer "B.Fab")
		)
		(fp_line
			(start 3.554984 -3.109976)
			(end 3.554984 3.109976)
			(stroke
				(width 0.1)
				(type default)
			)
			(layer "B.Fab")
		)
		(fp_text user "-"
			(at -5.334 -0.34925 270)
			(unlocked yes)
			(layer "B.SilkS")
			(effects
				(font
					(size 1.905 1.4224)
					(thickness 0.1524)
				)
				(justify left mirror)
			)
		)
		(fp_text user "+"
			(at 7.169912 -0.607822 270)
			(unlocked yes)
			(layer "B.SilkS")
			(effects
				(font
					(size 1.905 1.4224)
					(thickness 0.1524)
				)
				(justify left mirror)
			)
		)
		(fp_text user "+"
			(at 6.1214 -0.32385 270)
			(unlocked yes)
			(layer "B.Fab")
			(effects
				(font
					(size 1.905 1.4224)
					(thickness 0.1524)
				)
				(justify left mirror)
			)
		)
		(fp_text user "-"
			(at -5.334 -0.34925 270)
			(unlocked yes)
			(layer "B.Fab")
			(effects
				(font
					(size 1.905 1.4224)
					(thickness 0.1524)
				)
				(justify left mirror)
			)
		)
		(pad "A" smd rect
			(at 3.299968 0 90)
			(size 2.413 3.302)
			(layers "B.Cu" "B.Mask" "B.Paste")
			(net "GND")
		)
		(pad "C" smd rect
			(at -3.299968 0 90)
			(size 2.413 3.302)
			(layers "B.Cu" "B.Mask" "B.Paste")
			(net "P52V_HSC")
		)
	)
	(footprint ""
		(layer "B.Cu")
		(at 17.653 -129.667 180)
		(property "Reference" "R5437"
			(at 0 0 0)
			(layer "B.SilkS")
			(hide yes)
			(effects
				(font
					(size 1.27 1.27)
				)
				(justify mirror)
			)
		)
		(property "Value" ""
			(at 0 0 0)
			(layer "B.Fab")
			(effects
				(font
					(size 1.27 1.27)
				)
				(justify mirror)
			)
		)
		(duplicate_pad_numbers_are_jumpers no)
		(fp_line
			(start 0.7874 0.4064)
			(end 0.7874 -0.4064)
			(stroke
				(width 0.1524)
				(type default)
			)
			(layer "B.SilkS")
		)
		(fp_line
			(start 0.7874 -0.4064)
			(end -0.7874 -0.4064)
			(stroke
				(width 0.1524)
				(type default)
			)
			(layer "B.SilkS")
		)
		(fp_line
			(start -0.7874 0.4064)
			(end 0.7874 0.4064)
			(stroke
				(width 0.1524)
				(type default)
			)
			(layer "B.SilkS")
		)
		(fp_line
			(start -0.7874 -0.4064)
			(end -0.7874 0.4064)
			(stroke
				(width 0.1524)
				(type default)
			)
			(layer "B.SilkS")
		)
		(fp_line
			(start 0.67945 0.3048)
			(end 0.67945 -0.305054)
			(stroke
				(width 0.1)
				(type default)
			)
			(layer "B.Fab")
		)
		(fp_line
			(start 0.67945 -0.305054)
			(end 0.12065 -0.305054)
			(stroke
				(width 0.1)
				(type default)
			)
			(layer "B.Fab")
		)
		(fp_line
			(start 0.12065 0.3048)
			(end 0.67945 0.3048)
			(stroke
				(width 0.1)
				(type default)
			)
			(layer "B.Fab")
		)
		(fp_line
			(start 0.12065 0.2794)
			(end 0.12065 0.3048)
			(stroke
				(width 0.1)
				(type default)
			)
			(layer "B.Fab")
		)
		(fp_line
			(start 0.12065 -0.2794)
			(end -0.12065 -0.2794)
			(stroke
				(width 0.1)
				(type default)
			)
			(layer "B.Fab")
		)
		(fp_line
			(start 0.12065 -0.305054)
			(end 0.12065 -0.2794)
			(stroke
				(width 0.1)
				(type default)
			)
			(layer "B.Fab")
		)
		(fp_line
			(start -0.120396 0.3048)
			(end -0.120396 0.2794)
			(stroke
				(width 0.1)
				(type default)
			)
			(layer "B.Fab")
		)
		(fp_line
			(start -0.120396 0.2794)
			(end 0.12065 0.2794)
			(stroke
				(width 0.1)
				(type default)
			)
			(layer "B.Fab")
		)
		(fp_line
			(start -0.12065 -0.2794)
			(end -0.12065 -0.3048)
			(stroke
				(width 0.1)
				(type default)
			)
			(layer "B.Fab")
		)
		(fp_line
			(start -0.12065 -0.3048)
			(end -0.67945 -0.3048)
			(stroke
				(width 0.1)
				(type default)
			)
			(layer "B.Fab")
		)
		(fp_line
			(start -0.67945 0.3048)
			(end -0.120396 0.3048)
			(stroke
				(width 0.1)
				(type default)
			)
			(layer "B.Fab")
		)
		(fp_line
			(start -0.67945 -0.3048)
			(end -0.67945 0.3048)
			(stroke
				(width 0.1)
				(type default)
			)
			(layer "B.Fab")
		)
		(pad "1" smd rect
			(at 0.40005 0 180)
			(size 0.4572 0.508)
			(layers "B.Cu" "B.Mask" "B.Paste")
			(net "FAN_5_TACH_OL")
		)
		(pad "2" smd rect
			(at -0.40005 0 180)
			(size 0.4572 0.508)
			(layers "B.Cu" "B.Mask" "B.Paste")
			(net "GND")
		)
	)
	(footprint ""
		(layer "B.Cu")
		(at 44.99991 -118.709948)
		(property "Reference" "J3"
			(at 4.53009 -5.215382 0)
			(unlocked yes)
			(layer "B.SilkS")
			(effects
				(font
					(size 0.7874 0.5842)
					(thickness 0.1524)
				)
				(justify left mirror)
			)
		)
		(property "Value" ""
			(at 0 0 0)
			(layer "B.Fab")
			(effects
				(font
					(size 1.27 1.27)
				)
				(justify mirror)
			)
		)
		(duplicate_pad_numbers_are_jumpers no)
		(fp_line
			(start -6.35 -4.52501)
			(end 4.350004 -4.52501)
			(stroke
				(width 0.1524)
				(type default)
			)
			(layer "B.SilkS")
		)
		(fp_line
			(start -6.35 18.524982)
			(end -6.35 -4.52501)
			(stroke
				(width 0.1524)
				(type default)
			)
			(layer "B.SilkS")
		)
		(fp_line
			(start -3.24993 -1.42494)
			(end -1.96977 -1.42494)
			(stroke
				(width 0.1524)
				(type default)
			)
			(layer "B.SilkS")
		)
		(fp_line
			(start -3.24993 15.424912)
			(end -3.24993 -1.42494)
			(stroke
				(width 0.1524)
				(type default)
			)
			(layer "B.SilkS")
		)
		(fp_line
			(start -0.029972 -1.42494)
			(end 1.249934 -1.42494)
			(stroke
				(width 0.1524)
				(type default)
			)
			(layer "B.SilkS")
		)
		(fp_line
			(start 1.249934 -1.42494)
			(end 1.249934 5.799836)
			(stroke
				(width 0.1524)
				(type default)
			)
			(layer "B.SilkS")
		)
		(fp_line
			(start 1.249934 5.799836)
			(end 4.350004 5.799836)
			(stroke
				(width 0.1524)
				(type default)
			)
			(layer "B.SilkS")
		)
		(fp_line
			(start 1.249934 8.200136)
			(end 1.249934 15.424912)
			(stroke
				(width 0.1524)
				(type default)
			)
			(layer "B.SilkS")
		)
		(fp_line
			(start 1.249934 8.200136)
			(end 4.350004 8.200136)
			(stroke
				(width 0.1524)
				(type default)
			)
			(layer "B.SilkS")
		)
		(fp_line
			(start 1.249934 15.424912)
			(end -3.24993 15.424912)
			(stroke
				(width 0.1524)
				(type default)
			)
			(layer "B.SilkS")
		)
		(fp_line
			(start 4.350004 -4.52501)
			(end 4.350004 18.524982)
			(stroke
				(width 0.1524)
				(type default)
			)
			(layer "B.SilkS")
		)
		(fp_line
			(start 4.350004 18.524982)
			(end -6.35 18.524982)
			(stroke
				(width 0.1524)
				(type default)
			)
			(layer "B.SilkS")
		)
		(fp_poly
			(pts
				(xy 5.527802 -0.508) (xy 5.527802 0.508) (xy 4.511802 0)
			)
			(stroke
				(width 0)
				(type default)
			)
			(fill yes)
			(layer "B.SilkS")
		)
		(fp_line
			(start -6.35 -4.52501)
			(end 4.350004 -4.52501)
			(stroke
				(width 0.1)
				(type default)
			)
			(layer "B.Fab")
		)
		(fp_line
			(start -6.35 18.524982)
			(end -6.35 -4.52501)
			(stroke
				(width 0.1)
				(type default)
			)
			(layer "B.Fab")
		)
		(fp_line
			(start 4.350004 -4.52501)
			(end 4.350004 18.524982)
			(stroke
				(width 0.1)
				(type default)
			)
			(layer "B.Fab")
		)
		(fp_line
			(start 4.350004 18.524982)
			(end -6.35 18.524982)
			(stroke
				(width 0.1)
				(type default)
			)
			(layer "B.Fab")
		)
		(fp_poly
			(pts
				(xy 5.527802 -0.508) (xy 5.527802 0.508) (xy 4.511802 0)
			)
			(stroke
				(width 0)
				(type default)
			)
			(fill yes)
			(layer "B.Fab")
		)
		(pad "" np_thru_hole circle
			(at -0.999998 -1.89992 270)
			(size 1.4986 1.4986)
			(drill 1.4986)
			(layers "*.Cu" "*.Mask")
			(clearance 0.381)
			(thermal_gap 0.381)
		)
		(pad "1" thru_hole rect
			(at 0 0 270)
			(size 1.3716 1.3716)
			(drill 0.9652)
			(layers "*.Cu" "*.Mask")
			(remove_unused_layers no)
			(net "FAN_2_TACH_IL_D")
			(clearance 0.0508)
			(padstack
				(mode front_inner_back)
				(layer "Inner"
					(shape circle)
					(size 1.3716 1.3716)
					(clearance 0.0508)
				)
				(layer "B.Cu"
					(shape rect)
					(size 1.3716 1.3716)
					(thermal_gap 0.0508)
					(clearance 0.0508)
				)
			)
		)
		(pad "2" thru_hole circle
			(at -1.999996 0 270)
			(size 1.3716 1.3716)
			(drill 0.9652)
			(layers "*.Cu" "*.Mask")
			(remove_unused_layers no)
			(net "FAN_2_PWM_OL_R")
			(clearance 0.0508)
			(thermal_gap 0.0508)
		)
		(pad "3" thru_hole circle
			(at 0 1.999996 270)
			(size 1.3716 1.3716)
			(drill 0.9652)
			(layers "*.Cu" "*.Mask")
			(remove_unused_layers no)
			(net "FAN_2_PWM_IL_R")
			(clearance 0.0508)
			(thermal_gap 0.0508)
		)
		(pad "4" thru_hole circle
			(at -1.999996 1.999996 270)
			(size 1.3716 1.3716)
			(drill 0.9652)
			(layers "*.Cu" "*.Mask")
			(remove_unused_layers no)
			(net "FAN_2_PRESENT_R_N")
			(clearance 0.0508)
			(thermal_gap 0.0508)
		)
		(pad "5" thru_hole circle
			(at 0 3.999992 270)
			(size 1.3716 1.3716)
			(drill 0.9652)
			(layers "*.Cu" "*.Mask")
			(remove_unused_layers no)
			(net "P12V_LED_R1_FAN2")
			(clearance 0.0508)
			(thermal_gap 0.0508)
		)
		(pad "6" thru_hole circle
			(at -1.999996 3.999992 270)
			(size 1.3716 1.3716)
			(drill 0.9652)
			(layers "*.Cu" "*.Mask")
			(remove_unused_layers no)
			(net "SMB_FAN2_SCL_R")
			(clearance 0.0508)
			(thermal_gap 0.0508)
		)
		(pad "7" thru_hole circle
			(at 0 5.999988 270)
			(size 1.3716 1.3716)
			(drill 0.9652)
			(layers "*.Cu" "*.Mask")
			(remove_unused_layers no)
			(net "SMB_FAN2_SDA_R")
			(clearance 0.0508)
			(thermal_gap 0.0508)
		)
		(pad "8" thru_hole circle
			(at -1.999996 5.999988 270)
			(size 1.3716 1.3716)
			(drill 0.9652)
			(layers "*.Cu" "*.Mask")
			(remove_unused_layers no)
			(net "GND")
			(clearance 0.0508)
			(thermal_gap 0.0508)
		)
		(pad "9" thru_hole circle
			(at 0 7.999984 270)
			(size 1.3716 1.3716)
			(drill 0.9652)
			(layers "*.Cu" "*.Mask")
			(remove_unused_layers no)
			(net "GND")
			(clearance 0.0508)
			(thermal_gap 0.0508)
		)
		(pad "10" thru_hole circle
			(at -1.999996 7.999984 270)
			(size 1.3716 1.3716)
			(drill 0.9652)
			(layers "*.Cu" "*.Mask")
			(remove_unused_layers no)
			(net "P52V_FAN_2")
			(clearance 0.0508)
			(thermal_gap 0.0508)
		)
		(pad "11" thru_hole circle
			(at 0 9.99998 270)
			(size 1.3716 1.3716)
			(drill 0.9652)
			(layers "*.Cu" "*.Mask")
			(remove_unused_layers no)
			(net "P52V_FAN_2")
			(clearance 0.0508)
			(thermal_gap 0.0508)
		)
		(pad "12" thru_hole circle
			(at -1.999996 9.99998 270)
			(size 1.3716 1.3716)
			(drill 0.9652)
			(layers "*.Cu" "*.Mask")
			(remove_unused_layers no)
			(net "FAN_2_FAIL_R_LED_N")
			(clearance 0.0508)
			(thermal_gap 0.0508)
		)
		(pad "13" thru_hole circle
			(at 0 11.999976 270)
			(size 1.3716 1.3716)
			(drill 0.9652)
			(layers "*.Cu" "*.Mask")
			(remove_unused_layers no)
			(net "FAN_2_TACH_OL_D")
			(clearance 0.0508)
			(thermal_gap 0.0508)
		)
		(pad "14" thru_hole circle
			(at -1.999996 11.999976 270)
			(size 1.3716 1.3716)
			(drill 0.9652)
			(layers "*.Cu" "*.Mask")
			(remove_unused_layers no)
			(net "FAN_2_OK_R_LED_N")
			(clearance 0.0508)
			(thermal_gap 0.0508)
		)
		(pad "15" thru_hole circle
			(at 0 13.999972 270)
			(size 1.3716 1.3716)
			(drill 0.9652)
			(layers "*.Cu" "*.Mask")
			(remove_unused_layers no)
			(net "Net_612")
			(clearance 0.0508)
			(thermal_gap 0.0508)
		)
		(pad "16" thru_hole circle
			(at -1.999996 13.999972 270)
			(size 1.3716 1.3716)
			(drill 0.9652)
			(layers "*.Cu" "*.Mask")
			(remove_unused_layers no)
			(net "Net_611")
			(clearance 0.0508)
			(thermal_gap 0.0508)
		)
		(zone
			(layers "F.Cu" "B.Cu" "In1.Cu" "In2.Cu" "In3.Cu" "In4.Cu")
			(hatch none 0.5)
			(connect_pads
				(clearance 0)
			)
			(min_thickness 0.25)
			(keepout
				(tracks not_allowed)
				(vias allowed)
				(pads allowed)
				(copperpour not_allowed)
				(footprints allowed)
			)
			(placement
				(enabled no)
				(sheetname "")
			)
			(fill
				(thermal_gap 0.5)
				(thermal_bridge_width 0.5)
				(island_removal_mode 0)
			)
			(polygon
				(pts
					(arc
						(start 45.257212 -120.609868)
						(mid 42.742612 -120.609868)
						(end 45.257212 -120.609868)
					)
				)
			)
		)
	)
	(footprint ""
		(layer "B.Cu")
		(at 33.142428 -263.017 -90)
		(property "Reference" "PD3"
			(at 4.699 3.832098 270)
			(unlocked yes)
			(layer "B.SilkS")
			(effects
				(font
					(size 0.7874 0.5842)
					(thickness 0.1524)
				)
				(justify left mirror)
			)
		)
		(property "Value" ""
			(at 0 0 90)
			(layer "B.Fab")
			(effects
				(font
					(size 1.27 1.27)
				)
				(justify mirror)
			)
		)
		(duplicate_pad_numbers_are_jumpers no)
		(fp_line
			(start -5.536184 3.109976)
			(end -5.536184 -3.109976)
			(stroke
				(width 0.1524)
				(type default)
			)
			(layer "B.SilkS")
		)
		(fp_line
			(start 4.647184 3.109976)
			(end -5.536184 3.109976)
			(stroke
				(width 0.1524)
				(type default)
			)
			(layer "B.SilkS")
		)
		(fp_line
			(start 0.635 0.635)
			(end -0.635 -0.127)
			(stroke
				(width 0.1524)
				(type default)
			)
			(layer "B.SilkS")
		)
		(fp_line
			(start -0.635 -0.127)
			(end -1.397 -0.127)
			(stroke
				(width 0.1524)
				(type default)
			)
			(layer "B.SilkS")
		)
		(fp_line
			(start -0.635 -0.127)
			(end 0.635 -0.889)
			(stroke
				(width 0.1524)
				(type default)
			)
			(layer "B.SilkS")
		)
		(fp_line
			(start 1.397 -0.127)
			(end 0.635 -0.127)
			(stroke
				(width 0.1524)
				(type default)
			)
			(layer "B.SilkS")
		)
		(fp_line
			(start 0.635 -0.889)
			(end 0.635 0.635)
			(stroke
				(width 0.1524)
				(type default)
			)
			(layer "B.SilkS")
		)
		(fp_line
			(start -0.762 -1.143)
			(end -0.762 0.889)
			(stroke
				(width 0.1524)
				(type default)
			)
			(layer "B.SilkS")
		)
		(fp_line
			(start -5.536184 -3.109976)
			(end 4.647184 -3.109976)
			(stroke
				(width 0.1524)
				(type default)
			)
			(layer "B.SilkS")
		)
		(fp_line
			(start 4.647184 -3.109976)
			(end 4.647184 3.109976)
			(stroke
				(width 0.1524)
				(type default)
			)
			(layer "B.SilkS")
		)
		(fp_poly
			(pts
				(xy -5.5118 -3.0988) (xy -5.5118 3.1496) (xy -4.572 3.1496) (xy -4.572 -3.0988)
			)
			(stroke
				(width 0)
				(type default)
			)
			(fill yes)
			(layer "B.SilkS")
		)
		(fp_line
			(start -3.554984 3.109976)
			(end -3.554984 -3.109976)
			(stroke
				(width 0.1)
				(type default)
			)
			(layer "B.Fab")
		)
		(fp_line
			(start 3.554984 3.109976)
			(end -3.554984 3.109976)
			(stroke
				(width 0.1)
				(type default)
			)
			(layer "B.Fab")
		)
		(fp_line
			(start -3.554984 -3.109976)
			(end 3.554984 -3.109976)
			(stroke
				(width 0.1)
				(type default)
			)
			(layer "B.Fab")
		)
		(fp_line
			(start 3.554984 -3.109976)
			(end 3.554984 3.109976)
			(stroke
				(width 0.1)
				(type default)
			)
			(layer "B.Fab")
		)
		(fp_text user "+"
			(at 6.096 1.805178 270)
			(unlocked yes)
			(layer "B.SilkS")
			(effects
				(font
					(size 1.905 1.4224)
					(thickness 0.1524)
				)
				(justify left mirror)
			)
		)
		(fp_text user "-"
			(at -5.334 -0.34925 270)
			(unlocked yes)
			(layer "B.SilkS")
			(effects
				(font
					(size 1.905 1.4224)
					(thickness 0.1524)
				)
				(justify left mirror)
			)
		)
		(fp_text user "+"
			(at 6.1214 -0.32385 270)
			(unlocked yes)
			(layer "B.Fab")
			(effects
				(font
					(size 1.905 1.4224)
					(thickness 0.1524)
				)
				(justify left mirror)
			)
		)
		(fp_text user "-"
			(at -5.334 -0.34925 270)
			(unlocked yes)
			(layer "B.Fab")
			(effects
				(font
					(size 1.905 1.4224)
					(thickness 0.1524)
				)
				(justify left mirror)
			)
		)
		(pad "A" smd rect
			(at 3.299968 0 90)
			(size 2.413 3.302)
			(layers "B.Cu" "B.Mask" "B.Paste")
			(net "GND")
		)
		(pad "C" smd rect
			(at -3.299968 0 90)
			(size 2.413 3.302)
			(layers "B.Cu" "B.Mask" "B.Paste")
			(net "P52V_HSC")
		)
	)
	(footprint ""
		(layer "B.Cu")
		(at 16.782796 -274.764754 180)
		(property "Reference" "C2119"
			(at 0 0 0)
			(layer "B.SilkS")
			(hide yes)
			(effects
				(font
					(size 1.27 1.27)
				)
				(justify mirror)
			)
		)
		(property "Value" ""
			(at 0 0 0)
			(layer "B.Fab")
			(effects
				(font
					(size 1.27 1.27)
				)
				(justify mirror)
			)
		)
		(duplicate_pad_numbers_are_jumpers no)
		(fp_line
			(start 2.2098 0.9398)
			(end 2.2098 -0.9398)
			(stroke
				(width 0.1524)
				(type default)
			)
			(layer "B.SilkS")
		)
		(fp_line
			(start 2.2098 -0.9398)
			(end -2.2098 -0.9398)
			(stroke
				(width 0.1524)
				(type default)
			)
			(layer "B.SilkS")
		)
		(fp_line
			(start -2.2098 0.9398)
			(end 2.2098 0.9398)
			(stroke
				(width 0.1524)
				(type default)
			)
			(layer "B.SilkS")
		)
		(fp_line
			(start -2.2098 -0.9398)
			(end -2.2098 0.9398)
			(stroke
				(width 0.1524)
				(type default)
			)
			(layer "B.SilkS")
		)
		(fp_line
			(start 1.700022 0.899922)
			(end 1.700022 -0.899922)
			(stroke
				(width 0.1)
				(type default)
			)
			(layer "B.Fab")
		)
		(fp_line
			(start 1.700022 -0.899922)
			(end -1.700022 -0.899922)
			(stroke
				(width 0.1)
				(type default)
			)
			(layer "B.Fab")
		)
		(fp_line
			(start -1.700022 0.899922)
			(end 1.700022 0.899922)
			(stroke
				(width 0.1)
				(type default)
			)
			(layer "B.Fab")
		)
		(fp_line
			(start -1.700022 -0.899922)
			(end -1.700022 0.899922)
			(stroke
				(width 0.1)
				(type default)
			)
			(layer "B.Fab")
		)
		(pad "1" smd rect
			(at 1.4732 0 180)
			(size 1.1684 1.5748)
			(layers "B.Cu" "B.Mask" "B.Paste")
			(net "P52V_FAN_7")
		)
		(pad "2" smd rect
			(at -1.4732 0 180)
			(size 1.1684 1.5748)
			(layers "B.Cu" "B.Mask" "B.Paste")
			(net "GND")
		)
	)
	(footprint ""
		(layer "B.Cu")
		(at 6.108954 -50.877724)
		(property "Reference" "C2108"
			(at 0 0 0)
			(layer "B.SilkS")
			(hide yes)
			(effects
				(font
					(size 1.27 1.27)
				)
				(justify mirror)
			)
		)
		(property "Value" ""
			(at 0 0 0)
			(layer "B.Fab")
			(effects
				(font
					(size 1.27 1.27)
				)
				(justify mirror)
			)
		)
		(duplicate_pad_numbers_are_jumpers no)
		(fp_line
			(start -2.2098 -0.9398)
			(end -2.2098 0.9398)
			(stroke
				(width 0.1524)
				(type default)
			)
			(layer "B.SilkS")
		)
		(fp_line
			(start -2.2098 0.9398)
			(end 2.2098 0.9398)
			(stroke
				(width 0.1524)
				(type default)
			)
			(layer "B.SilkS")
		)
		(fp_line
			(start 2.2098 -0.9398)
			(end -2.2098 -0.9398)
			(stroke
				(width 0.1524)
				(type default)
			)
			(layer "B.SilkS")
		)
		(fp_line
			(start 2.2098 0.9398)
			(end 2.2098 -0.9398)
			(stroke
				(width 0.1524)
				(type default)
			)
			(layer "B.SilkS")
		)
		(fp_line
			(start -1.700022 -0.899922)
			(end -1.700022 0.899922)
			(stroke
				(width 0.1)
				(type default)
			)
			(layer "B.Fab")
		)
		(fp_line
			(start -1.700022 0.899922)
			(end 1.700022 0.899922)
			(stroke
				(width 0.1)
				(type default)
			)
			(layer "B.Fab")
		)
		(fp_line
			(start 1.700022 -0.899922)
			(end -1.700022 -0.899922)
			(stroke
				(width 0.1)
				(type default)
			)
			(layer "B.Fab")
		)
		(fp_line
			(start 1.700022 0.899922)
			(end 1.700022 -0.899922)
			(stroke
				(width 0.1)
				(type default)
			)
			(layer "B.Fab")
		)
		(pad "1" smd rect
			(at 1.4732 0)
			(size 1.1684 1.5748)
			(layers "B.Cu" "B.Mask" "B.Paste")
			(net "P52V_FAN_4")
		)
		(pad "2" smd rect
			(at -1.4732 0)
			(size 1.1684 1.5748)
			(layers "B.Cu" "B.Mask" "B.Paste")
			(net "GND")
		)
	)
	(footprint ""
		(layer "B.Cu")
		(at 47.498 -73.971912 90)
		(property "Reference" "PR38"
			(at 0 0 90)
			(layer "B.SilkS")
			(hide yes)
			(effects
				(font
					(size 1.27 1.27)
				)
				(justify mirror)
			)
		)
		(property "Value" ""
			(at 0 0 90)
			(layer "B.Fab")
			(effects
				(font
					(size 1.27 1.27)
				)
				(justify mirror)
			)
		)
		(duplicate_pad_numbers_are_jumpers no)
		(fp_line
			(start 0.7874 -0.4064)
			(end -0.7874 -0.4064)
			(stroke
				(width 0.1524)
				(type default)
			)
			(layer "B.SilkS")
		)
		(fp_line
			(start -0.7874 -0.4064)
			(end -0.7874 0.4064)
			(stroke
				(width 0.1524)
				(type default)
			)
			(layer "B.SilkS")
		)
		(fp_line
			(start 0.7874 0.4064)
			(end 0.7874 -0.4064)
			(stroke
				(width 0.1524)
				(type default)
			)
			(layer "B.SilkS")
		)
		(fp_line
			(start -0.7874 0.4064)
			(end 0.7874 0.4064)
			(stroke
				(width 0.1524)
				(type default)
			)
			(layer "B.SilkS")
		)
		(fp_line
			(start 0.67945 -0.305054)
			(end 0.12065 -0.305054)
			(stroke
				(width 0.1)
				(type default)
			)
			(layer "B.Fab")
		)
		(fp_line
			(start 0.12065 -0.305054)
			(end 0.12065 -0.2794)
			(stroke
				(width 0.1)
				(type default)
			)
			(layer "B.Fab")
		)
		(fp_line
			(start -0.12065 -0.3048)
			(end -0.67945 -0.3048)
			(stroke
				(width 0.1)
				(type default)
			)
			(layer "B.Fab")
		)
		(fp_line
			(start -0.67945 -0.3048)
			(end -0.67945 0.3048)
			(stroke
				(width 0.1)
				(type default)
			)
			(layer "B.Fab")
		)
		(fp_line
			(start 0.12065 -0.2794)
			(end -0.12065 -0.2794)
			(stroke
				(width 0.1)
				(type default)
			)
			(layer "B.Fab")
		)
		(fp_line
			(start -0.12065 -0.2794)
			(end -0.12065 -0.3048)
			(stroke
				(width 0.1)
				(type default)
			)
			(layer "B.Fab")
		)
		(fp_line
			(start 0.12065 0.2794)
			(end 0.12065 0.3048)
			(stroke
				(width 0.1)
				(type default)
			)
			(layer "B.Fab")
		)
		(fp_line
			(start -0.120396 0.2794)
			(end 0.12065 0.2794)
			(stroke
				(width 0.1)
				(type default)
			)
			(layer "B.Fab")
		)
		(fp_line
			(start 0.67945 0.3048)
			(end 0.67945 -0.305054)
			(stroke
				(width 0.1)
				(type default)
			)
			(layer "B.Fab")
		)
		(fp_line
			(start 0.12065 0.3048)
			(end 0.67945 0.3048)
			(stroke
				(width 0.1)
				(type default)
			)
			(layer "B.Fab")
		)
		(fp_line
			(start -0.120396 0.3048)
			(end -0.120396 0.2794)
			(stroke
				(width 0.1)
				(type default)
			)
			(layer "B.Fab")
		)
		(fp_line
			(start -0.67945 0.3048)
			(end -0.120396 0.3048)
			(stroke
				(width 0.1)
				(type default)
			)
			(layer "B.Fab")
		)
		(pad "1" smd circle
			(at 0.40005 0 270)
			(size 0 0)
			(layers "B.Cu" "B.Mask" "B.Paste")
			(net "FAN_2_CS")
		)
		(pad "2" smd circle
			(at -0.40005 0 270)
			(size 0 0)
			(layers "B.Cu" "B.Mask" "B.Paste")
			(net "GND")
		)
	)
	(footprint ""
		(layer "B.Cu")
		(at 7.947914 -67.494912 180)
		(property "Reference" "U359"
			(at -0.053086 1.820418 0)
			(unlocked yes)
			(layer "B.SilkS")
			(effects
				(font
					(size 0.7874 0.5842)
					(thickness 0.1524)
				)
				(justify mirror)
			)
		)
		(property "Value" ""
			(at 0 0 0)
			(layer "B.Fab")
			(effects
				(font
					(size 1.27 1.27)
				)
				(justify mirror)
			)
		)
		(duplicate_pad_numbers_are_jumpers no)
		(fp_line
			(start 1.7018 1.1176)
			(end 1.7018 -1.1176)
			(stroke
				(width 0.1524)
				(type default)
			)
			(layer "B.SilkS")
		)
		(fp_line
			(start 0.254 -1.1176)
			(end 1.7018 -1.1176)
			(stroke
				(width 0.1524)
				(type default)
			)
			(layer "B.SilkS")
		)
		(fp_line
			(start 0 -0.7112)
			(end 0.254 -1.1176)
			(stroke
				(width 0.1524)
				(type default)
			)
			(layer "B.SilkS")
		)
		(fp_line
			(start -0.254 -1.1176)
			(end 0 -0.7112)
			(stroke
				(width 0.1524)
				(type default)
			)
			(layer "B.SilkS")
		)
		(fp_line
			(start -1.7018 1.1176)
			(end 1.7018 1.1176)
			(stroke
				(width 0.1524)
				(type default)
			)
			(layer "B.SilkS")
		)
		(fp_line
			(start -1.7018 -1.1176)
			(end -0.254 -1.1176)
			(stroke
				(width 0.1524)
				(type default)
			)
			(layer "B.SilkS")
		)
		(fp_line
			(start -1.7018 -1.1176)
			(end -1.7018 1.1176)
			(stroke
				(width 0.1524)
				(type default)
			)
			(layer "B.SilkS")
		)
		(fp_poly
			(pts
				(xy 1.8161 -0.802386) (xy 2.4003 -0.573786) (xy 2.4003 -1.005586)
			)
			(stroke
				(width 0)
				(type default)
			)
			(fill yes)
			(layer "B.SilkS")
		)
		(fp_line
			(start 1.5494 1.1176)
			(end 1.5494 -1.1176)
			(stroke
				(width 0.1)
				(type default)
			)
			(layer "B.Fab")
		)
		(fp_line
			(start 0.254 -1.1176)
			(end 1.5494 -1.1176)
			(stroke
				(width 0.1)
				(type default)
			)
			(layer "B.Fab")
		)
		(fp_line
			(start -0.254 -1.1176)
			(end 0.254 -1.1176)
			(stroke
				(width 0.1)
				(type default)
			)
			(layer "B.Fab")
		)
		(fp_line
			(start -1.5494 1.1176)
			(end 1.5494 1.1176)
			(stroke
				(width 0.1)
				(type default)
			)
			(layer "B.Fab")
		)
		(fp_line
			(start -1.5494 -1.1176)
			(end -0.254 -1.1176)
			(stroke
				(width 0.1)
				(type default)
			)
			(layer "B.Fab")
		)
		(fp_line
			(start -1.5494 -1.1176)
			(end -1.5494 1.1176)
			(stroke
				(width 0.1)
				(type default)
			)
			(layer "B.Fab")
		)
		(fp_poly
			(pts
				(xy 1.8161 -0.675386) (xy 2.4003 -0.446786) (xy 2.4003 -0.878586)
			)
			(stroke
				(width 0)
				(type default)
			)
			(fill yes)
			(layer "B.Fab")
		)
		(pad "1" smd rect
			(at 0.962406 -0.649986 90)
			(size 0.3302 1.1684)
			(layers "B.Cu" "B.Mask" "B.Paste")
			(net "FAN_4_PRESENT_R")
		)
		(pad "2" smd rect
			(at 0.962406 0 90)
			(size 0.3302 1.1684)
			(layers "B.Cu" "B.Mask" "B.Paste")
			(net "P52V_FAN_4_BUFF_EN_R")
		)
		(pad "3" smd rect
			(at 0.962406 0.649986 90)
			(size 0.3302 1.1684)
			(layers "B.Cu" "B.Mask" "B.Paste")
			(net "GND")
		)
		(pad "4" smd rect
			(at -0.962406 0.649986 90)
			(size 0.3302 1.1684)
			(layers "B.Cu" "B.Mask" "B.Paste")
			(net "P52V_FAN_4_EN")
		)
		(pad "5" smd rect
			(at -0.962406 -0.649986 90)
			(size 0.3302 1.1684)
			(layers "B.Cu" "B.Mask" "B.Paste")
			(net "P3V3_AUX")
		)
	)
	(footprint ""
		(layer "B.Cu")
		(at 1.778 -64.827912 -90)
		(property "Reference" "PR50"
			(at 0 0 90)
			(layer "B.SilkS")
			(hide yes)
			(effects
				(font
					(size 1.27 1.27)
				)
				(justify mirror)
			)
		)
		(property "Value" ""
			(at 0 0 90)
			(layer "B.Fab")
			(effects
				(font
					(size 1.27 1.27)
				)
				(justify mirror)
			)
		)
		(duplicate_pad_numbers_are_jumpers no)
		(fp_line
			(start -0.7874 0.4064)
			(end 0.7874 0.4064)
			(stroke
				(width 0.1524)
				(type default)
			)
			(layer "B.SilkS")
		)
		(fp_line
			(start 0.7874 0.4064)
			(end 0.7874 -0.4064)
			(stroke
				(width 0.1524)
				(type default)
			)
			(layer "B.SilkS")
		)
		(fp_line
			(start -0.7874 -0.4064)
			(end -0.7874 0.4064)
			(stroke
				(width 0.1524)
				(type default)
			)
			(layer "B.SilkS")
		)
		(fp_line
			(start 0.7874 -0.4064)
			(end -0.7874 -0.4064)
			(stroke
				(width 0.1524)
				(type default)
			)
			(layer "B.SilkS")
		)
		(fp_line
			(start -0.67945 0.3048)
			(end -0.120396 0.3048)
			(stroke
				(width 0.1)
				(type default)
			)
			(layer "B.Fab")
		)
		(fp_line
			(start -0.120396 0.3048)
			(end -0.120396 0.2794)
			(stroke
				(width 0.1)
				(type default)
			)
			(layer "B.Fab")
		)
		(fp_line
			(start 0.12065 0.3048)
			(end 0.67945 0.3048)
			(stroke
				(width 0.1)
				(type default)
			)
			(layer "B.Fab")
		)
		(fp_line
			(start 0.67945 0.3048)
			(end 0.67945 -0.305054)
			(stroke
				(width 0.1)
				(type default)
			)
			(layer "B.Fab")
		)
		(fp_line
			(start -0.120396 0.2794)
			(end 0.12065 0.2794)
			(stroke
				(width 0.1)
				(type default)
			)
			(layer "B.Fab")
		)
		(fp_line
			(start 0.12065 0.2794)
			(end 0.12065 0.3048)
			(stroke
				(width 0.1)
				(type default)
			)
			(layer "B.Fab")
		)
		(fp_line
			(start -0.12065 -0.2794)
			(end -0.12065 -0.3048)
			(stroke
				(width 0.1)
				(type default)
			)
			(layer "B.Fab")
		)
		(fp_line
			(start 0.12065 -0.2794)
			(end -0.12065 -0.2794)
			(stroke
				(width 0.1)
				(type default)
			)
			(layer "B.Fab")
		)
		(fp_line
			(start -0.67945 -0.3048)
			(end -0.67945 0.3048)
			(stroke
				(width 0.1)
				(type default)
			)
			(layer "B.Fab")
		)
		(fp_line
			(start -0.12065 -0.3048)
			(end -0.67945 -0.3048)
			(stroke
				(width 0.1)
				(type default)
			)
			(layer "B.Fab")
		)
		(fp_line
			(start 0.12065 -0.305054)
			(end 0.12065 -0.2794)
			(stroke
				(width 0.1)
				(type default)
			)
			(layer "B.Fab")
		)
		(fp_line
			(start 0.67945 -0.305054)
			(end 0.12065 -0.305054)
			(stroke
				(width 0.1)
				(type default)
			)
			(layer "B.Fab")
		)
		(pad "1" smd circle
			(at 0.40005 0 90)
			(size 0 0)
			(layers "B.Cu" "B.Mask" "B.Paste")
			(net "FAN_4_CS")
		)
		(pad "2" smd circle
			(at -0.40005 0 90)
			(size 0 0)
			(layers "B.Cu" "B.Mask" "B.Paste")
			(net "GND")
		)
	)
	(footprint ""
		(layer "B.Cu")
		(at -6.938772 -296.164 180)
		(property "Reference" "J85"
			(at 1.316228 -5.48767 0)
			(unlocked yes)
			(layer "B.SilkS")
			(effects
				(font
					(size 0.7874 0.5842)
					(thickness 0.1524)
				)
				(justify left mirror)
			)
		)
		(property "Value" ""
			(at 0 0 0)
			(layer "B.Fab")
			(effects
				(font
					(size 1.27 1.27)
				)
				(justify mirror)
			)
		)
		(duplicate_pad_numbers_are_jumpers no)
		(fp_line
			(start 3.330702 -4.771136)
			(end -3.330702 -4.771136)
			(stroke
				(width 0.1524)
				(type default)
			)
			(layer "B.SilkS")
		)
		(fp_line
			(start 0 4.011168)
			(end 3.330702 -4.771136)
			(stroke
				(width 0.1524)
				(type default)
			)
			(layer "B.SilkS")
		)
		(fp_line
			(start -3.330702 -4.771136)
			(end 0 4.011168)
			(stroke
				(width 0.1524)
				(type default)
			)
			(layer "B.SilkS")
		)
		(fp_line
			(start 3.330702 -4.771136)
			(end -3.330702 -4.771136)
			(stroke
				(width 0.1)
				(type default)
			)
			(layer "B.Fab")
		)
		(fp_line
			(start 0 4.011168)
			(end 3.330702 -4.771136)
			(stroke
				(width 0.1)
				(type default)
			)
			(layer "B.Fab")
		)
		(fp_line
			(start -3.330702 -4.771136)
			(end 0 4.011168)
			(stroke
				(width 0.1)
				(type default)
			)
			(layer "B.Fab")
		)
		(pad "1" thru_hole circle
			(at 0 0)
			(size 2.159 2.159)
			(drill 1.7018)
			(layers "*.Cu" "*.Mask")
			(remove_unused_layers no)
			(net "GND2")
			(clearance 0.0254)
			(thermal_gap 0.0254)
		)
		(pad "2" thru_hole circle
			(at 1.27 -3.348736)
			(size 2.159 2.159)
			(drill 1.7018)
			(layers "*.Cu" "*.Mask")
			(remove_unused_layers no)
			(net "TDR_SE_50_OHM_IN2")
			(clearance 0.0254)
			(thermal_gap 0.0254)
		)
		(pad "3" thru_hole circle
			(at -1.27 -3.348736)
			(size 2.159 2.159)
			(drill 1.7018)
			(layers "*.Cu" "*.Mask")
			(remove_unused_layers no)
			(net "TDR_SE_50_OHM_IN2")
			(clearance 0.0254)
			(thermal_gap 0.0254)
		)
	)
	(footprint ""
		(layer "B.Cu")
		(at 5.08 -313.182 180)
		(property "Reference" "C2127"
			(at 0 0 0)
			(layer "B.SilkS")
			(hide yes)
			(effects
				(font
					(size 1.27 1.27)
				)
				(justify mirror)
			)
		)
		(property "Value" ""
			(at 0 0 0)
			(layer "B.Fab")
			(effects
				(font
					(size 1.27 1.27)
				)
				(justify mirror)
			)
		)
		(duplicate_pad_numbers_are_jumpers no)
		(fp_line
			(start 1.2954 0.5842)
			(end 1.2954 -0.5842)
			(stroke
				(width 0.1524)
				(type default)
			)
			(layer "B.SilkS")
		)
		(fp_line
			(start 1.2954 -0.5842)
			(end -1.2954 -0.5842)
			(stroke
				(width 0.1524)
				(type default)
			)
			(layer "B.SilkS")
		)
		(fp_line
			(start -1.2954 0.5842)
			(end 1.2954 0.5842)
			(stroke
				(width 0.1524)
				(type default)
			)
			(layer "B.SilkS")
		)
		(fp_line
			(start -1.2954 -0.5842)
			(end -1.2954 0.5842)
			(stroke
				(width 0.1524)
				(type default)
			)
			(layer "B.SilkS")
		)
		(fp_line
			(start 1.1938 0.4064)
			(end 1.1938 -0.4064)
			(stroke
				(width 0.1)
				(type default)
			)
			(layer "B.Fab")
		)
		(fp_line
			(start 1.1938 -0.4064)
			(end 0.8636 -0.4064)
			(stroke
				(width 0.1)
				(type default)
			)
			(layer "B.Fab")
		)
		(fp_line
			(start 0.8636 0.4572)
			(end 0.8636 0.4064)
			(stroke
				(width 0.1)
				(type default)
			)
			(layer "B.Fab")
		)
		(fp_line
			(start 0.8636 0.4064)
			(end 1.1938 0.4064)
			(stroke
				(width 0.1)
				(type default)
			)
			(layer "B.Fab")
		)
		(fp_line
			(start 0.8636 -0.4064)
			(end 0.8636 -0.4572)
			(stroke
				(width 0.1)
				(type default)
			)
			(layer "B.Fab")
		)
		(fp_line
			(start 0.8636 -0.4572)
			(end -0.8636 -0.4572)
			(stroke
				(width 0.1)
				(type default)
			)
			(layer "B.Fab")
		)
		(fp_line
			(start -0.8636 0.4572)
			(end 0.8636 0.4572)
			(stroke
				(width 0.1)
				(type default)
			)
			(layer "B.Fab")
		)
		(fp_line
			(start -0.8636 0.4064)
			(end -0.8636 0.4572)
			(stroke
				(width 0.1)
				(type default)
			)
			(layer "B.Fab")
		)
		(fp_line
			(start -0.8636 -0.4064)
			(end -1.1938 -0.4064)
			(stroke
				(width 0.1)
				(type default)
			)
			(layer "B.Fab")
		)
		(fp_line
			(start -0.8636 -0.4572)
			(end -0.8636 -0.4064)
			(stroke
				(width 0.1)
				(type default)
			)
			(layer "B.Fab")
		)
		(fp_line
			(start -1.1938 0.4064)
			(end -0.8636 0.4064)
			(stroke
				(width 0.1)
				(type default)
			)
			(layer "B.Fab")
		)
		(fp_line
			(start -1.1938 -0.4064)
			(end -1.1938 0.4064)
			(stroke
				(width 0.1)
				(type default)
			)
			(layer "B.Fab")
		)
		(pad "1" smd rect
			(at 0.7366 0 90)
			(size 0.7112 0.8128)
			(layers "B.Cu" "B.Mask" "B.Paste")
			(net "U412_D1")
		)
		(pad "2" smd rect
			(at -0.7366 0 90)
			(size 0.7112 0.8128)
			(layers "B.Cu" "B.Mask" "B.Paste")
			(net "GND")
		)
	)
	(footprint ""
		(layer "B.Cu")
		(at 9.922002 -167.771826 180)
		(property "Reference" "C53"
			(at 0 0 0)
			(layer "B.SilkS")
			(hide yes)
			(effects
				(font
					(size 1.27 1.27)
				)
				(justify mirror)
			)
		)
		(property "Value" ""
			(at 0 0 0)
			(layer "B.Fab")
			(effects
				(font
					(size 1.27 1.27)
				)
				(justify mirror)
			)
		)
		(duplicate_pad_numbers_are_jumpers no)
		(fp_line
			(start 0.7874 0.4064)
			(end 0.7874 -0.4064)
			(stroke
				(width 0.1524)
				(type default)
			)
			(layer "B.SilkS")
		)
		(fp_line
			(start 0.7874 -0.4064)
			(end -0.7874 -0.4064)
			(stroke
				(width 0.1524)
				(type default)
			)
			(layer "B.SilkS")
		)
		(fp_line
			(start -0.7874 0.4064)
			(end 0.7874 0.4064)
			(stroke
				(width 0.1524)
				(type default)
			)
			(layer "B.SilkS")
		)
		(fp_line
			(start -0.7874 -0.4064)
			(end -0.7874 0.4064)
			(stroke
				(width 0.1524)
				(type default)
			)
			(layer "B.SilkS")
		)
		(fp_line
			(start 0.67945 0.3048)
			(end 0.67945 -0.305054)
			(stroke
				(width 0.1)
				(type default)
			)
			(layer "B.Fab")
		)
		(fp_line
			(start 0.67945 -0.305054)
			(end 0.12065 -0.305054)
			(stroke
				(width 0.1)
				(type default)
			)
			(layer "B.Fab")
		)
		(fp_line
			(start 0.12065 0.3048)
			(end 0.67945 0.3048)
			(stroke
				(width 0.1)
				(type default)
			)
			(layer "B.Fab")
		)
		(fp_line
			(start 0.12065 0.2794)
			(end 0.12065 0.3048)
			(stroke
				(width 0.1)
				(type default)
			)
			(layer "B.Fab")
		)
		(fp_line
			(start 0.12065 -0.2794)
			(end -0.12065 -0.2794)
			(stroke
				(width 0.1)
				(type default)
			)
			(layer "B.Fab")
		)
		(fp_line
			(start 0.12065 -0.305054)
			(end 0.12065 -0.2794)
			(stroke
				(width 0.1)
				(type default)
			)
			(layer "B.Fab")
		)
		(fp_line
			(start -0.120396 0.3048)
			(end -0.120396 0.2794)
			(stroke
				(width 0.1)
				(type default)
			)
			(layer "B.Fab")
		)
		(fp_line
			(start -0.120396 0.2794)
			(end 0.12065 0.2794)
			(stroke
				(width 0.1)
				(type default)
			)
			(layer "B.Fab")
		)
		(fp_line
			(start -0.12065 -0.2794)
			(end -0.12065 -0.3048)
			(stroke
				(width 0.1)
				(type default)
			)
			(layer "B.Fab")
		)
		(fp_line
			(start -0.12065 -0.3048)
			(end -0.67945 -0.3048)
			(stroke
				(width 0.1)
				(type default)
			)
			(layer "B.Fab")
		)
		(fp_line
			(start -0.67945 0.3048)
			(end -0.120396 0.3048)
			(stroke
				(width 0.1)
				(type default)
			)
			(layer "B.Fab")
		)
		(fp_line
			(start -0.67945 -0.3048)
			(end -0.67945 0.3048)
			(stroke
				(width 0.1)
				(type default)
			)
			(layer "B.Fab")
		)
		(pad "1" smd circle
			(at 0.40005 0)
			(size 0 0)
			(layers "B.Cu" "B.Mask" "B.Paste")
			(net "P3V3_AUX")
		)
		(pad "2" smd circle
			(at -0.40005 0)
			(size 0 0)
			(layers "B.Cu" "B.Mask" "B.Paste")
			(net "GND")
		)
	)
	(footprint ""
		(layer "B.Cu")
		(at 32.131 -250.23699 -90)
		(property "Reference" "PR30"
			(at 0 0 90)
			(layer "B.SilkS")
			(hide yes)
			(effects
				(font
					(size 1.27 1.27)
				)
				(justify mirror)
			)
		)
		(property "Value" ""
			(at 0 0 90)
			(layer "B.Fab")
			(effects
				(font
					(size 1.27 1.27)
				)
				(justify mirror)
			)
		)
		(duplicate_pad_numbers_are_jumpers no)
		(fp_line
			(start -0.7874 0.4064)
			(end 0.7874 0.4064)
			(stroke
				(width 0.1524)
				(type default)
			)
			(layer "B.SilkS")
		)
		(fp_line
			(start 0.7874 0.4064)
			(end 0.7874 -0.4064)
			(stroke
				(width 0.1524)
				(type default)
			)
			(layer "B.SilkS")
		)
		(fp_line
			(start -0.7874 -0.4064)
			(end -0.7874 0.4064)
			(stroke
				(width 0.1524)
				(type default)
			)
			(layer "B.SilkS")
		)
		(fp_line
			(start 0.7874 -0.4064)
			(end -0.7874 -0.4064)
			(stroke
				(width 0.1524)
				(type default)
			)
			(layer "B.SilkS")
		)
		(fp_line
			(start -0.67945 0.3048)
			(end -0.120396 0.3048)
			(stroke
				(width 0.1)
				(type default)
			)
			(layer "B.Fab")
		)
		(fp_line
			(start -0.120396 0.3048)
			(end -0.120396 0.2794)
			(stroke
				(width 0.1)
				(type default)
			)
			(layer "B.Fab")
		)
		(fp_line
			(start 0.12065 0.3048)
			(end 0.67945 0.3048)
			(stroke
				(width 0.1)
				(type default)
			)
			(layer "B.Fab")
		)
		(fp_line
			(start 0.67945 0.3048)
			(end 0.67945 -0.305054)
			(stroke
				(width 0.1)
				(type default)
			)
			(layer "B.Fab")
		)
		(fp_line
			(start -0.120396 0.2794)
			(end 0.12065 0.2794)
			(stroke
				(width 0.1)
				(type default)
			)
			(layer "B.Fab")
		)
		(fp_line
			(start 0.12065 0.2794)
			(end 0.12065 0.3048)
			(stroke
				(width 0.1)
				(type default)
			)
			(layer "B.Fab")
		)
		(fp_line
			(start -0.12065 -0.2794)
			(end -0.12065 -0.3048)
			(stroke
				(width 0.1)
				(type default)
			)
			(layer "B.Fab")
		)
		(fp_line
			(start 0.12065 -0.2794)
			(end -0.12065 -0.2794)
			(stroke
				(width 0.1)
				(type default)
			)
			(layer "B.Fab")
		)
		(fp_line
			(start -0.67945 -0.3048)
			(end -0.67945 0.3048)
			(stroke
				(width 0.1)
				(type default)
			)
			(layer "B.Fab")
		)
		(fp_line
			(start -0.12065 -0.3048)
			(end -0.67945 -0.3048)
			(stroke
				(width 0.1)
				(type default)
			)
			(layer "B.Fab")
		)
		(fp_line
			(start 0.12065 -0.305054)
			(end 0.12065 -0.2794)
			(stroke
				(width 0.1)
				(type default)
			)
			(layer "B.Fab")
		)
		(fp_line
			(start 0.67945 -0.305054)
			(end 0.12065 -0.305054)
			(stroke
				(width 0.1)
				(type default)
			)
			(layer "B.Fab")
		)
		(pad "1" smd circle
			(at 0.40005 0 90)
			(size 0 0)
			(layers "B.Cu" "B.Mask" "B.Paste")
			(net "FAN_1_CS")
		)
		(pad "2" smd circle
			(at -0.40005 0 90)
			(size 0 0)
			(layers "B.Cu" "B.Mask" "B.Paste")
			(net "GND")
		)
	)
	(footprint ""
		(layer "B.Cu")
		(at 12.7 -258.572 90)
		(property "Reference" "PC56"
			(at 0 0 90)
			(layer "B.SilkS")
			(hide yes)
			(effects
				(font
					(size 1.27 1.27)
				)
				(justify mirror)
			)
		)
		(property "Value" ""
			(at 0 0 90)
			(layer "B.Fab")
			(effects
				(font
					(size 1.27 1.27)
				)
				(justify mirror)
			)
		)
		(duplicate_pad_numbers_are_jumpers no)
		(fp_line
			(start 0.7874 -0.4064)
			(end -0.7874 -0.4064)
			(stroke
				(width 0.1524)
				(type default)
			)
			(layer "B.SilkS")
		)
		(fp_line
			(start -0.7874 -0.4064)
			(end -0.7874 0.4064)
			(stroke
				(width 0.1524)
				(type default)
			)
			(layer "B.SilkS")
		)
		(fp_line
			(start 0.7874 0.4064)
			(end 0.7874 -0.4064)
			(stroke
				(width 0.1524)
				(type default)
			)
			(layer "B.SilkS")
		)
		(fp_line
			(start -0.7874 0.4064)
			(end 0.7874 0.4064)
			(stroke
				(width 0.1524)
				(type default)
			)
			(layer "B.SilkS")
		)
		(fp_line
			(start 0.67945 -0.305054)
			(end 0.12065 -0.305054)
			(stroke
				(width 0.1)
				(type default)
			)
			(layer "B.Fab")
		)
		(fp_line
			(start 0.12065 -0.305054)
			(end 0.12065 -0.2794)
			(stroke
				(width 0.1)
				(type default)
			)
			(layer "B.Fab")
		)
		(fp_line
			(start -0.12065 -0.3048)
			(end -0.67945 -0.3048)
			(stroke
				(width 0.1)
				(type default)
			)
			(layer "B.Fab")
		)
		(fp_line
			(start -0.67945 -0.3048)
			(end -0.67945 0.3048)
			(stroke
				(width 0.1)
				(type default)
			)
			(layer "B.Fab")
		)
		(fp_line
			(start 0.12065 -0.2794)
			(end -0.12065 -0.2794)
			(stroke
				(width 0.1)
				(type default)
			)
			(layer "B.Fab")
		)
		(fp_line
			(start -0.12065 -0.2794)
			(end -0.12065 -0.3048)
			(stroke
				(width 0.1)
				(type default)
			)
			(layer "B.Fab")
		)
		(fp_line
			(start 0.12065 0.2794)
			(end 0.12065 0.3048)
			(stroke
				(width 0.1)
				(type default)
			)
			(layer "B.Fab")
		)
		(fp_line
			(start -0.120396 0.2794)
			(end 0.12065 0.2794)
			(stroke
				(width 0.1)
				(type default)
			)
			(layer "B.Fab")
		)
		(fp_line
			(start 0.67945 0.3048)
			(end 0.67945 -0.305054)
			(stroke
				(width 0.1)
				(type default)
			)
			(layer "B.Fab")
		)
		(fp_line
			(start 0.12065 0.3048)
			(end 0.67945 0.3048)
			(stroke
				(width 0.1)
				(type default)
			)
			(layer "B.Fab")
		)
		(fp_line
			(start -0.120396 0.3048)
			(end -0.120396 0.2794)
			(stroke
				(width 0.1)
				(type default)
			)
			(layer "B.Fab")
		)
		(fp_line
			(start -0.67945 0.3048)
			(end -0.120396 0.3048)
			(stroke
				(width 0.1)
				(type default)
			)
			(layer "B.Fab")
		)
		(pad "1" smd circle
			(at 0.40005 0 270)
			(size 0 0)
			(layers "B.Cu" "B.Mask" "B.Paste")
			(net "FAN_7_P3V_R")
		)
		(pad "2" smd circle
			(at -0.40005 0 270)
			(size 0 0)
			(layers "B.Cu" "B.Mask" "B.Paste")
			(net "GND")
		)
	)
	(footprint ""
		(layer "B.Cu")
		(at 4.826 -64.837056 -90)
		(property "Reference" "PC41"
			(at 0 0 90)
			(layer "B.SilkS")
			(hide yes)
			(effects
				(font
					(size 1.27 1.27)
				)
				(justify mirror)
			)
		)
		(property "Value" ""
			(at 0 0 90)
			(layer "B.Fab")
			(effects
				(font
					(size 1.27 1.27)
				)
				(justify mirror)
			)
		)
		(duplicate_pad_numbers_are_jumpers no)
		(fp_line
			(start -0.7874 0.4064)
			(end 0.7874 0.4064)
			(stroke
				(width 0.1524)
				(type default)
			)
			(layer "B.SilkS")
		)
		(fp_line
			(start 0.7874 0.4064)
			(end 0.7874 -0.4064)
			(stroke
				(width 0.1524)
				(type default)
			)
			(layer "B.SilkS")
		)
		(fp_line
			(start -0.7874 -0.4064)
			(end -0.7874 0.4064)
			(stroke
				(width 0.1524)
				(type default)
			)
			(layer "B.SilkS")
		)
		(fp_line
			(start 0.7874 -0.4064)
			(end -0.7874 -0.4064)
			(stroke
				(width 0.1524)
				(type default)
			)
			(layer "B.SilkS")
		)
		(fp_line
			(start -0.67945 0.3048)
			(end -0.120396 0.3048)
			(stroke
				(width 0.1)
				(type default)
			)
			(layer "B.Fab")
		)
		(fp_line
			(start -0.120396 0.3048)
			(end -0.120396 0.2794)
			(stroke
				(width 0.1)
				(type default)
			)
			(layer "B.Fab")
		)
		(fp_line
			(start 0.12065 0.3048)
			(end 0.67945 0.3048)
			(stroke
				(width 0.1)
				(type default)
			)
			(layer "B.Fab")
		)
		(fp_line
			(start 0.67945 0.3048)
			(end 0.67945 -0.305054)
			(stroke
				(width 0.1)
				(type default)
			)
			(layer "B.Fab")
		)
		(fp_line
			(start -0.120396 0.2794)
			(end 0.12065 0.2794)
			(stroke
				(width 0.1)
				(type default)
			)
			(layer "B.Fab")
		)
		(fp_line
			(start 0.12065 0.2794)
			(end 0.12065 0.3048)
			(stroke
				(width 0.1)
				(type default)
			)
			(layer "B.Fab")
		)
		(fp_line
			(start -0.12065 -0.2794)
			(end -0.12065 -0.3048)
			(stroke
				(width 0.1)
				(type default)
			)
			(layer "B.Fab")
		)
		(fp_line
			(start 0.12065 -0.2794)
			(end -0.12065 -0.2794)
			(stroke
				(width 0.1)
				(type default)
			)
			(layer "B.Fab")
		)
		(fp_line
			(start -0.67945 -0.3048)
			(end -0.67945 0.3048)
			(stroke
				(width 0.1)
				(type default)
			)
			(layer "B.Fab")
		)
		(fp_line
			(start -0.12065 -0.3048)
			(end -0.67945 -0.3048)
			(stroke
				(width 0.1)
				(type default)
			)
			(layer "B.Fab")
		)
		(fp_line
			(start 0.12065 -0.305054)
			(end 0.12065 -0.2794)
			(stroke
				(width 0.1)
				(type default)
			)
			(layer "B.Fab")
		)
		(fp_line
			(start 0.67945 -0.305054)
			(end 0.12065 -0.305054)
			(stroke
				(width 0.1)
				(type default)
			)
			(layer "B.Fab")
		)
		(pad "1" smd circle
			(at 0.40005 0 90)
			(size 0 0)
			(layers "B.Cu" "B.Mask" "B.Paste")
			(net "FAN_4_TIMER")
		)
		(pad "2" smd circle
			(at -0.40005 0 90)
			(size 0 0)
			(layers "B.Cu" "B.Mask" "B.Paste")
			(net "GND")
		)
	)
	(footprint ""
		(layer "B.Cu")
		(at 7.947914 -252.095 180)
		(property "Reference" "U383"
			(at -0.434086 1.75133 0)
			(unlocked yes)
			(layer "B.SilkS")
			(effects
				(font
					(size 0.7874 0.5842)
					(thickness 0.1524)
				)
				(justify mirror)
			)
		)
		(property "Value" ""
			(at 0 0 0)
			(layer "B.Fab")
			(effects
				(font
					(size 1.27 1.27)
				)
				(justify mirror)
			)
		)
		(duplicate_pad_numbers_are_jumpers no)
		(fp_line
			(start 1.7018 1.1176)
			(end 1.7018 -1.1176)
			(stroke
				(width 0.1524)
				(type default)
			)
			(layer "B.SilkS")
		)
		(fp_line
			(start 0.254 -1.1176)
			(end 1.7018 -1.1176)
			(stroke
				(width 0.1524)
				(type default)
			)
			(layer "B.SilkS")
		)
		(fp_line
			(start 0 -0.7112)
			(end 0.254 -1.1176)
			(stroke
				(width 0.1524)
				(type default)
			)
			(layer "B.SilkS")
		)
		(fp_line
			(start -0.254 -1.1176)
			(end 0 -0.7112)
			(stroke
				(width 0.1524)
				(type default)
			)
			(layer "B.SilkS")
		)
		(fp_line
			(start -1.7018 1.1176)
			(end 1.7018 1.1176)
			(stroke
				(width 0.1524)
				(type default)
			)
			(layer "B.SilkS")
		)
		(fp_line
			(start -1.7018 -1.1176)
			(end -0.254 -1.1176)
			(stroke
				(width 0.1524)
				(type default)
			)
			(layer "B.SilkS")
		)
		(fp_line
			(start -1.7018 -1.1176)
			(end -1.7018 1.1176)
			(stroke
				(width 0.1524)
				(type default)
			)
			(layer "B.SilkS")
		)
		(fp_poly
			(pts
				(xy 1.8161 -0.675386) (xy 2.4003 -0.446786) (xy 2.4003 -0.878586)
			)
			(stroke
				(width 0)
				(type default)
			)
			(fill yes)
			(layer "B.SilkS")
		)
		(fp_line
			(start 1.5494 1.1176)
			(end 1.5494 -1.1176)
			(stroke
				(width 0.1)
				(type default)
			)
			(layer "B.Fab")
		)
		(fp_line
			(start 0.254 -1.1176)
			(end 1.5494 -1.1176)
			(stroke
				(width 0.1)
				(type default)
			)
			(layer "B.Fab")
		)
		(fp_line
			(start -0.254 -1.1176)
			(end 0.254 -1.1176)
			(stroke
				(width 0.1)
				(type default)
			)
			(layer "B.Fab")
		)
		(fp_line
			(start -1.5494 1.1176)
			(end 1.5494 1.1176)
			(stroke
				(width 0.1)
				(type default)
			)
			(layer "B.Fab")
		)
		(fp_line
			(start -1.5494 -1.1176)
			(end -0.254 -1.1176)
			(stroke
				(width 0.1)
				(type default)
			)
			(layer "B.Fab")
		)
		(fp_line
			(start -1.5494 -1.1176)
			(end -1.5494 1.1176)
			(stroke
				(width 0.1)
				(type default)
			)
			(layer "B.Fab")
		)
		(fp_poly
			(pts
				(xy 1.8161 -0.675386) (xy 2.4003 -0.446786) (xy 2.4003 -0.878586)
			)
			(stroke
				(width 0)
				(type default)
			)
			(fill yes)
			(layer "B.Fab")
		)
		(pad "1" smd rect
			(at 0.962406 -0.649986 90)
			(size 0.3302 1.1684)
			(layers "B.Cu" "B.Mask" "B.Paste")
			(net "FAN_6_PRESENT_R")
		)
		(pad "2" smd rect
			(at 0.962406 0 90)
			(size 0.3302 1.1684)
			(layers "B.Cu" "B.Mask" "B.Paste")
			(net "P52V_FAN_6_BUFF_EN_R")
		)
		(pad "3" smd rect
			(at 0.962406 0.649986 90)
			(size 0.3302 1.1684)
			(layers "B.Cu" "B.Mask" "B.Paste")
			(net "GND")
		)
		(pad "4" smd rect
			(at -0.962406 0.649986 90)
			(size 0.3302 1.1684)
			(layers "B.Cu" "B.Mask" "B.Paste")
			(net "P52V_FAN_6_EN")
		)
		(pad "5" smd rect
			(at -0.962406 -0.649986 90)
			(size 0.3302 1.1684)
			(layers "B.Cu" "B.Mask" "B.Paste")
			(net "P3V3_AUX")
		)
	)
	(footprint ""
		(layer "B.Cu")
		(at 33.4518 -276.3774)
		(property "Reference" "C2098"
			(at 0 0 0)
			(layer "B.SilkS")
			(hide yes)
			(effects
				(font
					(size 1.27 1.27)
				)
				(justify mirror)
			)
		)
		(property "Value" ""
			(at 0 0 0)
			(layer "B.Fab")
			(effects
				(font
					(size 1.27 1.27)
				)
				(justify mirror)
			)
		)
		(duplicate_pad_numbers_are_jumpers no)
		(fp_line
			(start -2.2098 -0.9398)
			(end -2.2098 0.9398)
			(stroke
				(width 0.1524)
				(type default)
			)
			(layer "B.SilkS")
		)
		(fp_line
			(start -2.2098 0.9398)
			(end 2.2098 0.9398)
			(stroke
				(width 0.1524)
				(type default)
			)
			(layer "B.SilkS")
		)
		(fp_line
			(start 2.2098 -0.9398)
			(end -2.2098 -0.9398)
			(stroke
				(width 0.1524)
				(type default)
			)
			(layer "B.SilkS")
		)
		(fp_line
			(start 2.2098 0.9398)
			(end 2.2098 -0.9398)
			(stroke
				(width 0.1524)
				(type default)
			)
			(layer "B.SilkS")
		)
		(fp_line
			(start -1.700022 -0.899922)
			(end -1.700022 0.899922)
			(stroke
				(width 0.1)
				(type default)
			)
			(layer "B.Fab")
		)
		(fp_line
			(start -1.700022 0.899922)
			(end 1.700022 0.899922)
			(stroke
				(width 0.1)
				(type default)
			)
			(layer "B.Fab")
		)
		(fp_line
			(start 1.700022 -0.899922)
			(end -1.700022 -0.899922)
			(stroke
				(width 0.1)
				(type default)
			)
			(layer "B.Fab")
		)
		(fp_line
			(start 1.700022 0.899922)
			(end 1.700022 -0.899922)
			(stroke
				(width 0.1)
				(type default)
			)
			(layer "B.Fab")
		)
		(pad "1" smd rect
			(at 1.4732 0)
			(size 1.1684 1.5748)
			(layers "B.Cu" "B.Mask" "B.Paste")
			(net "P52V_FAN_0")
		)
		(pad "2" smd rect
			(at -1.4732 0)
			(size 1.1684 1.5748)
			(layers "B.Cu" "B.Mask" "B.Paste")
			(net "GND")
		)
	)
	(footprint ""
		(layer "B.Cu")
		(at 44.069 -234.315 180)
		(property "Reference" "C2100"
			(at 0 0 0)
			(layer "B.SilkS")
			(hide yes)
			(effects
				(font
					(size 1.27 1.27)
				)
				(justify mirror)
			)
		)
		(property "Value" ""
			(at 0 0 0)
			(layer "B.Fab")
			(effects
				(font
					(size 1.27 1.27)
				)
				(justify mirror)
			)
		)
		(duplicate_pad_numbers_are_jumpers no)
		(fp_line
			(start 2.2098 0.9398)
			(end 2.2098 -0.9398)
			(stroke
				(width 0.1524)
				(type default)
			)
			(layer "B.SilkS")
		)
		(fp_line
			(start 2.2098 -0.9398)
			(end -2.2098 -0.9398)
			(stroke
				(width 0.1524)
				(type default)
			)
			(layer "B.SilkS")
		)
		(fp_line
			(start -2.2098 0.9398)
			(end 2.2098 0.9398)
			(stroke
				(width 0.1524)
				(type default)
			)
			(layer "B.SilkS")
		)
		(fp_line
			(start -2.2098 -0.9398)
			(end -2.2098 0.9398)
			(stroke
				(width 0.1524)
				(type default)
			)
			(layer "B.SilkS")
		)
		(fp_line
			(start 1.700022 0.899922)
			(end 1.700022 -0.899922)
			(stroke
				(width 0.1)
				(type default)
			)
			(layer "B.Fab")
		)
		(fp_line
			(start 1.700022 -0.899922)
			(end -1.700022 -0.899922)
			(stroke
				(width 0.1)
				(type default)
			)
			(layer "B.Fab")
		)
		(fp_line
			(start -1.700022 0.899922)
			(end 1.700022 0.899922)
			(stroke
				(width 0.1)
				(type default)
			)
			(layer "B.Fab")
		)
		(fp_line
			(start -1.700022 -0.899922)
			(end -1.700022 0.899922)
			(stroke
				(width 0.1)
				(type default)
			)
			(layer "B.Fab")
		)
		(pad "1" smd rect
			(at 1.4732 0 180)
			(size 1.1684 1.5748)
			(layers "B.Cu" "B.Mask" "B.Paste")
			(net "P52V_FAN_1")
		)
		(pad "2" smd rect
			(at -1.4732 0 180)
			(size 1.1684 1.5748)
			(layers "B.Cu" "B.Mask" "B.Paste")
			(net "GND")
		)
	)
	(footprint ""
		(layer "B.Cu")
		(at 6.700012 -289.310064 180)
		(property "Reference" "J8"
			(at 2.001012 19.273266 0)
			(unlocked yes)
			(layer "B.SilkS")
			(effects
				(font
					(size 0.7874 0.5842)
					(thickness 0.1524)
				)
				(justify left mirror)
			)
		)
		(property "Value" ""
			(at 0 0 0)
			(layer "B.Fab")
			(effects
				(font
					(size 1.27 1.27)
				)
				(justify mirror)
			)
		)
		(duplicate_pad_numbers_are_jumpers no)
		(fp_line
			(start 4.350004 18.524982)
			(end -6.35 18.524982)
			(stroke
				(width 0.1524)
				(type default)
			)
			(layer "B.SilkS")
		)
		(fp_line
			(start 4.350004 -4.52501)
			(end 4.350004 18.524982)
			(stroke
				(width 0.1524)
				(type default)
			)
			(layer "B.SilkS")
		)
		(fp_line
			(start 1.249934 15.424912)
			(end -3.24993 15.424912)
			(stroke
				(width 0.1524)
				(type default)
			)
			(layer "B.SilkS")
		)
		(fp_line
			(start 1.249934 8.200136)
			(end 4.350004 8.200136)
			(stroke
				(width 0.1524)
				(type default)
			)
			(layer "B.SilkS")
		)
		(fp_line
			(start 1.249934 8.200136)
			(end 1.249934 15.424912)
			(stroke
				(width 0.1524)
				(type default)
			)
			(layer "B.SilkS")
		)
		(fp_line
			(start 1.249934 5.799836)
			(end 4.350004 5.799836)
			(stroke
				(width 0.1524)
				(type default)
			)
			(layer "B.SilkS")
		)
		(fp_line
			(start 1.249934 -1.42494)
			(end 1.249934 5.799836)
			(stroke
				(width 0.1524)
				(type default)
			)
			(layer "B.SilkS")
		)
		(fp_line
			(start -0.029972 -1.42494)
			(end 1.249934 -1.42494)
			(stroke
				(width 0.1524)
				(type default)
			)
			(layer "B.SilkS")
		)
		(fp_line
			(start -3.24993 15.424912)
			(end -3.24993 -1.42494)
			(stroke
				(width 0.1524)
				(type default)
			)
			(layer "B.SilkS")
		)
		(fp_line
			(start -3.24993 -1.42494)
			(end -1.96977 -1.42494)
			(stroke
				(width 0.1524)
				(type default)
			)
			(layer "B.SilkS")
		)
		(fp_line
			(start -6.35 18.524982)
			(end -6.35 -4.52501)
			(stroke
				(width 0.1524)
				(type default)
			)
			(layer "B.SilkS")
		)
		(fp_line
			(start -6.35 -4.52501)
			(end 4.350004 -4.52501)
			(stroke
				(width 0.1524)
				(type default)
			)
			(layer "B.SilkS")
		)
		(fp_poly
			(pts
				(xy 5.527802 -0.508) (xy 5.527802 0.508) (xy 4.511802 0)
			)
			(stroke
				(width 0)
				(type default)
			)
			(fill yes)
			(layer "B.SilkS")
		)
		(fp_line
			(start 4.350004 18.524982)
			(end -6.35 18.524982)
			(stroke
				(width 0.1)
				(type default)
			)
			(layer "B.Fab")
		)
		(fp_line
			(start 4.350004 -4.52501)
			(end 4.350004 18.524982)
			(stroke
				(width 0.1)
				(type default)
			)
			(layer "B.Fab")
		)
		(fp_line
			(start -6.35 18.524982)
			(end -6.35 -4.52501)
			(stroke
				(width 0.1)
				(type default)
			)
			(layer "B.Fab")
		)
		(fp_line
			(start -6.35 -4.52501)
			(end 4.350004 -4.52501)
			(stroke
				(width 0.1)
				(type default)
			)
			(layer "B.Fab")
		)
		(fp_poly
			(pts
				(xy 5.527802 -0.508) (xy 5.527802 0.508) (xy 4.511802 0)
			)
			(stroke
				(width 0)
				(type default)
			)
			(fill yes)
			(layer "B.Fab")
		)
		(pad "" np_thru_hole circle
			(at -0.999998 -1.89992 90)
			(size 1.4986 1.4986)
			(drill 1.4986)
			(layers "*.Cu" "*.Mask")
			(clearance 0.381)
			(thermal_gap 0.381)
		)
		(pad "1" thru_hole rect
			(at 0 0 90)
			(size 1.3716 1.3716)
			(drill 0.9652)
			(layers "*.Cu" "*.Mask")
			(remove_unused_layers no)
			(net "FAN_7_TACH_IL_D")
			(clearance 0.0508)
			(padstack
				(mode front_inner_back)
				(layer "Inner"
					(shape circle)
					(size 1.3716 1.3716)
					(clearance 0.0508)
				)
				(layer "B.Cu"
					(shape rect)
					(size 1.3716 1.3716)
					(thermal_gap 0.0508)
					(clearance 0.0508)
				)
			)
		)
		(pad "2" thru_hole circle
			(at -1.999996 0 90)
			(size 1.3716 1.3716)
			(drill 0.9652)
			(layers "*.Cu" "*.Mask")
			(remove_unused_layers no)
			(net "FAN_7_PWM_OL_R")
			(clearance 0.0508)
			(thermal_gap 0.0508)
		)
		(pad "3" thru_hole circle
			(at 0 1.999996 90)
			(size 1.3716 1.3716)
			(drill 0.9652)
			(layers "*.Cu" "*.Mask")
			(remove_unused_layers no)
			(net "FAN_7_PWM_IL_R")
			(clearance 0.0508)
			(thermal_gap 0.0508)
		)
		(pad "4" thru_hole circle
			(at -1.999996 1.999996 90)
			(size 1.3716 1.3716)
			(drill 0.9652)
			(layers "*.Cu" "*.Mask")
			(remove_unused_layers no)
			(net "FAN_7_PRESENT_R_N")
			(clearance 0.0508)
			(thermal_gap 0.0508)
		)
		(pad "5" thru_hole circle
			(at 0 3.999992 90)
			(size 1.3716 1.3716)
			(drill 0.9652)
			(layers "*.Cu" "*.Mask")
			(remove_unused_layers no)
			(net "P12V_LED_R1_FAN7")
			(clearance 0.0508)
			(thermal_gap 0.0508)
		)
		(pad "6" thru_hole circle
			(at -1.999996 3.999992 90)
			(size 1.3716 1.3716)
			(drill 0.9652)
			(layers "*.Cu" "*.Mask")
			(remove_unused_layers no)
			(net "SMB_FAN7_SCL_R")
			(clearance 0.0508)
			(thermal_gap 0.0508)
		)
		(pad "7" thru_hole circle
			(at 0 5.999988 90)
			(size 1.3716 1.3716)
			(drill 0.9652)
			(layers "*.Cu" "*.Mask")
			(remove_unused_layers no)
			(net "SMB_FAN7_SDA_R")
			(clearance 0.0508)
			(thermal_gap 0.0508)
		)
		(pad "8" thru_hole circle
			(at -1.999996 5.999988 90)
			(size 1.3716 1.3716)
			(drill 0.9652)
			(layers "*.Cu" "*.Mask")
			(remove_unused_layers no)
			(net "GND")
			(clearance 0.0508)
			(thermal_gap 0.0508)
		)
		(pad "9" thru_hole circle
			(at 0 7.999984 90)
			(size 1.3716 1.3716)
			(drill 0.9652)
			(layers "*.Cu" "*.Mask")
			(remove_unused_layers no)
			(net "GND")
			(clearance 0.0508)
			(thermal_gap 0.0508)
		)
		(pad "10" thru_hole circle
			(at -1.999996 7.999984 90)
			(size 1.3716 1.3716)
			(drill 0.9652)
			(layers "*.Cu" "*.Mask")
			(remove_unused_layers no)
			(net "P52V_FAN_7")
			(clearance 0.0508)
			(thermal_gap 0.0508)
		)
		(pad "11" thru_hole circle
			(at 0 9.99998 90)
			(size 1.3716 1.3716)
			(drill 0.9652)
			(layers "*.Cu" "*.Mask")
			(remove_unused_layers no)
			(net "P52V_FAN_7")
			(clearance 0.0508)
			(thermal_gap 0.0508)
		)
		(pad "12" thru_hole circle
			(at -1.999996 9.99998 90)
			(size 1.3716 1.3716)
			(drill 0.9652)
			(layers "*.Cu" "*.Mask")
			(remove_unused_layers no)
			(net "FAN_7_FAIL_R_LED_N")
			(clearance 0.0508)
			(thermal_gap 0.0508)
		)
		(pad "13" thru_hole circle
			(at 0 11.999976 90)
			(size 1.3716 1.3716)
			(drill 0.9652)
			(layers "*.Cu" "*.Mask")
			(remove_unused_layers no)
			(net "FAN_7_TACH_OL_D")
			(clearance 0.0508)
			(thermal_gap 0.0508)
		)
		(pad "14" thru_hole circle
			(at -1.999996 11.999976 90)
			(size 1.3716 1.3716)
			(drill 0.9652)
			(layers "*.Cu" "*.Mask")
			(remove_unused_layers no)
			(net "FAN_7_OK_R_LED_N")
			(clearance 0.0508)
			(thermal_gap 0.0508)
		)
		(pad "15" thru_hole circle
			(at 0 13.999972 90)
			(size 1.3716 1.3716)
			(drill 0.9652)
			(layers "*.Cu" "*.Mask")
			(remove_unused_layers no)
			(net "Net_597")
			(clearance 0.0508)
			(thermal_gap 0.0508)
		)
		(pad "16" thru_hole circle
			(at -1.999996 13.999972 90)
			(size 1.3716 1.3716)
			(drill 0.9652)
			(layers "*.Cu" "*.Mask")
			(remove_unused_layers no)
			(net "Net_596")
			(clearance 0.0508)
			(thermal_gap 0.0508)
		)
		(zone
			(layers "F.Cu" "B.Cu" "In1.Cu" "In2.Cu" "In3.Cu" "In4.Cu")
			(hatch none 0.5)
			(connect_pads
				(clearance 0)
			)
			(min_thickness 0.25)
			(keepout
				(tracks not_allowed)
				(vias allowed)
				(pads allowed)
				(copperpour not_allowed)
				(footprints allowed)
			)
			(placement
				(enabled no)
				(sheetname "")
			)
			(fill
				(thermal_gap 0.5)
				(thermal_bridge_width 0.5)
				(island_removal_mode 0)
			)
			(polygon
				(pts
					(arc
						(start 8.95731 -287.410144)
						(mid 6.44271 -287.410144)
						(end 8.95731 -287.410144)
					)
				)
			)
		)
	)
	(footprint ""
		(layer "B.Cu")
		(at 6.700012 -12.409932 180)
		(property "Reference" "J5"
			(at 2.763012 19.186398 0)
			(unlocked yes)
			(layer "B.SilkS")
			(effects
				(font
					(size 0.7874 0.5842)
					(thickness 0.1524)
				)
				(justify left mirror)
			)
		)
		(property "Value" ""
			(at 0 0 0)
			(layer "B.Fab")
			(effects
				(font
					(size 1.27 1.27)
				)
				(justify mirror)
			)
		)
		(duplicate_pad_numbers_are_jumpers no)
		(fp_line
			(start 4.350004 18.524982)
			(end -6.35 18.524982)
			(stroke
				(width 0.1524)
				(type default)
			)
			(layer "B.SilkS")
		)
		(fp_line
			(start 4.350004 -4.52501)
			(end 4.350004 18.524982)
			(stroke
				(width 0.1524)
				(type default)
			)
			(layer "B.SilkS")
		)
		(fp_line
			(start 1.249934 15.424912)
			(end -3.24993 15.424912)
			(stroke
				(width 0.1524)
				(type default)
			)
			(layer "B.SilkS")
		)
		(fp_line
			(start 1.249934 8.200136)
			(end 4.350004 8.200136)
			(stroke
				(width 0.1524)
				(type default)
			)
			(layer "B.SilkS")
		)
		(fp_line
			(start 1.249934 8.200136)
			(end 1.249934 15.424912)
			(stroke
				(width 0.1524)
				(type default)
			)
			(layer "B.SilkS")
		)
		(fp_line
			(start 1.249934 5.799836)
			(end 4.350004 5.799836)
			(stroke
				(width 0.1524)
				(type default)
			)
			(layer "B.SilkS")
		)
		(fp_line
			(start 1.249934 -1.42494)
			(end 1.249934 5.799836)
			(stroke
				(width 0.1524)
				(type default)
			)
			(layer "B.SilkS")
		)
		(fp_line
			(start -0.029972 -1.42494)
			(end 1.249934 -1.42494)
			(stroke
				(width 0.1524)
				(type default)
			)
			(layer "B.SilkS")
		)
		(fp_line
			(start -3.24993 15.424912)
			(end -3.24993 -1.42494)
			(stroke
				(width 0.1524)
				(type default)
			)
			(layer "B.SilkS")
		)
		(fp_line
			(start -3.24993 -1.42494)
			(end -1.96977 -1.42494)
			(stroke
				(width 0.1524)
				(type default)
			)
			(layer "B.SilkS")
		)
		(fp_line
			(start -6.35 18.524982)
			(end -6.35 -4.52501)
			(stroke
				(width 0.1524)
				(type default)
			)
			(layer "B.SilkS")
		)
		(fp_line
			(start -6.35 -4.52501)
			(end 4.350004 -4.52501)
			(stroke
				(width 0.1524)
				(type default)
			)
			(layer "B.SilkS")
		)
		(fp_poly
			(pts
				(xy 5.527802 -0.508) (xy 5.527802 0.508) (xy 4.511802 0)
			)
			(stroke
				(width 0)
				(type default)
			)
			(fill yes)
			(layer "B.SilkS")
		)
		(fp_line
			(start 4.350004 18.524982)
			(end -6.35 18.524982)
			(stroke
				(width 0.1)
				(type default)
			)
			(layer "B.Fab")
		)
		(fp_line
			(start 4.350004 -4.52501)
			(end 4.350004 18.524982)
			(stroke
				(width 0.1)
				(type default)
			)
			(layer "B.Fab")
		)
		(fp_line
			(start -6.35 18.524982)
			(end -6.35 -4.52501)
			(stroke
				(width 0.1)
				(type default)
			)
			(layer "B.Fab")
		)
		(fp_line
			(start -6.35 -4.52501)
			(end 4.350004 -4.52501)
			(stroke
				(width 0.1)
				(type default)
			)
			(layer "B.Fab")
		)
		(fp_poly
			(pts
				(xy 5.527802 -0.508) (xy 5.527802 0.508) (xy 4.511802 0)
			)
			(stroke
				(width 0)
				(type default)
			)
			(fill yes)
			(layer "B.Fab")
		)
		(pad "" np_thru_hole circle
			(at -0.999998 -1.89992 90)
			(size 1.4986 1.4986)
			(drill 1.4986)
			(layers "*.Cu" "*.Mask")
			(clearance 0.381)
			(thermal_gap 0.381)
		)
		(pad "1" thru_hole rect
			(at 0 0 90)
			(size 1.3716 1.3716)
			(drill 0.9652)
			(layers "*.Cu" "*.Mask")
			(remove_unused_layers no)
			(net "FAN_4_TACH_IL_D")
			(clearance 0.0508)
			(padstack
				(mode front_inner_back)
				(layer "Inner"
					(shape circle)
					(size 1.3716 1.3716)
					(clearance 0.0508)
				)
				(layer "B.Cu"
					(shape rect)
					(size 1.3716 1.3716)
					(thermal_gap 0.0508)
					(clearance 0.0508)
				)
			)
		)
		(pad "2" thru_hole circle
			(at -1.999996 0 90)
			(size 1.3716 1.3716)
			(drill 0.9652)
			(layers "*.Cu" "*.Mask")
			(remove_unused_layers no)
			(net "FAN_4_PWM_OL_R")
			(clearance 0.0508)
			(thermal_gap 0.0508)
		)
		(pad "3" thru_hole circle
			(at 0 1.999996 90)
			(size 1.3716 1.3716)
			(drill 0.9652)
			(layers "*.Cu" "*.Mask")
			(remove_unused_layers no)
			(net "FAN_4_PWM_IL_R")
			(clearance 0.0508)
			(thermal_gap 0.0508)
		)
		(pad "4" thru_hole circle
			(at -1.999996 1.999996 90)
			(size 1.3716 1.3716)
			(drill 0.9652)
			(layers "*.Cu" "*.Mask")
			(remove_unused_layers no)
			(net "FAN_4_PRESENT_R_N")
			(clearance 0.0508)
			(thermal_gap 0.0508)
		)
		(pad "5" thru_hole circle
			(at 0 3.999992 90)
			(size 1.3716 1.3716)
			(drill 0.9652)
			(layers "*.Cu" "*.Mask")
			(remove_unused_layers no)
			(net "P12V_LED_R1_FAN4")
			(clearance 0.0508)
			(thermal_gap 0.0508)
		)
		(pad "6" thru_hole circle
			(at -1.999996 3.999992 90)
			(size 1.3716 1.3716)
			(drill 0.9652)
			(layers "*.Cu" "*.Mask")
			(remove_unused_layers no)
			(net "SMB_FAN4_SCL_R")
			(clearance 0.0508)
			(thermal_gap 0.0508)
		)
		(pad "7" thru_hole circle
			(at 0 5.999988 90)
			(size 1.3716 1.3716)
			(drill 0.9652)
			(layers "*.Cu" "*.Mask")
			(remove_unused_layers no)
			(net "SMB_FAN4_SDA_R")
			(clearance 0.0508)
			(thermal_gap 0.0508)
		)
		(pad "8" thru_hole circle
			(at -1.999996 5.999988 90)
			(size 1.3716 1.3716)
			(drill 0.9652)
			(layers "*.Cu" "*.Mask")
			(remove_unused_layers no)
			(net "GND")
			(clearance 0.0508)
			(thermal_gap 0.0508)
		)
		(pad "9" thru_hole circle
			(at 0 7.999984 90)
			(size 1.3716 1.3716)
			(drill 0.9652)
			(layers "*.Cu" "*.Mask")
			(remove_unused_layers no)
			(net "GND")
			(clearance 0.0508)
			(thermal_gap 0.0508)
		)
		(pad "10" thru_hole circle
			(at -1.999996 7.999984 90)
			(size 1.3716 1.3716)
			(drill 0.9652)
			(layers "*.Cu" "*.Mask")
			(remove_unused_layers no)
			(net "P52V_FAN_4")
			(clearance 0.0508)
			(thermal_gap 0.0508)
		)
		(pad "11" thru_hole circle
			(at 0 9.99998 90)
			(size 1.3716 1.3716)
			(drill 0.9652)
			(layers "*.Cu" "*.Mask")
			(remove_unused_layers no)
			(net "P52V_FAN_4")
			(clearance 0.0508)
			(thermal_gap 0.0508)
		)
		(pad "12" thru_hole circle
			(at -1.999996 9.99998 90)
			(size 1.3716 1.3716)
			(drill 0.9652)
			(layers "*.Cu" "*.Mask")
			(remove_unused_layers no)
			(net "FAN_4_FAIL_R_LED_N")
			(clearance 0.0508)
			(thermal_gap 0.0508)
		)
		(pad "13" thru_hole circle
			(at 0 11.999976 90)
			(size 1.3716 1.3716)
			(drill 0.9652)
			(layers "*.Cu" "*.Mask")
			(remove_unused_layers no)
			(net "FAN_4_TACH_OL_D")
			(clearance 0.0508)
			(thermal_gap 0.0508)
		)
		(pad "14" thru_hole circle
			(at -1.999996 11.999976 90)
			(size 1.3716 1.3716)
			(drill 0.9652)
			(layers "*.Cu" "*.Mask")
			(remove_unused_layers no)
			(net "FAN_4_OK_R_LED_N")
			(clearance 0.0508)
			(thermal_gap 0.0508)
		)
		(pad "15" thru_hole circle
			(at 0 13.999972 90)
			(size 1.3716 1.3716)
			(drill 0.9652)
			(layers "*.Cu" "*.Mask")
			(remove_unused_layers no)
			(net "Net_606")
			(clearance 0.0508)
			(thermal_gap 0.0508)
		)
		(pad "16" thru_hole circle
			(at -1.999996 13.999972 90)
			(size 1.3716 1.3716)
			(drill 0.9652)
			(layers "*.Cu" "*.Mask")
			(remove_unused_layers no)
			(net "Net_605")
			(clearance 0.0508)
			(thermal_gap 0.0508)
		)
		(zone
			(layers "F.Cu" "B.Cu" "In1.Cu" "In2.Cu" "In3.Cu" "In4.Cu")
			(hatch none 0.5)
			(connect_pads
				(clearance 0)
			)
			(min_thickness 0.25)
			(keepout
				(tracks not_allowed)
				(vias allowed)
				(pads allowed)
				(copperpour not_allowed)
				(footprints allowed)
			)
			(placement
				(enabled no)
				(sheetname "")
			)
			(fill
				(thermal_gap 0.5)
				(thermal_bridge_width 0.5)
				(island_removal_mode 0)
			)
			(polygon
				(pts
					(arc
						(start 8.95731 -10.510012)
						(mid 6.44271 -10.510012)
						(end 8.95731 -10.510012)
					)
				)
			)
		)
	)
	(footprint ""
		(layer "B.Cu")
		(at 14.774418 -64.192912 90)
		(property "Reference" "PD15"
			(at -5.518912 3.867912 270)
			(unlocked yes)
			(layer "B.SilkS")
			(effects
				(font
					(size 0.7874 0.5842)
					(thickness 0.1524)
				)
				(justify left mirror)
			)
		)
		(property "Value" ""
			(at 0 0 90)
			(layer "B.Fab")
			(effects
				(font
					(size 1.27 1.27)
				)
				(justify mirror)
			)
		)
		(duplicate_pad_numbers_are_jumpers no)
		(fp_line
			(start 4.647184 -3.109976)
			(end 4.647184 3.109976)
			(stroke
				(width 0.1524)
				(type default)
			)
			(layer "B.SilkS")
		)
		(fp_line
			(start -5.536184 -3.109976)
			(end 4.647184 -3.109976)
			(stroke
				(width 0.1524)
				(type default)
			)
			(layer "B.SilkS")
		)
		(fp_line
			(start -0.762 -1.143)
			(end -0.762 0.889)
			(stroke
				(width 0.1524)
				(type default)
			)
			(layer "B.SilkS")
		)
		(fp_line
			(start 0.635 -0.889)
			(end 0.635 0.635)
			(stroke
				(width 0.1524)
				(type default)
			)
			(layer "B.SilkS")
		)
		(fp_line
			(start 1.397 -0.127)
			(end 0.635 -0.127)
			(stroke
				(width 0.1524)
				(type default)
			)
			(layer "B.SilkS")
		)
		(fp_line
			(start -0.635 -0.127)
			(end 0.635 -0.889)
			(stroke
				(width 0.1524)
				(type default)
			)
			(layer "B.SilkS")
		)
		(fp_line
			(start -0.635 -0.127)
			(end -1.397 -0.127)
			(stroke
				(width 0.1524)
				(type default)
			)
			(layer "B.SilkS")
		)
		(fp_line
			(start 0.635 0.635)
			(end -0.635 -0.127)
			(stroke
				(width 0.1524)
				(type default)
			)
			(layer "B.SilkS")
		)
		(fp_line
			(start 4.647184 3.109976)
			(end -5.536184 3.109976)
			(stroke
				(width 0.1524)
				(type default)
			)
			(layer "B.SilkS")
		)
		(fp_line
			(start -5.536184 3.109976)
			(end -5.536184 -3.109976)
			(stroke
				(width 0.1524)
				(type default)
			)
			(layer "B.SilkS")
		)
		(fp_poly
			(pts
				(xy -5.5118 -3.0988) (xy -5.5118 3.1496) (xy -4.572 3.1496) (xy -4.572 -3.0988)
			)
			(stroke
				(width 0)
				(type default)
			)
			(fill yes)
			(layer "B.SilkS")
		)
		(fp_line
			(start 3.554984 -3.109976)
			(end 3.554984 3.109976)
			(stroke
				(width 0.1)
				(type default)
			)
			(layer "B.Fab")
		)
		(fp_line
			(start -3.554984 -3.109976)
			(end 3.554984 -3.109976)
			(stroke
				(width 0.1)
				(type default)
			)
			(layer "B.Fab")
		)
		(fp_line
			(start 3.554984 3.109976)
			(end -3.554984 3.109976)
			(stroke
				(width 0.1)
				(type default)
			)
			(layer "B.Fab")
		)
		(fp_line
			(start -3.554984 3.109976)
			(end -3.554984 -3.109976)
			(stroke
				(width 0.1)
				(type default)
			)
			(layer "B.Fab")
		)
		(fp_text user "-"
			(at -5.334 -0.34925 90)
			(unlocked yes)
			(layer "B.SilkS")
			(effects
				(font
					(size 1.905 1.4224)
					(thickness 0.1524)
				)
				(justify left mirror)
			)
		)
		(fp_text user "+"
			(at 6.1214 -0.32385 90)
			(unlocked yes)
			(layer "B.SilkS")
			(effects
				(font
					(size 1.905 1.4224)
					(thickness 0.1524)
				)
				(justify left mirror)
			)
		)
		(fp_text user "-"
			(at -5.334 -0.34925 90)
			(unlocked yes)
			(layer "B.Fab")
			(effects
				(font
					(size 1.905 1.4224)
					(thickness 0.1524)
				)
				(justify left mirror)
			)
		)
		(fp_text user "+"
			(at 6.1214 -0.32385 90)
			(unlocked yes)
			(layer "B.Fab")
			(effects
				(font
					(size 1.905 1.4224)
					(thickness 0.1524)
				)
				(justify left mirror)
			)
		)
		(pad "A" smd rect
			(at 3.299968 0 270)
			(size 2.413 3.302)
			(layers "B.Cu" "B.Mask" "B.Paste")
			(net "GND")
		)
		(pad "C" smd rect
			(at -3.299968 0 270)
			(size 2.413 3.302)
			(layers "B.Cu" "B.Mask" "B.Paste")
			(net "P52V_HSC")
		)
	)
	(footprint ""
		(layer "B.Cu")
		(at 17.033494 -255.778 -90)
		(property "Reference" "U398"
			(at 1.524 -2.878836 270)
			(unlocked yes)
			(layer "B.SilkS")
			(effects
				(font
					(size 0.7874 0.5842)
					(thickness 0.1524)
				)
				(justify left mirror)
			)
		)
		(property "Value" ""
			(at 0 0 90)
			(layer "B.Fab")
			(effects
				(font
					(size 1.27 1.27)
				)
				(justify mirror)
			)
		)
		(duplicate_pad_numbers_are_jumpers no)
		(fp_line
			(start -1.3462 1.1938)
			(end -1.3462 -1.1938)
			(stroke
				(width 0.1524)
				(type default)
			)
			(layer "B.SilkS")
		)
		(fp_line
			(start 1.3462 1.1938)
			(end -1.3462 1.1938)
			(stroke
				(width 0.1524)
				(type default)
			)
			(layer "B.SilkS")
		)
		(fp_line
			(start -1.3462 -1.1938)
			(end 1.3462 -1.1938)
			(stroke
				(width 0.1524)
				(type default)
			)
			(layer "B.SilkS")
		)
		(fp_line
			(start 1.3462 -1.1938)
			(end 1.3462 1.1684)
			(stroke
				(width 0.1524)
				(type default)
			)
			(layer "B.SilkS")
		)
		(fp_poly
			(pts
				(xy 1.447038 -0.760476) (xy 2.052066 -0.457962) (xy 2.052066 -1.06299)
			)
			(stroke
				(width 0)
				(type default)
			)
			(fill yes)
			(layer "B.SilkS")
		)
		(fp_line
			(start -0.674878 1.124966)
			(end -0.674878 -1.124966)
			(stroke
				(width 0.1)
				(type default)
			)
			(layer "B.Fab")
		)
		(fp_line
			(start 0.674878 1.124966)
			(end -0.674878 1.124966)
			(stroke
				(width 0.1)
				(type default)
			)
			(layer "B.Fab")
		)
		(fp_line
			(start -0.674878 -1.124966)
			(end 0.674878 -1.124966)
			(stroke
				(width 0.1)
				(type default)
			)
			(layer "B.Fab")
		)
		(fp_line
			(start 0.674878 -1.124966)
			(end 0.674878 1.124966)
			(stroke
				(width 0.1)
				(type default)
			)
			(layer "B.Fab")
		)
		(fp_poly
			(pts
				(xy 1.447038 -0.760476) (xy 2.052066 -0.457962) (xy 2.052066 -1.06299)
			)
			(stroke
				(width 0)
				(type default)
			)
			(fill yes)
			(layer "B.Fab")
		)
		(pad "1" smd rect
			(at 0.899922 -0.750062 90)
			(size 0.6096 0.6096)
			(layers "B.Cu" "B.Mask" "B.Paste")
			(net "NC_U398_P1")
		)
		(pad "2" smd rect
			(at 0.899922 0)
			(size 0.4064 0.6096)
			(layers "B.Cu" "B.Mask" "B.Paste")
			(net "FAN_7_PRSNT_BUF_N")
		)
		(pad "3" smd rect
			(at 0.899922 0.750062 90)
			(size 0.6096 0.6096)
			(layers "B.Cu" "B.Mask" "B.Paste")
			(net "GND")
		)
		(pad "4" smd rect
			(at -0.899922 0.750062 90)
			(size 0.6096 0.6096)
			(layers "B.Cu" "B.Mask" "B.Paste")
			(net "FAN_7_PRESENT")
		)
		(pad "5" smd rect
			(at -0.899922 -0.750062 90)
			(size 0.6096 0.6096)
			(layers "B.Cu" "B.Mask" "B.Paste")
			(net "P3V3_AUX")
		)
	)
	(footprint ""
		(layer "B.Cu")
		(at 17.309846 -269.922244 180)
		(property "Reference" "PC55"
			(at 0 0 0)
			(layer "B.SilkS")
			(hide yes)
			(effects
				(font
					(size 1.27 1.27)
				)
				(justify mirror)
			)
		)
		(property "Value" ""
			(at 0 0 0)
			(layer "B.Fab")
			(effects
				(font
					(size 1.27 1.27)
				)
				(justify mirror)
			)
		)
		(duplicate_pad_numbers_are_jumpers no)
		(fp_line
			(start 1.524 0.762)
			(end 1.524 -0.762)
			(stroke
				(width 0.1524)
				(type default)
			)
			(layer "B.SilkS")
		)
		(fp_line
			(start 1.524 -0.762)
			(end -1.524 -0.762)
			(stroke
				(width 0.1524)
				(type default)
			)
			(layer "B.SilkS")
		)
		(fp_line
			(start -1.524 0.762)
			(end 1.524 0.762)
			(stroke
				(width 0.1524)
				(type default)
			)
			(layer "B.SilkS")
		)
		(fp_line
			(start -1.524 -0.762)
			(end -1.524 0.762)
			(stroke
				(width 0.1524)
				(type default)
			)
			(layer "B.SilkS")
		)
		(fp_line
			(start 1.1049 0.724916)
			(end -1.1049 0.724916)
			(stroke
				(width 0.1)
				(type default)
			)
			(layer "B.Fab")
		)
		(fp_line
			(start 1.1049 -0.724916)
			(end 1.1049 0.724916)
			(stroke
				(width 0.1)
				(type default)
			)
			(layer "B.Fab")
		)
		(fp_line
			(start -1.1049 0.724916)
			(end -1.1049 -0.724916)
			(stroke
				(width 0.1)
				(type default)
			)
			(layer "B.Fab")
		)
		(fp_line
			(start -1.1049 -0.724916)
			(end 1.1049 -0.724916)
			(stroke
				(width 0.1)
				(type default)
			)
			(layer "B.Fab")
		)
		(pad "1" smd rect
			(at 0.889 0 180)
			(size 1.016 1.27)
			(layers "B.Cu" "B.Mask" "B.Paste")
			(net "P52V_FAN_7")
		)
		(pad "2" smd rect
			(at -0.889 0 180)
			(size 1.016 1.27)
			(layers "B.Cu" "B.Mask" "B.Paste")
			(net "GND")
		)
	)
	(footprint ""
		(layer "B.Cu")
		(at 40.894 -127.762 180)
		(property "Reference" "R5431"
			(at 0 0 0)
			(layer "B.SilkS")
			(hide yes)
			(effects
				(font
					(size 1.27 1.27)
				)
				(justify mirror)
			)
		)
		(property "Value" ""
			(at 0 0 0)
			(layer "B.Fab")
			(effects
				(font
					(size 1.27 1.27)
				)
				(justify mirror)
			)
		)
		(duplicate_pad_numbers_are_jumpers no)
		(fp_line
			(start 0.7874 0.4064)
			(end 0.7874 -0.4064)
			(stroke
				(width 0.1524)
				(type default)
			)
			(layer "B.SilkS")
		)
		(fp_line
			(start 0.7874 -0.4064)
			(end -0.7874 -0.4064)
			(stroke
				(width 0.1524)
				(type default)
			)
			(layer "B.SilkS")
		)
		(fp_line
			(start -0.7874 0.4064)
			(end 0.7874 0.4064)
			(stroke
				(width 0.1524)
				(type default)
			)
			(layer "B.SilkS")
		)
		(fp_line
			(start -0.7874 -0.4064)
			(end -0.7874 0.4064)
			(stroke
				(width 0.1524)
				(type default)
			)
			(layer "B.SilkS")
		)
		(fp_line
			(start 0.67945 0.3048)
			(end 0.67945 -0.305054)
			(stroke
				(width 0.1)
				(type default)
			)
			(layer "B.Fab")
		)
		(fp_line
			(start 0.67945 -0.305054)
			(end 0.12065 -0.305054)
			(stroke
				(width 0.1)
				(type default)
			)
			(layer "B.Fab")
		)
		(fp_line
			(start 0.12065 0.3048)
			(end 0.67945 0.3048)
			(stroke
				(width 0.1)
				(type default)
			)
			(layer "B.Fab")
		)
		(fp_line
			(start 0.12065 0.2794)
			(end 0.12065 0.3048)
			(stroke
				(width 0.1)
				(type default)
			)
			(layer "B.Fab")
		)
		(fp_line
			(start 0.12065 -0.2794)
			(end -0.12065 -0.2794)
			(stroke
				(width 0.1)
				(type default)
			)
			(layer "B.Fab")
		)
		(fp_line
			(start 0.12065 -0.305054)
			(end 0.12065 -0.2794)
			(stroke
				(width 0.1)
				(type default)
			)
			(layer "B.Fab")
		)
		(fp_line
			(start -0.120396 0.3048)
			(end -0.120396 0.2794)
			(stroke
				(width 0.1)
				(type default)
			)
			(layer "B.Fab")
		)
		(fp_line
			(start -0.120396 0.2794)
			(end 0.12065 0.2794)
			(stroke
				(width 0.1)
				(type default)
			)
			(layer "B.Fab")
		)
		(fp_line
			(start -0.12065 -0.2794)
			(end -0.12065 -0.3048)
			(stroke
				(width 0.1)
				(type default)
			)
			(layer "B.Fab")
		)
		(fp_line
			(start -0.12065 -0.3048)
			(end -0.67945 -0.3048)
			(stroke
				(width 0.1)
				(type default)
			)
			(layer "B.Fab")
		)
		(fp_line
			(start -0.67945 0.3048)
			(end -0.120396 0.3048)
			(stroke
				(width 0.1)
				(type default)
			)
			(layer "B.Fab")
		)
		(fp_line
			(start -0.67945 -0.3048)
			(end -0.67945 0.3048)
			(stroke
				(width 0.1)
				(type default)
			)
			(layer "B.Fab")
		)
		(pad "1" smd rect
			(at 0.40005 0 180)
			(size 0.4572 0.508)
			(layers "B.Cu" "B.Mask" "B.Paste")
			(net "FAN_2_TACH_OL")
		)
		(pad "2" smd rect
			(at -0.40005 0 180)
			(size 0.4572 0.508)
			(layers "B.Cu" "B.Mask" "B.Paste")
			(net "GND")
		)
	)
	(footprint ""
		(layer "B.Cu")
		(at 16.764 -86.1822 180)
		(property "Reference" "PC43"
			(at 0 0 0)
			(layer "B.SilkS")
			(hide yes)
			(effects
				(font
					(size 1.27 1.27)
				)
				(justify mirror)
			)
		)
		(property "Value" ""
			(at 0 0 0)
			(layer "B.Fab")
			(effects
				(font
					(size 1.27 1.27)
				)
				(justify mirror)
			)
		)
		(duplicate_pad_numbers_are_jumpers no)
		(fp_line
			(start 1.524 0.762)
			(end 1.524 -0.762)
			(stroke
				(width 0.1524)
				(type default)
			)
			(layer "B.SilkS")
		)
		(fp_line
			(start 1.524 -0.762)
			(end -1.524 -0.762)
			(stroke
				(width 0.1524)
				(type default)
			)
			(layer "B.SilkS")
		)
		(fp_line
			(start -1.524 0.762)
			(end 1.524 0.762)
			(stroke
				(width 0.1524)
				(type default)
			)
			(layer "B.SilkS")
		)
		(fp_line
			(start -1.524 -0.762)
			(end -1.524 0.762)
			(stroke
				(width 0.1524)
				(type default)
			)
			(layer "B.SilkS")
		)
		(fp_line
			(start 1.1049 0.724916)
			(end -1.1049 0.724916)
			(stroke
				(width 0.1)
				(type default)
			)
			(layer "B.Fab")
		)
		(fp_line
			(start 1.1049 -0.724916)
			(end 1.1049 0.724916)
			(stroke
				(width 0.1)
				(type default)
			)
			(layer "B.Fab")
		)
		(fp_line
			(start -1.1049 0.724916)
			(end -1.1049 -0.724916)
			(stroke
				(width 0.1)
				(type default)
			)
			(layer "B.Fab")
		)
		(fp_line
			(start -1.1049 -0.724916)
			(end 1.1049 -0.724916)
			(stroke
				(width 0.1)
				(type default)
			)
			(layer "B.Fab")
		)
		(pad "1" smd rect
			(at 0.889 0 180)
			(size 1.016 1.27)
			(layers "B.Cu" "B.Mask" "B.Paste")
			(net "P52V_FAN_5")
		)
		(pad "2" smd rect
			(at -0.889 0 180)
			(size 1.016 1.27)
			(layers "B.Cu" "B.Mask" "B.Paste")
			(net "GND")
		)
	)
	(footprint ""
		(layer "B.Cu")
		(at 42.01668 -79.804768 180)
		(property "Reference" "PU5"
			(at -5.60832 -2.361438 0)
			(unlocked yes)
			(layer "B.SilkS")
			(effects
				(font
					(size 0.7874 0.5842)
					(thickness 0.1524)
				)
				(justify left mirror)
			)
		)
		(property "Value" ""
			(at 0 0 0)
			(layer "B.Fab")
			(effects
				(font
					(size 1.27 1.27)
				)
				(justify mirror)
			)
		)
		(duplicate_pad_numbers_are_jumpers no)
		(fp_line
			(start 2.549906 2.549906)
			(end 2.4384 2.549906)
			(stroke
				(width 0.1524)
				(type default)
			)
			(layer "B.SilkS")
		)
		(fp_line
			(start 2.549906 2.2352)
			(end 2.549906 2.549906)
			(stroke
				(width 0.1524)
				(type default)
			)
			(layer "B.SilkS")
		)
		(fp_line
			(start 2.549906 1.4986)
			(end 2.549906 1.7526)
			(stroke
				(width 0.1524)
				(type default)
			)
			(layer "B.SilkS")
		)
		(fp_line
			(start 2.549906 0.6858)
			(end 2.549906 0.9144)
			(stroke
				(width 0.1524)
				(type default)
			)
			(layer "B.SilkS")
		)
		(fp_line
			(start 2.549906 -0.9144)
			(end 2.549906 0.1016)
			(stroke
				(width 0.1524)
				(type default)
			)
			(layer "B.SilkS")
		)
		(fp_line
			(start 2.549906 -1.7526)
			(end 2.549906 -1.4986)
			(stroke
				(width 0.1524)
				(type default)
			)
			(layer "B.SilkS")
		)
		(fp_line
			(start 2.549906 -2.549906)
			(end 2.549906 -2.2352)
			(stroke
				(width 0.1524)
				(type default)
			)
			(layer "B.SilkS")
		)
		(fp_line
			(start 2.4384 -2.549906)
			(end 2.549906 -2.549906)
			(stroke
				(width 0.1524)
				(type default)
			)
			(layer "B.SilkS")
		)
		(fp_line
			(start 2.199894 -3.9624)
			(end 2.199894 -2.9464)
			(stroke
				(width 0.1524)
				(type default)
			)
			(layer "B.SilkS")
		)
		(fp_line
			(start 1.800098 2.9464)
			(end 1.800098 3.4544)
			(stroke
				(width 0.1524)
				(type default)
			)
			(layer "B.SilkS")
		)
		(fp_line
			(start 0.199898 -3.4544)
			(end 0.199898 -2.9464)
			(stroke
				(width 0.1524)
				(type default)
			)
			(layer "B.SilkS")
		)
		(fp_line
			(start -0.199898 2.9464)
			(end -0.199898 3.9624)
			(stroke
				(width 0.1524)
				(type default)
			)
			(layer "B.SilkS")
		)
		(fp_line
			(start -1.800098 -3.9624)
			(end -1.800098 -2.9464)
			(stroke
				(width 0.1524)
				(type default)
			)
			(layer "B.SilkS")
		)
		(fp_line
			(start -2.199894 2.9464)
			(end -2.199894 3.4544)
			(stroke
				(width 0.1524)
				(type default)
			)
			(layer "B.SilkS")
		)
		(fp_line
			(start -2.4384 2.549906)
			(end -2.549906 2.549906)
			(stroke
				(width 0.1524)
				(type default)
			)
			(layer "B.SilkS")
		)
		(fp_line
			(start -2.549906 2.549906)
			(end -2.549906 2.2352)
			(stroke
				(width 0.1524)
				(type default)
			)
			(layer "B.SilkS")
		)
		(fp_line
			(start -2.549906 1.7526)
			(end -2.549906 1.4986)
			(stroke
				(width 0.1524)
				(type default)
			)
			(layer "B.SilkS")
		)
		(fp_line
			(start -2.549906 0.9144)
			(end -2.549906 -0.1016)
			(stroke
				(width 0.1524)
				(type default)
			)
			(layer "B.SilkS")
		)
		(fp_line
			(start -2.549906 -0.6858)
			(end -2.549906 -0.9144)
			(stroke
				(width 0.1524)
				(type default)
			)
			(layer "B.SilkS")
		)
		(fp_line
			(start -2.549906 -1.4986)
			(end -2.549906 -1.7526)
			(stroke
				(width 0.1524)
				(type default)
			)
			(layer "B.SilkS")
		)
		(fp_line
			(start -2.549906 -2.2352)
			(end -2.549906 -2.549906)
			(stroke
				(width 0.1524)
				(type default)
			)
			(layer "B.SilkS")
		)
		(fp_line
			(start -2.549906 -2.549906)
			(end -2.4384 -2.549906)
			(stroke
				(width 0.1524)
				(type default)
			)
			(layer "B.SilkS")
		)
		(fp_poly
			(pts
				(xy 3.531362 -1.49606) (xy 2.939034 -1.199896) (xy 3.531362 -0.903732)
			)
			(stroke
				(width 0)
				(type default)
			)
			(fill yes)
			(layer "B.SilkS")
		)
		(fp_line
			(start 2.549906 2.549906)
			(end -2.549906 2.549906)
			(stroke
				(width 0.1)
				(type default)
			)
			(layer "B.Fab")
		)
		(fp_line
			(start 2.549906 -2.549906)
			(end 2.549906 2.549906)
			(stroke
				(width 0.1)
				(type default)
			)
			(layer "B.Fab")
		)
		(fp_line
			(start 2.199894 -3.9624)
			(end 2.199894 -2.9464)
			(stroke
				(width 0.1)
				(type default)
			)
			(layer "B.Fab")
		)
		(fp_line
			(start 1.800098 2.9464)
			(end 1.800098 3.4544)
			(stroke
				(width 0.1)
				(type default)
			)
			(layer "B.Fab")
		)
		(fp_line
			(start 0.199898 -3.4544)
			(end 0.199898 -2.9464)
			(stroke
				(width 0.1)
				(type default)
			)
			(layer "B.Fab")
		)
		(fp_line
			(start -0.199898 2.9464)
			(end -0.199898 3.9624)
			(stroke
				(width 0.1)
				(type default)
			)
			(layer "B.Fab")
		)
		(fp_line
			(start -1.800098 -3.9624)
			(end -1.800098 -2.9464)
			(stroke
				(width 0.1)
				(type default)
			)
			(layer "B.Fab")
		)
		(fp_line
			(start -2.199894 2.9464)
			(end -2.199894 3.4544)
			(stroke
				(width 0.1)
				(type default)
			)
			(layer "B.Fab")
		)
		(fp_line
			(start -2.549906 2.549906)
			(end -2.549906 -2.549906)
			(stroke
				(width 0.1)
				(type default)
			)
			(layer "B.Fab")
		)
		(fp_line
			(start -2.549906 -2.549906)
			(end 2.549906 -2.549906)
			(stroke
				(width 0.1)
				(type default)
			)
			(layer "B.Fab")
		)
		(fp_poly
			(pts
				(xy 3.7084 -1.584706) (xy 2.939034 -1.199896) (xy 3.7084 -0.81534)
			)
			(stroke
				(width 0)
				(type default)
			)
			(fill yes)
			(layer "B.Fab")
		)
		(fp_text user "3"
			(at 3.299968 1.1938 90)
			(unlocked yes)
			(layer "B.SilkS")
			(effects
				(font
					(size 0.635 0.4064)
					(thickness 0.1524)
				)
				(justify mirror)
			)
		)
		(fp_text user "30"
			(at 2.9464 -3.045968 180)
			(unlocked yes)
			(layer "B.SilkS")
			(effects
				(font
					(size 0.635 0.4064)
					(thickness 0.1524)
				)
				(justify mirror)
			)
		)
		(fp_text user "4"
			(at 2.6416 3.151632 180)
			(unlocked yes)
			(layer "B.SilkS")
			(effects
				(font
					(size 0.635 0.4064)
					(thickness 0.1524)
				)
				(justify mirror)
			)
		)
		(fp_text user "19"
			(at -2.8448 -3.096768 180)
			(unlocked yes)
			(layer "B.SilkS")
			(effects
				(font
					(size 0.635 0.4064)
					(thickness 0.1524)
				)
				(justify mirror)
			)
		)
		(fp_text user "15"
			(at -2.8956 3.126232 180)
			(unlocked yes)
			(layer "B.SilkS")
			(effects
				(font
					(size 0.635 0.4064)
					(thickness 0.1524)
				)
				(justify mirror)
			)
		)
		(fp_text user "18"
			(at -3.304032 -1.2192 90)
			(unlocked yes)
			(layer "B.SilkS")
			(effects
				(font
					(size 0.635 0.4064)
					(thickness 0.1524)
				)
				(justify mirror)
			)
		)
		(fp_text user "16"
			(at -3.329432 1.2192 90)
			(unlocked yes)
			(layer "B.SilkS")
			(effects
				(font
					(size 0.635 0.4064)
					(thickness 0.1524)
				)
				(justify mirror)
			)
		)
		(fp_text user "3"
			(at 3.299968 1.1938 90)
			(unlocked yes)
			(layer "B.Fab")
			(effects
				(font
					(size 0.635 0.4064)
					(thickness 0.1524)
				)
				(justify mirror)
			)
		)
		(fp_text user "30"
			(at 2.9464 -3.045968 180)
			(unlocked yes)
			(layer "B.Fab")
			(effects
				(font
					(size 0.635 0.4064)
					(thickness 0.1524)
				)
				(justify mirror)
			)
		)
		(fp_text user "4"
			(at 2.6416 3.151632 180)
			(unlocked yes)
			(layer "B.Fab")
			(effects
				(font
					(size 0.635 0.4064)
					(thickness 0.1524)
				)
				(justify mirror)
			)
		)
		(fp_text user "19"
			(at -2.8448 -3.096768 180)
			(unlocked yes)
			(layer "B.Fab")
			(effects
				(font
					(size 0.635 0.4064)
					(thickness 0.1524)
				)
				(justify mirror)
			)
		)
		(fp_text user "15"
			(at -2.8956 3.126232 180)
			(unlocked yes)
			(layer "B.Fab")
			(effects
				(font
					(size 0.635 0.4064)
					(thickness 0.1524)
				)
				(justify mirror)
			)
		)
		(fp_text user "18"
			(at -3.304032 -1.2192 90)
			(unlocked yes)
			(layer "B.Fab")
			(effects
				(font
					(size 0.635 0.4064)
					(thickness 0.1524)
				)
				(justify mirror)
			)
		)
		(fp_text user "16"
			(at -3.329432 1.2192 90)
			(unlocked yes)
			(layer "B.Fab")
			(effects
				(font
					(size 0.635 0.4064)
					(thickness 0.1524)
				)
				(justify mirror)
			)
		)
		(pad "1" smd circle
			(at 1.599946 -1.199896 90)
			(size 0 0)
			(layers "B.Cu" "B.Mask" "B.Paste")
			(net "P52V_HSC")
		)
		(pad "2" smd rect
			(at 1.549908 0.40005 270)
			(size 0.3048 2.5146)
			(layers "B.Cu" "B.Mask" "B.Paste")
			(net "P52V_HSC")
		)
		(pad "3" smd rect
			(at 1.549908 1.199896 270)
			(size 0.3048 2.5146)
			(layers "B.Cu" "B.Mask" "B.Paste")
			(net "P52V_FAN_2")
		)
		(pad "4" smd circle
			(at 2.199894 2.350008 180)
			(size 0 0)
			(layers "B.Cu" "B.Mask" "B.Paste")
			(net "P52V_FAN_2")
		)
		(pad "5" smd rect
			(at 1.800098 2.350008)
			(size 0.1778 0.9144)
			(layers "B.Cu" "B.Mask" "B.Paste")
			(net "P52V_FAN_2")
		)
		(pad "6" smd rect
			(at 1.400048 2.350008)
			(size 0.1778 0.9144)
			(layers "B.Cu" "B.Mask" "B.Paste")
			(net "P52V_FAN_2")
		)
		(pad "7" smd rect
			(at 0.999998 2.350008)
			(size 0.1778 0.9144)
			(layers "B.Cu" "B.Mask" "B.Paste")
			(net "P52V_FAN_2")
		)
		(pad "8" smd rect
			(at 0.599948 2.350008)
			(size 0.1778 0.9144)
			(layers "B.Cu" "B.Mask" "B.Paste")
			(net "P52V_FAN_2")
		)
		(pad "9" smd rect
			(at 0.199898 2.350008)
			(size 0.1778 0.9144)
			(layers "B.Cu" "B.Mask" "B.Paste")
			(net "P52V_FAN_2")
		)
		(pad "10" smd rect
			(at -0.199898 2.350008)
			(size 0.1778 0.9144)
			(layers "B.Cu" "B.Mask" "B.Paste")
			(net "P52V_FAN_2")
		)
		(pad "11" smd rect
			(at -0.599948 2.350008)
			(size 0.1778 0.9144)
			(layers "B.Cu" "B.Mask" "B.Paste")
			(net "P52V_FAN_2")
		)
		(pad "12" smd rect
			(at -0.999998 2.350008)
			(size 0.1778 0.9144)
			(layers "B.Cu" "B.Mask" "B.Paste")
			(net "P52V_FAN_2")
		)
		(pad "13" smd rect
			(at -1.400048 2.350008)
			(size 0.1778 0.9144)
			(layers "B.Cu" "B.Mask" "B.Paste")
			(net "P52V_FAN_2")
		)
		(pad "14" smd rect
			(at -1.800098 2.350008)
			(size 0.1778 0.9144)
			(layers "B.Cu" "B.Mask" "B.Paste")
			(net "P52V_FAN_2")
		)
		(pad "15" smd circle
			(at -2.199894 2.350008 180)
			(size 0 0)
			(layers "B.Cu" "B.Mask" "B.Paste")
			(net "P52V_FAN_2")
		)
		(pad "16" smd rect
			(at -1.549908 1.199896 270)
			(size 0.3048 2.5146)
			(layers "B.Cu" "B.Mask" "B.Paste")
			(net "P52V_FAN_2")
		)
		(pad "17" smd rect
			(at -1.549908 -0.40005 270)
			(size 0.3048 2.5146)
			(layers "B.Cu" "B.Mask" "B.Paste")
			(net "P52V_FAN_2")
		)
		(pad "18" smd rect
			(at -1.549908 -1.199896 270)
			(size 0.3048 2.5146)
			(layers "B.Cu" "B.Mask" "B.Paste")
			(net "P52V_HSC")
		)
		(pad "19" smd circle
			(at -2.199894 -2.350008)
			(size 0 0)
			(layers "B.Cu" "B.Mask" "B.Paste")
			(net "FAN_2_CS")
		)
		(pad "20" smd rect
			(at -1.800098 -2.350008)
			(size 0.1778 0.9144)
			(layers "B.Cu" "B.Mask" "B.Paste")
			(net "FAN_2_IMON")
		)
		(pad "21" smd rect
			(at -1.400048 -2.350008)
			(size 0.1778 0.9144)
			(layers "B.Cu" "B.Mask" "B.Paste")
			(net "FAN_2_SS")
		)
		(pad "22" smd rect
			(at -0.999998 -2.350008)
			(size 0.1778 0.9144)
			(layers "B.Cu" "B.Mask" "B.Paste")
			(net "FAN_2_FAULT")
		)
		(pad "23" smd rect
			(at -0.599948 -2.350008)
			(size 0.1778 0.9144)
			(layers "B.Cu" "B.Mask" "B.Paste")
			(net "FAN_2_TIMER")
		)
		(pad "24" smd rect
			(at -0.199898 -2.350008)
			(size 0.1778 0.9144)
			(layers "B.Cu" "B.Mask" "B.Paste")
			(net "FAN_2_CLREF")
		)
		(pad "25" smd rect
			(at 0.199898 -2.350008)
			(size 0.1778 0.9144)
			(layers "B.Cu" "B.Mask" "B.Paste")
			(net "GND")
		)
		(pad "26" smd rect
			(at 0.599948 -2.350008)
			(size 0.1778 0.9144)
			(layers "B.Cu" "B.Mask" "B.Paste")
			(net "FAN_2_ON")
		)
		(pad "27" smd rect
			(at 0.999998 -2.350008)
			(size 0.1778 0.9144)
			(layers "B.Cu" "B.Mask" "B.Paste")
			(net "FAN_2_P3V_R")
		)
		(pad "28" smd rect
			(at 1.400048 -2.350008)
			(size 0.1778 0.9144)
			(layers "B.Cu" "B.Mask" "B.Paste")
			(net "FAN_2_P5V")
		)
		(pad "29" smd rect
			(at 1.800098 -2.350008)
			(size 0.1778 0.9144)
			(layers "B.Cu" "B.Mask" "B.Paste")
			(net "FAN_2_TEMP")
		)
		(pad "30" smd circle
			(at 2.199894 -2.350008)
			(size 0 0)
			(layers "B.Cu" "B.Mask" "B.Paste")
			(net "FAN_2_MODE")
		)
	)
	(footprint ""
		(layer "B.Cu")
		(at 18.430494 -73.971912 -90)
		(property "Reference" "PR62"
			(at 0 0 90)
			(layer "B.SilkS")
			(hide yes)
			(effects
				(font
					(size 1.27 1.27)
				)
				(justify mirror)
			)
		)
		(property "Value" ""
			(at 0 0 90)
			(layer "B.Fab")
			(effects
				(font
					(size 1.27 1.27)
				)
				(justify mirror)
			)
		)
		(duplicate_pad_numbers_are_jumpers no)
		(fp_line
			(start -0.7874 0.4064)
			(end 0.7874 0.4064)
			(stroke
				(width 0.1524)
				(type default)
			)
			(layer "B.SilkS")
		)
		(fp_line
			(start 0.7874 0.4064)
			(end 0.7874 -0.4064)
			(stroke
				(width 0.1524)
				(type default)
			)
			(layer "B.SilkS")
		)
		(fp_line
			(start -0.7874 -0.4064)
			(end -0.7874 0.4064)
			(stroke
				(width 0.1524)
				(type default)
			)
			(layer "B.SilkS")
		)
		(fp_line
			(start 0.7874 -0.4064)
			(end -0.7874 -0.4064)
			(stroke
				(width 0.1524)
				(type default)
			)
			(layer "B.SilkS")
		)
		(fp_line
			(start -0.67945 0.3048)
			(end -0.120396 0.3048)
			(stroke
				(width 0.1)
				(type default)
			)
			(layer "B.Fab")
		)
		(fp_line
			(start -0.120396 0.3048)
			(end -0.120396 0.2794)
			(stroke
				(width 0.1)
				(type default)
			)
			(layer "B.Fab")
		)
		(fp_line
			(start 0.12065 0.3048)
			(end 0.67945 0.3048)
			(stroke
				(width 0.1)
				(type default)
			)
			(layer "B.Fab")
		)
		(fp_line
			(start 0.67945 0.3048)
			(end 0.67945 -0.305054)
			(stroke
				(width 0.1)
				(type default)
			)
			(layer "B.Fab")
		)
		(fp_line
			(start -0.120396 0.2794)
			(end 0.12065 0.2794)
			(stroke
				(width 0.1)
				(type default)
			)
			(layer "B.Fab")
		)
		(fp_line
			(start 0.12065 0.2794)
			(end 0.12065 0.3048)
			(stroke
				(width 0.1)
				(type default)
			)
			(layer "B.Fab")
		)
		(fp_line
			(start -0.12065 -0.2794)
			(end -0.12065 -0.3048)
			(stroke
				(width 0.1)
				(type default)
			)
			(layer "B.Fab")
		)
		(fp_line
			(start 0.12065 -0.2794)
			(end -0.12065 -0.2794)
			(stroke
				(width 0.1)
				(type default)
			)
			(layer "B.Fab")
		)
		(fp_line
			(start -0.67945 -0.3048)
			(end -0.67945 0.3048)
			(stroke
				(width 0.1)
				(type default)
			)
			(layer "B.Fab")
		)
		(fp_line
			(start -0.12065 -0.3048)
			(end -0.67945 -0.3048)
			(stroke
				(width 0.1)
				(type default)
			)
			(layer "B.Fab")
		)
		(fp_line
			(start 0.12065 -0.305054)
			(end 0.12065 -0.2794)
			(stroke
				(width 0.1)
				(type default)
			)
			(layer "B.Fab")
		)
		(fp_line
			(start 0.67945 -0.305054)
			(end 0.12065 -0.305054)
			(stroke
				(width 0.1)
				(type default)
			)
			(layer "B.Fab")
		)
		(pad "1" smd rect
			(at 0.40005 0 270)
			(size 0.4572 0.508)
			(layers "B.Cu" "B.Mask" "B.Paste")
			(net "GND")
		)
		(pad "2" smd rect
			(at -0.40005 0 270)
			(size 0.4572 0.508)
			(layers "B.Cu" "B.Mask" "B.Paste")
			(net "FAN_5_IMON")
		)
	)
	(footprint ""
		(layer "B.Cu")
		(at 16.906494 -71.177912 -90)
		(property "Reference" "U393"
			(at 1.200912 -3.005836 270)
			(unlocked yes)
			(layer "B.SilkS")
			(effects
				(font
					(size 0.7874 0.5842)
					(thickness 0.1524)
				)
				(justify left mirror)
			)
		)
		(property "Value" ""
			(at 0 0 90)
			(layer "B.Fab")
			(effects
				(font
					(size 1.27 1.27)
				)
				(justify mirror)
			)
		)
		(duplicate_pad_numbers_are_jumpers no)
		(fp_line
			(start -1.3462 1.1938)
			(end -1.3462 -1.1938)
			(stroke
				(width 0.1524)
				(type default)
			)
			(layer "B.SilkS")
		)
		(fp_line
			(start 1.3462 1.1938)
			(end -1.3462 1.1938)
			(stroke
				(width 0.1524)
				(type default)
			)
			(layer "B.SilkS")
		)
		(fp_line
			(start -1.3462 -1.1938)
			(end 1.3462 -1.1938)
			(stroke
				(width 0.1524)
				(type default)
			)
			(layer "B.SilkS")
		)
		(fp_line
			(start 1.3462 -1.1938)
			(end 1.3462 1.1684)
			(stroke
				(width 0.1524)
				(type default)
			)
			(layer "B.SilkS")
		)
		(fp_poly
			(pts
				(xy 1.447038 -0.760476) (xy 2.052066 -0.457962) (xy 2.052066 -1.06299)
			)
			(stroke
				(width 0)
				(type default)
			)
			(fill yes)
			(layer "B.SilkS")
		)
		(fp_line
			(start -0.674878 1.124966)
			(end -0.674878 -1.124966)
			(stroke
				(width 0.1)
				(type default)
			)
			(layer "B.Fab")
		)
		(fp_line
			(start 0.674878 1.124966)
			(end -0.674878 1.124966)
			(stroke
				(width 0.1)
				(type default)
			)
			(layer "B.Fab")
		)
		(fp_line
			(start -0.674878 -1.124966)
			(end 0.674878 -1.124966)
			(stroke
				(width 0.1)
				(type default)
			)
			(layer "B.Fab")
		)
		(fp_line
			(start 0.674878 -1.124966)
			(end 0.674878 1.124966)
			(stroke
				(width 0.1)
				(type default)
			)
			(layer "B.Fab")
		)
		(fp_poly
			(pts
				(xy 1.447038 -0.760476) (xy 2.052066 -0.457962) (xy 2.052066 -1.06299)
			)
			(stroke
				(width 0)
				(type default)
			)
			(fill yes)
			(layer "B.Fab")
		)
		(pad "1" smd rect
			(at 0.899922 -0.750062 90)
			(size 0.6096 0.6096)
			(layers "B.Cu" "B.Mask" "B.Paste")
			(net "NC_U393_P1")
		)
		(pad "2" smd rect
			(at 0.899922 0)
			(size 0.4064 0.6096)
			(layers "B.Cu" "B.Mask" "B.Paste")
			(net "FAN_5_PRSNT_BUF_N")
		)
		(pad "3" smd rect
			(at 0.899922 0.750062 90)
			(size 0.6096 0.6096)
			(layers "B.Cu" "B.Mask" "B.Paste")
			(net "GND")
		)
		(pad "4" smd rect
			(at -0.899922 0.750062 90)
			(size 0.6096 0.6096)
			(layers "B.Cu" "B.Mask" "B.Paste")
			(net "FAN_5_PRESENT")
		)
		(pad "5" smd rect
			(at -0.899922 -0.750062 90)
			(size 0.6096 0.6096)
			(layers "B.Cu" "B.Mask" "B.Paste")
			(net "P3V3_AUX")
		)
	)
	(footprint ""
		(layer "B.Cu")
		(at 6.107176 -45.9232)
		(property "Reference" "C2110"
			(at 0 0 0)
			(layer "B.SilkS")
			(hide yes)
			(effects
				(font
					(size 1.27 1.27)
				)
				(justify mirror)
			)
		)
		(property "Value" ""
			(at 0 0 0)
			(layer "B.Fab")
			(effects
				(font
					(size 1.27 1.27)
				)
				(justify mirror)
			)
		)
		(duplicate_pad_numbers_are_jumpers no)
		(fp_line
			(start -2.2098 -0.9398)
			(end -2.2098 0.9398)
			(stroke
				(width 0.1524)
				(type default)
			)
			(layer "B.SilkS")
		)
		(fp_line
			(start -2.2098 0.9398)
			(end 2.2098 0.9398)
			(stroke
				(width 0.1524)
				(type default)
			)
			(layer "B.SilkS")
		)
		(fp_line
			(start 2.2098 -0.9398)
			(end -2.2098 -0.9398)
			(stroke
				(width 0.1524)
				(type default)
			)
			(layer "B.SilkS")
		)
		(fp_line
			(start 2.2098 0.9398)
			(end 2.2098 -0.9398)
			(stroke
				(width 0.1524)
				(type default)
			)
			(layer "B.SilkS")
		)
		(fp_line
			(start -1.700022 -0.899922)
			(end -1.700022 0.899922)
			(stroke
				(width 0.1)
				(type default)
			)
			(layer "B.Fab")
		)
		(fp_line
			(start -1.700022 0.899922)
			(end 1.700022 0.899922)
			(stroke
				(width 0.1)
				(type default)
			)
			(layer "B.Fab")
		)
		(fp_line
			(start 1.700022 -0.899922)
			(end -1.700022 -0.899922)
			(stroke
				(width 0.1)
				(type default)
			)
			(layer "B.Fab")
		)
		(fp_line
			(start 1.700022 0.899922)
			(end 1.700022 -0.899922)
			(stroke
				(width 0.1)
				(type default)
			)
			(layer "B.Fab")
		)
		(pad "1" smd rect
			(at 1.4732 0)
			(size 1.1684 1.5748)
			(layers "B.Cu" "B.Mask" "B.Paste")
			(net "P52V_FAN_4")
		)
		(pad "2" smd rect
			(at -1.4732 0)
			(size 1.1684 1.5748)
			(layers "B.Cu" "B.Mask" "B.Paste")
			(net "GND")
		)
	)
	(footprint ""
		(layer "B.Cu")
		(at 17.653 -127.381 180)
		(property "Reference" "R5436"
			(at 0 0 0)
			(layer "B.SilkS")
			(hide yes)
			(effects
				(font
					(size 1.27 1.27)
				)
				(justify mirror)
			)
		)
		(property "Value" ""
			(at 0 0 0)
			(layer "B.Fab")
			(effects
				(font
					(size 1.27 1.27)
				)
				(justify mirror)
			)
		)
		(duplicate_pad_numbers_are_jumpers no)
		(fp_line
			(start 0.7874 0.4064)
			(end 0.7874 -0.4064)
			(stroke
				(width 0.1524)
				(type default)
			)
			(layer "B.SilkS")
		)
		(fp_line
			(start 0.7874 -0.4064)
			(end -0.7874 -0.4064)
			(stroke
				(width 0.1524)
				(type default)
			)
			(layer "B.SilkS")
		)
		(fp_line
			(start -0.7874 0.4064)
			(end 0.7874 0.4064)
			(stroke
				(width 0.1524)
				(type default)
			)
			(layer "B.SilkS")
		)
		(fp_line
			(start -0.7874 -0.4064)
			(end -0.7874 0.4064)
			(stroke
				(width 0.1524)
				(type default)
			)
			(layer "B.SilkS")
		)
		(fp_line
			(start 0.67945 0.3048)
			(end 0.67945 -0.305054)
			(stroke
				(width 0.1)
				(type default)
			)
			(layer "B.Fab")
		)
		(fp_line
			(start 0.67945 -0.305054)
			(end 0.12065 -0.305054)
			(stroke
				(width 0.1)
				(type default)
			)
			(layer "B.Fab")
		)
		(fp_line
			(start 0.12065 0.3048)
			(end 0.67945 0.3048)
			(stroke
				(width 0.1)
				(type default)
			)
			(layer "B.Fab")
		)
		(fp_line
			(start 0.12065 0.2794)
			(end 0.12065 0.3048)
			(stroke
				(width 0.1)
				(type default)
			)
			(layer "B.Fab")
		)
		(fp_line
			(start 0.12065 -0.2794)
			(end -0.12065 -0.2794)
			(stroke
				(width 0.1)
				(type default)
			)
			(layer "B.Fab")
		)
		(fp_line
			(start 0.12065 -0.305054)
			(end 0.12065 -0.2794)
			(stroke
				(width 0.1)
				(type default)
			)
			(layer "B.Fab")
		)
		(fp_line
			(start -0.120396 0.3048)
			(end -0.120396 0.2794)
			(stroke
				(width 0.1)
				(type default)
			)
			(layer "B.Fab")
		)
		(fp_line
			(start -0.120396 0.2794)
			(end 0.12065 0.2794)
			(stroke
				(width 0.1)
				(type default)
			)
			(layer "B.Fab")
		)
		(fp_line
			(start -0.12065 -0.2794)
			(end -0.12065 -0.3048)
			(stroke
				(width 0.1)
				(type default)
			)
			(layer "B.Fab")
		)
		(fp_line
			(start -0.12065 -0.3048)
			(end -0.67945 -0.3048)
			(stroke
				(width 0.1)
				(type default)
			)
			(layer "B.Fab")
		)
		(fp_line
			(start -0.67945 0.3048)
			(end -0.120396 0.3048)
			(stroke
				(width 0.1)
				(type default)
			)
			(layer "B.Fab")
		)
		(fp_line
			(start -0.67945 -0.3048)
			(end -0.67945 0.3048)
			(stroke
				(width 0.1)
				(type default)
			)
			(layer "B.Fab")
		)
		(pad "1" smd rect
			(at 0.40005 0 180)
			(size 0.4572 0.508)
			(layers "B.Cu" "B.Mask" "B.Paste")
			(net "FAN_5_TACH_IL")
		)
		(pad "2" smd rect
			(at -0.40005 0 180)
			(size 0.4572 0.508)
			(layers "B.Cu" "B.Mask" "B.Paste")
			(net "GND")
		)
	)
	(footprint ""
		(layer "B.Cu")
		(at 33.4518 -279.0444)
		(property "Reference" "C2096"
			(at 0 0 0)
			(layer "B.SilkS")
			(hide yes)
			(effects
				(font
					(size 1.27 1.27)
				)
				(justify mirror)
			)
		)
		(property "Value" ""
			(at 0 0 0)
			(layer "B.Fab")
			(effects
				(font
					(size 1.27 1.27)
				)
				(justify mirror)
			)
		)
		(duplicate_pad_numbers_are_jumpers no)
		(fp_line
			(start -2.2098 -0.9398)
			(end -2.2098 0.9398)
			(stroke
				(width 0.1524)
				(type default)
			)
			(layer "B.SilkS")
		)
		(fp_line
			(start -2.2098 0.9398)
			(end 2.2098 0.9398)
			(stroke
				(width 0.1524)
				(type default)
			)
			(layer "B.SilkS")
		)
		(fp_line
			(start 2.2098 -0.9398)
			(end -2.2098 -0.9398)
			(stroke
				(width 0.1524)
				(type default)
			)
			(layer "B.SilkS")
		)
		(fp_line
			(start 2.2098 0.9398)
			(end 2.2098 -0.9398)
			(stroke
				(width 0.1524)
				(type default)
			)
			(layer "B.SilkS")
		)
		(fp_line
			(start -1.700022 -0.899922)
			(end -1.700022 0.899922)
			(stroke
				(width 0.1)
				(type default)
			)
			(layer "B.Fab")
		)
		(fp_line
			(start -1.700022 0.899922)
			(end 1.700022 0.899922)
			(stroke
				(width 0.1)
				(type default)
			)
			(layer "B.Fab")
		)
		(fp_line
			(start 1.700022 -0.899922)
			(end -1.700022 -0.899922)
			(stroke
				(width 0.1)
				(type default)
			)
			(layer "B.Fab")
		)
		(fp_line
			(start 1.700022 0.899922)
			(end 1.700022 -0.899922)
			(stroke
				(width 0.1)
				(type default)
			)
			(layer "B.Fab")
		)
		(pad "1" smd rect
			(at 1.4732 0)
			(size 1.1684 1.5748)
			(layers "B.Cu" "B.Mask" "B.Paste")
			(net "P52V_FAN_0")
		)
		(pad "2" smd rect
			(at -1.4732 0)
			(size 1.1684 1.5748)
			(layers "B.Cu" "B.Mask" "B.Paste")
			(net "GND")
		)
	)
	(footprint ""
		(layer "B.Cu")
		(at 6.223 -249.047 180)
		(property "Reference" "PR69"
			(at 0 0 0)
			(layer "B.SilkS")
			(hide yes)
			(effects
				(font
					(size 1.27 1.27)
				)
				(justify mirror)
			)
		)
		(property "Value" ""
			(at 0 0 0)
			(layer "B.Fab")
			(effects
				(font
					(size 1.27 1.27)
				)
				(justify mirror)
			)
		)
		(duplicate_pad_numbers_are_jumpers no)
		(fp_line
			(start 0.7874 0.4064)
			(end 0.7874 -0.4064)
			(stroke
				(width 0.1524)
				(type default)
			)
			(layer "B.SilkS")
		)
		(fp_line
			(start 0.7874 -0.4064)
			(end -0.7874 -0.4064)
			(stroke
				(width 0.1524)
				(type default)
			)
			(layer "B.SilkS")
		)
		(fp_line
			(start -0.7874 0.4064)
			(end 0.7874 0.4064)
			(stroke
				(width 0.1524)
				(type default)
			)
			(layer "B.SilkS")
		)
		(fp_line
			(start -0.7874 -0.4064)
			(end -0.7874 0.4064)
			(stroke
				(width 0.1524)
				(type default)
			)
			(layer "B.SilkS")
		)
		(fp_line
			(start 0.67945 0.3048)
			(end 0.67945 -0.305054)
			(stroke
				(width 0.1)
				(type default)
			)
			(layer "B.Fab")
		)
		(fp_line
			(start 0.67945 -0.305054)
			(end 0.12065 -0.305054)
			(stroke
				(width 0.1)
				(type default)
			)
			(layer "B.Fab")
		)
		(fp_line
			(start 0.12065 0.3048)
			(end 0.67945 0.3048)
			(stroke
				(width 0.1)
				(type default)
			)
			(layer "B.Fab")
		)
		(fp_line
			(start 0.12065 0.2794)
			(end 0.12065 0.3048)
			(stroke
				(width 0.1)
				(type default)
			)
			(layer "B.Fab")
		)
		(fp_line
			(start 0.12065 -0.2794)
			(end -0.12065 -0.2794)
			(stroke
				(width 0.1)
				(type default)
			)
			(layer "B.Fab")
		)
		(fp_line
			(start 0.12065 -0.305054)
			(end 0.12065 -0.2794)
			(stroke
				(width 0.1)
				(type default)
			)
			(layer "B.Fab")
		)
		(fp_line
			(start -0.120396 0.3048)
			(end -0.120396 0.2794)
			(stroke
				(width 0.1)
				(type default)
			)
			(layer "B.Fab")
		)
		(fp_line
			(start -0.120396 0.2794)
			(end 0.12065 0.2794)
			(stroke
				(width 0.1)
				(type default)
			)
			(layer "B.Fab")
		)
		(fp_line
			(start -0.12065 -0.2794)
			(end -0.12065 -0.3048)
			(stroke
				(width 0.1)
				(type default)
			)
			(layer "B.Fab")
		)
		(fp_line
			(start -0.12065 -0.3048)
			(end -0.67945 -0.3048)
			(stroke
				(width 0.1)
				(type default)
			)
			(layer "B.Fab")
		)
		(fp_line
			(start -0.67945 0.3048)
			(end -0.120396 0.3048)
			(stroke
				(width 0.1)
				(type default)
			)
			(layer "B.Fab")
		)
		(fp_line
			(start -0.67945 -0.3048)
			(end -0.67945 0.3048)
			(stroke
				(width 0.1)
				(type default)
			)
			(layer "B.Fab")
		)
		(pad "1" smd circle
			(at 0.40005 0)
			(size 0 0)
			(layers "B.Cu" "B.Mask" "B.Paste")
			(net "FAN_6_CLREF")
		)
		(pad "2" smd circle
			(at -0.40005 0)
			(size 0 0)
			(layers "B.Cu" "B.Mask" "B.Paste")
			(net "GND")
		)
	)
	(footprint ""
		(layer "B.Cu")
		(at 6.223 -250.063)
		(property "Reference" "PC3124"
			(at 0 0 0)
			(layer "B.SilkS")
			(hide yes)
			(effects
				(font
					(size 1.27 1.27)
				)
				(justify mirror)
			)
		)
		(property "Value" ""
			(at 0 0 0)
			(layer "B.Fab")
			(effects
				(font
					(size 1.27 1.27)
				)
				(justify mirror)
			)
		)
		(duplicate_pad_numbers_are_jumpers no)
		(fp_line
			(start -0.7874 -0.4064)
			(end -0.7874 0.4064)
			(stroke
				(width 0.1524)
				(type default)
			)
			(layer "B.SilkS")
		)
		(fp_line
			(start -0.7874 0.4064)
			(end 0.7874 0.4064)
			(stroke
				(width 0.1524)
				(type default)
			)
			(layer "B.SilkS")
		)
		(fp_line
			(start 0.7874 -0.4064)
			(end -0.7874 -0.4064)
			(stroke
				(width 0.1524)
				(type default)
			)
			(layer "B.SilkS")
		)
		(fp_line
			(start 0.7874 0.4064)
			(end 0.7874 -0.4064)
			(stroke
				(width 0.1524)
				(type default)
			)
			(layer "B.SilkS")
		)
		(fp_line
			(start -0.67945 -0.3048)
			(end -0.67945 0.3048)
			(stroke
				(width 0.1)
				(type default)
			)
			(layer "B.Fab")
		)
		(fp_line
			(start -0.67945 0.3048)
			(end -0.120396 0.3048)
			(stroke
				(width 0.1)
				(type default)
			)
			(layer "B.Fab")
		)
		(fp_line
			(start -0.12065 -0.3048)
			(end -0.67945 -0.3048)
			(stroke
				(width 0.1)
				(type default)
			)
			(layer "B.Fab")
		)
		(fp_line
			(start -0.12065 -0.2794)
			(end -0.12065 -0.3048)
			(stroke
				(width 0.1)
				(type default)
			)
			(layer "B.Fab")
		)
		(fp_line
			(start -0.120396 0.2794)
			(end 0.12065 0.2794)
			(stroke
				(width 0.1)
				(type default)
			)
			(layer "B.Fab")
		)
		(fp_line
			(start -0.120396 0.3048)
			(end -0.120396 0.2794)
			(stroke
				(width 0.1)
				(type default)
			)
			(layer "B.Fab")
		)
		(fp_line
			(start 0.12065 -0.305054)
			(end 0.12065 -0.2794)
			(stroke
				(width 0.1)
				(type default)
			)
			(layer "B.Fab")
		)
		(fp_line
			(start 0.12065 -0.2794)
			(end -0.12065 -0.2794)
			(stroke
				(width 0.1)
				(type default)
			)
			(layer "B.Fab")
		)
		(fp_line
			(start 0.12065 0.2794)
			(end 0.12065 0.3048)
			(stroke
				(width 0.1)
				(type default)
			)
			(layer "B.Fab")
		)
		(fp_line
			(start 0.12065 0.3048)
			(end 0.67945 0.3048)
			(stroke
				(width 0.1)
				(type default)
			)
			(layer "B.Fab")
		)
		(fp_line
			(start 0.67945 -0.305054)
			(end 0.12065 -0.305054)
			(stroke
				(width 0.1)
				(type default)
			)
			(layer "B.Fab")
		)
		(fp_line
			(start 0.67945 0.3048)
			(end 0.67945 -0.305054)
			(stroke
				(width 0.1)
				(type default)
			)
			(layer "B.Fab")
		)
		(pad "1" smd circle
			(at 0.40005 0 180)
			(size 0 0)
			(layers "B.Cu" "B.Mask" "B.Paste")
			(net "GND")
		)
		(pad "2" smd circle
			(at -0.40005 0 180)
			(size 0 0)
			(layers "B.Cu" "B.Mask" "B.Paste")
			(net "FAN_6_CLREF")
		)
	)
	(footprint ""
		(layer "B.Cu")
		(at 46.6852 -274.9804 -90)
		(property "Reference" "PD1"
			(at 4.7752 -3.749548 270)
			(unlocked yes)
			(layer "B.SilkS")
			(effects
				(font
					(size 0.7874 0.5842)
					(thickness 0.1524)
				)
				(justify left mirror)
			)
		)
		(property "Value" ""
			(at 0 0 90)
			(layer "B.Fab")
			(effects
				(font
					(size 1.27 1.27)
				)
				(justify mirror)
			)
		)
		(duplicate_pad_numbers_are_jumpers no)
		(fp_line
			(start -5.334 3.109976)
			(end -4.8133 3.109976)
			(stroke
				(width 0.1524)
				(type default)
			)
			(layer "B.SilkS")
		)
		(fp_line
			(start -5.334 3.109976)
			(end -5.334 0)
			(stroke
				(width 0.1524)
				(type default)
			)
			(layer "B.SilkS")
		)
		(fp_line
			(start -5.207 3.109976)
			(end -5.207 -3.109976)
			(stroke
				(width 0.1524)
				(type default)
			)
			(layer "B.SilkS")
		)
		(fp_line
			(start -5.1308 3.109976)
			(end -5.1308 -3.109976)
			(stroke
				(width 0.1524)
				(type default)
			)
			(layer "B.SilkS")
		)
		(fp_line
			(start -5.0292 3.109976)
			(end -5.0292 -3.109976)
			(stroke
				(width 0.1524)
				(type default)
			)
			(layer "B.SilkS")
		)
		(fp_line
			(start -4.9276 3.109976)
			(end -4.9276 -3.109976)
			(stroke
				(width 0.1524)
				(type default)
			)
			(layer "B.SilkS")
		)
		(fp_line
			(start -4.826 3.109976)
			(end 4.826 3.109976)
			(stroke
				(width 0.1524)
				(type default)
			)
			(layer "B.SilkS")
		)
		(fp_line
			(start 4.826 3.109976)
			(end 4.826 0)
			(stroke
				(width 0.1524)
				(type default)
			)
			(layer "B.SilkS")
		)
		(fp_line
			(start -1.143 1.397)
			(end -1.143 -1.397)
			(stroke
				(width 0.1524)
				(type default)
			)
			(layer "B.SilkS")
		)
		(fp_line
			(start 1.016 1.016)
			(end -1.016 0)
			(stroke
				(width 0.1524)
				(type default)
			)
			(layer "B.SilkS")
		)
		(fp_line
			(start -5.334 0)
			(end -5.334 -3.109976)
			(stroke
				(width 0.1524)
				(type default)
			)
			(layer "B.SilkS")
		)
		(fp_line
			(start -4.826 0)
			(end -4.826 3.109976)
			(stroke
				(width 0.1524)
				(type default)
			)
			(layer "B.SilkS")
		)
		(fp_line
			(start -1.143 0)
			(end -1.8034 0)
			(stroke
				(width 0.1524)
				(type default)
			)
			(layer "B.SilkS")
		)
		(fp_line
			(start -1.143 0)
			(end 1.016 -1.016)
			(stroke
				(width 0.1524)
				(type default)
			)
			(layer "B.SilkS")
		)
		(fp_line
			(start 1.0922 0)
			(end 1.7018 0)
			(stroke
				(width 0.1524)
				(type default)
			)
			(layer "B.SilkS")
		)
		(fp_line
			(start 4.826 0)
			(end 4.826 -3.109976)
			(stroke
				(width 0.1524)
				(type default)
			)
			(layer "B.SilkS")
		)
		(fp_line
			(start 1.016 -1.016)
			(end 1.016 1.016)
			(stroke
				(width 0.1524)
				(type default)
			)
			(layer "B.SilkS")
		)
		(fp_line
			(start -4.826 -3.109976)
			(end -4.826 0)
			(stroke
				(width 0.1524)
				(type default)
			)
			(layer "B.SilkS")
		)
		(fp_line
			(start -4.8133 -3.109976)
			(end -5.3467 -3.109976)
			(stroke
				(width 0.1524)
				(type default)
			)
			(layer "B.SilkS")
		)
		(fp_line
			(start 4.826 -3.109976)
			(end -4.826 -3.109976)
			(stroke
				(width 0.1524)
				(type default)
			)
			(layer "B.SilkS")
		)
		(fp_line
			(start -3.554984 3.109976)
			(end 3.554984 3.109976)
			(stroke
				(width 0.1)
				(type default)
			)
			(layer "B.Fab")
		)
		(fp_line
			(start 3.554984 3.109976)
			(end 3.554984 -3.109976)
			(stroke
				(width 0.1)
				(type default)
			)
			(layer "B.Fab")
		)
		(fp_line
			(start -1.143 1.397)
			(end -1.143 -1.397)
			(stroke
				(width 0.1)
				(type default)
			)
			(layer "B.Fab")
		)
		(fp_line
			(start 1.016 1.016)
			(end -1.016 0)
			(stroke
				(width 0.1)
				(type default)
			)
			(layer "B.Fab")
		)
		(fp_line
			(start -1.143 0)
			(end -1.8034 0)
			(stroke
				(width 0.1)
				(type default)
			)
			(layer "B.Fab")
		)
		(fp_line
			(start -1.143 0)
			(end 1.016 -1.016)
			(stroke
				(width 0.1)
				(type default)
			)
			(layer "B.Fab")
		)
		(fp_line
			(start 1.0922 0)
			(end 1.7018 0)
			(stroke
				(width 0.1)
				(type default)
			)
			(layer "B.Fab")
		)
		(fp_line
			(start 1.016 -1.016)
			(end 1.016 1.016)
			(stroke
				(width 0.1)
				(type default)
			)
			(layer "B.Fab")
		)
		(fp_line
			(start -3.554984 -3.109976)
			(end -3.554984 3.109976)
			(stroke
				(width 0.1)
				(type default)
			)
			(layer "B.Fab")
		)
		(fp_line
			(start 3.554984 -3.109976)
			(end -3.554984 -3.109976)
			(stroke
				(width 0.1)
				(type default)
			)
			(layer "B.Fab")
		)
		(fp_text user "+"
			(at 4.8006 2.45745 90)
			(unlocked yes)
			(layer "B.SilkS")
			(effects
				(font
					(size 1.905 1.4224)
					(thickness 0.1524)
				)
				(justify left mirror)
			)
		)
		(fp_text user "-"
			(at -7.4422 0.12065 90)
			(unlocked yes)
			(layer "B.SilkS")
			(effects
				(font
					(size 1.905 1.4224)
					(thickness 0.1524)
				)
				(justify left mirror)
			)
		)
		(fp_text user "-"
			(at -6.6802 0.22225 90)
			(unlocked yes)
			(layer "B.Fab")
			(effects
				(font
					(size 1.905 1.4224)
					(thickness 0.1524)
				)
				(justify left mirror)
			)
		)
		(fp_text user "+"
			(at 4.5466 0.19685 90)
			(unlocked yes)
			(layer "B.Fab")
			(effects
				(font
					(size 1.905 1.4224)
					(thickness 0.1524)
				)
				(justify left mirror)
			)
		)
		(pad "A" smd rect
			(at 3.400044 0 270)
			(size 2.5146 3.302)
			(layers "B.Cu" "B.Mask" "B.Paste")
			(net "GND")
		)
		(pad "C" smd rect
			(at -3.400044 0 270)
			(size 2.5146 3.302)
			(layers "B.Cu" "B.Mask" "B.Paste")
			(net "P52V_FAN_0")
		)
	)
	(footprint ""
		(layer "B.Cu")
		(at 17.653 -133.096 180)
		(property "Reference" "R5439"
			(at 0 0 0)
			(layer "B.SilkS")
			(hide yes)
			(effects
				(font
					(size 1.27 1.27)
				)
				(justify mirror)
			)
		)
		(property "Value" ""
			(at 0 0 0)
			(layer "B.Fab")
			(effects
				(font
					(size 1.27 1.27)
				)
				(justify mirror)
			)
		)
		(duplicate_pad_numbers_are_jumpers no)
		(fp_line
			(start 0.7874 0.4064)
			(end 0.7874 -0.4064)
			(stroke
				(width 0.1524)
				(type default)
			)
			(layer "B.SilkS")
		)
		(fp_line
			(start 0.7874 -0.4064)
			(end -0.7874 -0.4064)
			(stroke
				(width 0.1524)
				(type default)
			)
			(layer "B.SilkS")
		)
		(fp_line
			(start -0.7874 0.4064)
			(end 0.7874 0.4064)
			(stroke
				(width 0.1524)
				(type default)
			)
			(layer "B.SilkS")
		)
		(fp_line
			(start -0.7874 -0.4064)
			(end -0.7874 0.4064)
			(stroke
				(width 0.1524)
				(type default)
			)
			(layer "B.SilkS")
		)
		(fp_line
			(start 0.67945 0.3048)
			(end 0.67945 -0.305054)
			(stroke
				(width 0.1)
				(type default)
			)
			(layer "B.Fab")
		)
		(fp_line
			(start 0.67945 -0.305054)
			(end 0.12065 -0.305054)
			(stroke
				(width 0.1)
				(type default)
			)
			(layer "B.Fab")
		)
		(fp_line
			(start 0.12065 0.3048)
			(end 0.67945 0.3048)
			(stroke
				(width 0.1)
				(type default)
			)
			(layer "B.Fab")
		)
		(fp_line
			(start 0.12065 0.2794)
			(end 0.12065 0.3048)
			(stroke
				(width 0.1)
				(type default)
			)
			(layer "B.Fab")
		)
		(fp_line
			(start 0.12065 -0.2794)
			(end -0.12065 -0.2794)
			(stroke
				(width 0.1)
				(type default)
			)
			(layer "B.Fab")
		)
		(fp_line
			(start 0.12065 -0.305054)
			(end 0.12065 -0.2794)
			(stroke
				(width 0.1)
				(type default)
			)
			(layer "B.Fab")
		)
		(fp_line
			(start -0.120396 0.3048)
			(end -0.120396 0.2794)
			(stroke
				(width 0.1)
				(type default)
			)
			(layer "B.Fab")
		)
		(fp_line
			(start -0.120396 0.2794)
			(end 0.12065 0.2794)
			(stroke
				(width 0.1)
				(type default)
			)
			(layer "B.Fab")
		)
		(fp_line
			(start -0.12065 -0.2794)
			(end -0.12065 -0.3048)
			(stroke
				(width 0.1)
				(type default)
			)
			(layer "B.Fab")
		)
		(fp_line
			(start -0.12065 -0.3048)
			(end -0.67945 -0.3048)
			(stroke
				(width 0.1)
				(type default)
			)
			(layer "B.Fab")
		)
		(fp_line
			(start -0.67945 0.3048)
			(end -0.120396 0.3048)
			(stroke
				(width 0.1)
				(type default)
			)
			(layer "B.Fab")
		)
		(fp_line
			(start -0.67945 -0.3048)
			(end -0.67945 0.3048)
			(stroke
				(width 0.1)
				(type default)
			)
			(layer "B.Fab")
		)
		(pad "1" smd rect
			(at 0.40005 0 180)
			(size 0.4572 0.508)
			(layers "B.Cu" "B.Mask" "B.Paste")
			(net "FAN_6_TACH_OL")
		)
		(pad "2" smd rect
			(at -0.40005 0 180)
			(size 0.4572 0.508)
			(layers "B.Cu" "B.Mask" "B.Paste")
			(net "GND")
		)
	)
	(footprint ""
		(layer "B.Cu")
		(at 37.587428 -78.416912 90)
		(property "Reference" "PC16"
			(at 0 0 90)
			(layer "B.SilkS")
			(hide yes)
			(effects
				(font
					(size 1.27 1.27)
				)
				(justify mirror)
			)
		)
		(property "Value" ""
			(at 0 0 90)
			(layer "B.Fab")
			(effects
				(font
					(size 1.27 1.27)
				)
				(justify mirror)
			)
		)
		(duplicate_pad_numbers_are_jumpers no)
		(fp_line
			(start 1.524 -0.762)
			(end -1.524 -0.762)
			(stroke
				(width 0.1524)
				(type default)
			)
			(layer "B.SilkS")
		)
		(fp_line
			(start -1.524 -0.762)
			(end -1.524 0.762)
			(stroke
				(width 0.1524)
				(type default)
			)
			(layer "B.SilkS")
		)
		(fp_line
			(start 1.524 0.762)
			(end 1.524 -0.762)
			(stroke
				(width 0.1524)
				(type default)
			)
			(layer "B.SilkS")
		)
		(fp_line
			(start -1.524 0.762)
			(end 1.524 0.762)
			(stroke
				(width 0.1524)
				(type default)
			)
			(layer "B.SilkS")
		)
		(fp_line
			(start 1.1049 -0.724916)
			(end 1.1049 0.724916)
			(stroke
				(width 0.1)
				(type default)
			)
			(layer "B.Fab")
		)
		(fp_line
			(start -1.1049 -0.724916)
			(end 1.1049 -0.724916)
			(stroke
				(width 0.1)
				(type default)
			)
			(layer "B.Fab")
		)
		(fp_line
			(start 1.1049 0.724916)
			(end -1.1049 0.724916)
			(stroke
				(width 0.1)
				(type default)
			)
			(layer "B.Fab")
		)
		(fp_line
			(start -1.1049 0.724916)
			(end -1.1049 -0.724916)
			(stroke
				(width 0.1)
				(type default)
			)
			(layer "B.Fab")
		)
		(pad "1" smd rect
			(at 0.889 0 90)
			(size 1.016 1.27)
			(layers "B.Cu" "B.Mask" "B.Paste")
			(net "P52V_HSC")
		)
		(pad "2" smd rect
			(at -0.889 0 90)
			(size 1.016 1.27)
			(layers "B.Cu" "B.Mask" "B.Paste")
			(net "GND")
		)
	)
	(footprint ""
		(layer "B.Cu")
		(at 5.50799 -90.371168 -90)
		(property "Reference" "PD11"
			(at 4.7752 -3.749548 270)
			(unlocked yes)
			(layer "B.SilkS")
			(effects
				(font
					(size 0.7874 0.5842)
					(thickness 0.1524)
				)
				(justify left mirror)
			)
		)
		(property "Value" ""
			(at 0 0 90)
			(layer "B.Fab")
			(effects
				(font
					(size 1.27 1.27)
				)
				(justify mirror)
			)
		)
		(duplicate_pad_numbers_are_jumpers no)
		(fp_line
			(start -5.334 3.109976)
			(end -4.8133 3.109976)
			(stroke
				(width 0.1524)
				(type default)
			)
			(layer "B.SilkS")
		)
		(fp_line
			(start -5.334 3.109976)
			(end -5.334 0)
			(stroke
				(width 0.1524)
				(type default)
			)
			(layer "B.SilkS")
		)
		(fp_line
			(start -5.207 3.109976)
			(end -5.207 -3.109976)
			(stroke
				(width 0.1524)
				(type default)
			)
			(layer "B.SilkS")
		)
		(fp_line
			(start -5.1308 3.109976)
			(end -5.1308 -3.109976)
			(stroke
				(width 0.1524)
				(type default)
			)
			(layer "B.SilkS")
		)
		(fp_line
			(start -5.0292 3.109976)
			(end -5.0292 -3.109976)
			(stroke
				(width 0.1524)
				(type default)
			)
			(layer "B.SilkS")
		)
		(fp_line
			(start -4.9276 3.109976)
			(end -4.9276 -3.109976)
			(stroke
				(width 0.1524)
				(type default)
			)
			(layer "B.SilkS")
		)
		(fp_line
			(start -4.826 3.109976)
			(end 4.826 3.109976)
			(stroke
				(width 0.1524)
				(type default)
			)
			(layer "B.SilkS")
		)
		(fp_line
			(start 4.826 3.109976)
			(end 4.826 0)
			(stroke
				(width 0.1524)
				(type default)
			)
			(layer "B.SilkS")
		)
		(fp_line
			(start -1.143 1.397)
			(end -1.143 -1.397)
			(stroke
				(width 0.1524)
				(type default)
			)
			(layer "B.SilkS")
		)
		(fp_line
			(start 1.016 1.016)
			(end -1.016 0)
			(stroke
				(width 0.1524)
				(type default)
			)
			(layer "B.SilkS")
		)
		(fp_line
			(start -5.334 0)
			(end -5.334 -3.109976)
			(stroke
				(width 0.1524)
				(type default)
			)
			(layer "B.SilkS")
		)
		(fp_line
			(start -4.826 0)
			(end -4.826 3.109976)
			(stroke
				(width 0.1524)
				(type default)
			)
			(layer "B.SilkS")
		)
		(fp_line
			(start -1.143 0)
			(end -1.8034 0)
			(stroke
				(width 0.1524)
				(type default)
			)
			(layer "B.SilkS")
		)
		(fp_line
			(start -1.143 0)
			(end 1.016 -1.016)
			(stroke
				(width 0.1524)
				(type default)
			)
			(layer "B.SilkS")
		)
		(fp_line
			(start 1.0922 0)
			(end 1.7018 0)
			(stroke
				(width 0.1524)
				(type default)
			)
			(layer "B.SilkS")
		)
		(fp_line
			(start 4.826 0)
			(end 4.826 -3.109976)
			(stroke
				(width 0.1524)
				(type default)
			)
			(layer "B.SilkS")
		)
		(fp_line
			(start 1.016 -1.016)
			(end 1.016 1.016)
			(stroke
				(width 0.1524)
				(type default)
			)
			(layer "B.SilkS")
		)
		(fp_line
			(start -4.826 -3.109976)
			(end -4.826 0)
			(stroke
				(width 0.1524)
				(type default)
			)
			(layer "B.SilkS")
		)
		(fp_line
			(start -4.8133 -3.109976)
			(end -5.3467 -3.109976)
			(stroke
				(width 0.1524)
				(type default)
			)
			(layer "B.SilkS")
		)
		(fp_line
			(start 4.826 -3.109976)
			(end -4.826 -3.109976)
			(stroke
				(width 0.1524)
				(type default)
			)
			(layer "B.SilkS")
		)
		(fp_line
			(start -3.554984 3.109976)
			(end 3.554984 3.109976)
			(stroke
				(width 0.1)
				(type default)
			)
			(layer "B.Fab")
		)
		(fp_line
			(start 3.554984 3.109976)
			(end 3.554984 -3.109976)
			(stroke
				(width 0.1)
				(type default)
			)
			(layer "B.Fab")
		)
		(fp_line
			(start -1.143 1.397)
			(end -1.143 -1.397)
			(stroke
				(width 0.1)
				(type default)
			)
			(layer "B.Fab")
		)
		(fp_line
			(start 1.016 1.016)
			(end -1.016 0)
			(stroke
				(width 0.1)
				(type default)
			)
			(layer "B.Fab")
		)
		(fp_line
			(start -1.143 0)
			(end -1.8034 0)
			(stroke
				(width 0.1)
				(type default)
			)
			(layer "B.Fab")
		)
		(fp_line
			(start -1.143 0)
			(end 1.016 -1.016)
			(stroke
				(width 0.1)
				(type default)
			)
			(layer "B.Fab")
		)
		(fp_line
			(start 1.0922 0)
			(end 1.7018 0)
			(stroke
				(width 0.1)
				(type default)
			)
			(layer "B.Fab")
		)
		(fp_line
			(start 1.016 -1.016)
			(end 1.016 1.016)
			(stroke
				(width 0.1)
				(type default)
			)
			(layer "B.Fab")
		)
		(fp_line
			(start -3.554984 -3.109976)
			(end -3.554984 3.109976)
			(stroke
				(width 0.1)
				(type default)
			)
			(layer "B.Fab")
		)
		(fp_line
			(start 3.554984 -3.109976)
			(end -3.554984 -3.109976)
			(stroke
				(width 0.1)
				(type default)
			)
			(layer "B.Fab")
		)
		(fp_text user "-"
			(at -6.682232 -1.76276 90)
			(unlocked yes)
			(layer "B.SilkS")
			(effects
				(font
					(size 1.905 1.4224)
					(thickness 0.1524)
				)
				(justify left mirror)
			)
		)
		(fp_text user "+"
			(at 4.620768 -1.76276 90)
			(unlocked yes)
			(layer "B.SilkS")
			(effects
				(font
					(size 1.905 1.4224)
					(thickness 0.1524)
				)
				(justify left mirror)
			)
		)
		(fp_text user "-"
			(at -6.6802 0.22225 90)
			(unlocked yes)
			(layer "B.Fab")
			(effects
				(font
					(size 1.905 1.4224)
					(thickness 0.1524)
				)
				(justify left mirror)
			)
		)
		(fp_text user "+"
			(at 4.5466 0.19685 90)
			(unlocked yes)
			(layer "B.Fab")
			(effects
				(font
					(size 1.905 1.4224)
					(thickness 0.1524)
				)
				(justify left mirror)
			)
		)
		(pad "A" smd rect
			(at 3.400044 0 270)
			(size 2.5146 3.302)
			(layers "B.Cu" "B.Mask" "B.Paste")
			(net "GND")
		)
		(pad "C" smd rect
			(at -3.400044 0 270)
			(size 2.5146 3.302)
			(layers "B.Cu" "B.Mask" "B.Paste")
			(net "P52V_FAN_5")
		)
	)
	(footprint ""
		(layer "B.Cu")
		(at 44.704 -47.625 180)
		(property "Reference" "C2106"
			(at 0 0 0)
			(layer "B.SilkS")
			(hide yes)
			(effects
				(font
					(size 1.27 1.27)
				)
				(justify mirror)
			)
		)
		(property "Value" ""
			(at 0 0 0)
			(layer "B.Fab")
			(effects
				(font
					(size 1.27 1.27)
				)
				(justify mirror)
			)
		)
		(duplicate_pad_numbers_are_jumpers no)
		(fp_line
			(start 2.2098 0.9398)
			(end 2.2098 -0.9398)
			(stroke
				(width 0.1524)
				(type default)
			)
			(layer "B.SilkS")
		)
		(fp_line
			(start 2.2098 -0.9398)
			(end -2.2098 -0.9398)
			(stroke
				(width 0.1524)
				(type default)
			)
			(layer "B.SilkS")
		)
		(fp_line
			(start -2.2098 0.9398)
			(end 2.2098 0.9398)
			(stroke
				(width 0.1524)
				(type default)
			)
			(layer "B.SilkS")
		)
		(fp_line
			(start -2.2098 -0.9398)
			(end -2.2098 0.9398)
			(stroke
				(width 0.1524)
				(type default)
			)
			(layer "B.SilkS")
		)
		(fp_line
			(start 1.700022 0.899922)
			(end 1.700022 -0.899922)
			(stroke
				(width 0.1)
				(type default)
			)
			(layer "B.Fab")
		)
		(fp_line
			(start 1.700022 -0.899922)
			(end -1.700022 -0.899922)
			(stroke
				(width 0.1)
				(type default)
			)
			(layer "B.Fab")
		)
		(fp_line
			(start -1.700022 0.899922)
			(end 1.700022 0.899922)
			(stroke
				(width 0.1)
				(type default)
			)
			(layer "B.Fab")
		)
		(fp_line
			(start -1.700022 -0.899922)
			(end -1.700022 0.899922)
			(stroke
				(width 0.1)
				(type default)
			)
			(layer "B.Fab")
		)
		(pad "1" smd rect
			(at 1.4732 0 180)
			(size 1.1684 1.5748)
			(layers "B.Cu" "B.Mask" "B.Paste")
			(net "P52V_FAN_3")
		)
		(pad "2" smd rect
			(at -1.4732 0 180)
			(size 1.1684 1.5748)
			(layers "B.Cu" "B.Mask" "B.Paste")
			(net "GND")
		)
	)
	(footprint ""
		(layer "B.Cu")
		(at 33.401 -64.837056 90)
		(property "Reference" "PR46"
			(at 0 0 90)
			(layer "B.SilkS")
			(hide yes)
			(effects
				(font
					(size 1.27 1.27)
				)
				(justify mirror)
			)
		)
		(property "Value" ""
			(at 0 0 90)
			(layer "B.Fab")
			(effects
				(font
					(size 1.27 1.27)
				)
				(justify mirror)
			)
		)
		(duplicate_pad_numbers_are_jumpers no)
		(fp_line
			(start 0.7874 -0.4064)
			(end -0.7874 -0.4064)
			(stroke
				(width 0.1524)
				(type default)
			)
			(layer "B.SilkS")
		)
		(fp_line
			(start -0.7874 -0.4064)
			(end -0.7874 0.4064)
			(stroke
				(width 0.1524)
				(type default)
			)
			(layer "B.SilkS")
		)
		(fp_line
			(start 0.7874 0.4064)
			(end 0.7874 -0.4064)
			(stroke
				(width 0.1524)
				(type default)
			)
			(layer "B.SilkS")
		)
		(fp_line
			(start -0.7874 0.4064)
			(end 0.7874 0.4064)
			(stroke
				(width 0.1524)
				(type default)
			)
			(layer "B.SilkS")
		)
		(fp_line
			(start 0.67945 -0.305054)
			(end 0.12065 -0.305054)
			(stroke
				(width 0.1)
				(type default)
			)
			(layer "B.Fab")
		)
		(fp_line
			(start 0.12065 -0.305054)
			(end 0.12065 -0.2794)
			(stroke
				(width 0.1)
				(type default)
			)
			(layer "B.Fab")
		)
		(fp_line
			(start -0.12065 -0.3048)
			(end -0.67945 -0.3048)
			(stroke
				(width 0.1)
				(type default)
			)
			(layer "B.Fab")
		)
		(fp_line
			(start -0.67945 -0.3048)
			(end -0.67945 0.3048)
			(stroke
				(width 0.1)
				(type default)
			)
			(layer "B.Fab")
		)
		(fp_line
			(start 0.12065 -0.2794)
			(end -0.12065 -0.2794)
			(stroke
				(width 0.1)
				(type default)
			)
			(layer "B.Fab")
		)
		(fp_line
			(start -0.12065 -0.2794)
			(end -0.12065 -0.3048)
			(stroke
				(width 0.1)
				(type default)
			)
			(layer "B.Fab")
		)
		(fp_line
			(start 0.12065 0.2794)
			(end 0.12065 0.3048)
			(stroke
				(width 0.1)
				(type default)
			)
			(layer "B.Fab")
		)
		(fp_line
			(start -0.120396 0.2794)
			(end 0.12065 0.2794)
			(stroke
				(width 0.1)
				(type default)
			)
			(layer "B.Fab")
		)
		(fp_line
			(start 0.67945 0.3048)
			(end 0.67945 -0.305054)
			(stroke
				(width 0.1)
				(type default)
			)
			(layer "B.Fab")
		)
		(fp_line
			(start 0.12065 0.3048)
			(end 0.67945 0.3048)
			(stroke
				(width 0.1)
				(type default)
			)
			(layer "B.Fab")
		)
		(fp_line
			(start -0.120396 0.3048)
			(end -0.120396 0.2794)
			(stroke
				(width 0.1)
				(type default)
			)
			(layer "B.Fab")
		)
		(fp_line
			(start -0.67945 0.3048)
			(end -0.120396 0.3048)
			(stroke
				(width 0.1)
				(type default)
			)
			(layer "B.Fab")
		)
		(pad "1" smd circle
			(at 0.40005 0 270)
			(size 0 0)
			(layers "B.Cu" "B.Mask" "B.Paste")
			(net "GND")
		)
		(pad "2" smd circle
			(at -0.40005 0 270)
			(size 0 0)
			(layers "B.Cu" "B.Mask" "B.Paste")
			(net "FAN_3_IMON")
		)
	)
	(footprint ""
		(layer "B.Cu")
		(at 44.621958 -239.1664 180)
		(property "Reference" "PC24"
			(at 0 0 0)
			(layer "B.SilkS")
			(hide yes)
			(effects
				(font
					(size 1.27 1.27)
				)
				(justify mirror)
			)
		)
		(property "Value" ""
			(at 0 0 0)
			(layer "B.Fab")
			(effects
				(font
					(size 1.27 1.27)
				)
				(justify mirror)
			)
		)
		(duplicate_pad_numbers_are_jumpers no)
		(fp_line
			(start 1.524 0.762)
			(end 1.524 -0.762)
			(stroke
				(width 0.1524)
				(type default)
			)
			(layer "B.SilkS")
		)
		(fp_line
			(start 1.524 -0.762)
			(end -1.524 -0.762)
			(stroke
				(width 0.1524)
				(type default)
			)
			(layer "B.SilkS")
		)
		(fp_line
			(start -1.524 0.762)
			(end 1.524 0.762)
			(stroke
				(width 0.1524)
				(type default)
			)
			(layer "B.SilkS")
		)
		(fp_line
			(start -1.524 -0.762)
			(end -1.524 0.762)
			(stroke
				(width 0.1524)
				(type default)
			)
			(layer "B.SilkS")
		)
		(fp_line
			(start 1.1049 0.724916)
			(end -1.1049 0.724916)
			(stroke
				(width 0.1)
				(type default)
			)
			(layer "B.Fab")
		)
		(fp_line
			(start 1.1049 -0.724916)
			(end 1.1049 0.724916)
			(stroke
				(width 0.1)
				(type default)
			)
			(layer "B.Fab")
		)
		(fp_line
			(start -1.1049 0.724916)
			(end -1.1049 -0.724916)
			(stroke
				(width 0.1)
				(type default)
			)
			(layer "B.Fab")
		)
		(fp_line
			(start -1.1049 -0.724916)
			(end 1.1049 -0.724916)
			(stroke
				(width 0.1)
				(type default)
			)
			(layer "B.Fab")
		)
		(pad "1" smd rect
			(at 0.889 0 180)
			(size 1.016 1.27)
			(layers "B.Cu" "B.Mask" "B.Paste")
			(net "P52V_FAN_1")
		)
		(pad "2" smd rect
			(at -0.889 0 180)
			(size 1.016 1.27)
			(layers "B.Cu" "B.Mask" "B.Paste")
			(net "GND")
		)
	)
	(footprint ""
		(layer "B.Cu")
		(at 34.666428 -67.621912 90)
		(property "Reference" "U391"
			(at -1.327912 -1.900428 270)
			(unlocked yes)
			(layer "B.SilkS")
			(effects
				(font
					(size 0.7874 0.5842)
					(thickness 0.1524)
				)
				(justify left mirror)
			)
		)
		(property "Value" ""
			(at 0 0 90)
			(layer "B.Fab")
			(effects
				(font
					(size 1.27 1.27)
				)
				(justify mirror)
			)
		)
		(duplicate_pad_numbers_are_jumpers no)
		(fp_line
			(start 1.3462 -1.1938)
			(end 1.3462 1.1684)
			(stroke
				(width 0.1524)
				(type default)
			)
			(layer "B.SilkS")
		)
		(fp_line
			(start -1.3462 -1.1938)
			(end 1.3462 -1.1938)
			(stroke
				(width 0.1524)
				(type default)
			)
			(layer "B.SilkS")
		)
		(fp_line
			(start 1.3462 1.1938)
			(end -1.3462 1.1938)
			(stroke
				(width 0.1524)
				(type default)
			)
			(layer "B.SilkS")
		)
		(fp_line
			(start -1.3462 1.1938)
			(end -1.3462 -1.1938)
			(stroke
				(width 0.1524)
				(type default)
			)
			(layer "B.SilkS")
		)
		(fp_poly
			(pts
				(xy 1.447038 -0.760476) (xy 2.052066 -0.457962) (xy 2.052066 -1.06299)
			)
			(stroke
				(width 0)
				(type default)
			)
			(fill yes)
			(layer "B.SilkS")
		)
		(fp_line
			(start 0.674878 -1.124966)
			(end 0.674878 1.124966)
			(stroke
				(width 0.1)
				(type default)
			)
			(layer "B.Fab")
		)
		(fp_line
			(start -0.674878 -1.124966)
			(end 0.674878 -1.124966)
			(stroke
				(width 0.1)
				(type default)
			)
			(layer "B.Fab")
		)
		(fp_line
			(start 0.674878 1.124966)
			(end -0.674878 1.124966)
			(stroke
				(width 0.1)
				(type default)
			)
			(layer "B.Fab")
		)
		(fp_line
			(start -0.674878 1.124966)
			(end -0.674878 -1.124966)
			(stroke
				(width 0.1)
				(type default)
			)
			(layer "B.Fab")
		)
		(fp_poly
			(pts
				(xy 1.447038 -0.760476) (xy 2.052066 -0.457962) (xy 2.052066 -1.06299)
			)
			(stroke
				(width 0)
				(type default)
			)
			(fill yes)
			(layer "B.Fab")
		)
		(pad "1" smd rect
			(at 0.899922 -0.750062 270)
			(size 0.6096 0.6096)
			(layers "B.Cu" "B.Mask" "B.Paste")
			(net "NC_U391_P1")
		)
		(pad "2" smd rect
			(at 0.899922 0 180)
			(size 0.4064 0.6096)
			(layers "B.Cu" "B.Mask" "B.Paste")
			(net "FAN_3_PRSNT_BUF_N")
		)
		(pad "3" smd rect
			(at 0.899922 0.750062 270)
			(size 0.6096 0.6096)
			(layers "B.Cu" "B.Mask" "B.Paste")
			(net "GND")
		)
		(pad "4" smd rect
			(at -0.899922 0.750062 270)
			(size 0.6096 0.6096)
			(layers "B.Cu" "B.Mask" "B.Paste")
			(net "FAN_3_PRESENT")
		)
		(pad "5" smd rect
			(at -0.899922 -0.750062 270)
			(size 0.6096 0.6096)
			(layers "B.Cu" "B.Mask" "B.Paste")
			(net "P3V3_AUX")
		)
	)
	(footprint ""
		(layer "B.Cu")
		(at 45.085 -258.572 90)
		(property "Reference" "PC5"
			(at 0 0 90)
			(layer "B.SilkS")
			(hide yes)
			(effects
				(font
					(size 1.27 1.27)
				)
				(justify mirror)
			)
		)
		(property "Value" ""
			(at 0 0 90)
			(layer "B.Fab")
			(effects
				(font
					(size 1.27 1.27)
				)
				(justify mirror)
			)
		)
		(duplicate_pad_numbers_are_jumpers no)
		(fp_line
			(start 0.7874 -0.4064)
			(end -0.7874 -0.4064)
			(stroke
				(width 0.1524)
				(type default)
			)
			(layer "B.SilkS")
		)
		(fp_line
			(start -0.7874 -0.4064)
			(end -0.7874 0.4064)
			(stroke
				(width 0.1524)
				(type default)
			)
			(layer "B.SilkS")
		)
		(fp_line
			(start 0.7874 0.4064)
			(end 0.7874 -0.4064)
			(stroke
				(width 0.1524)
				(type default)
			)
			(layer "B.SilkS")
		)
		(fp_line
			(start -0.7874 0.4064)
			(end 0.7874 0.4064)
			(stroke
				(width 0.1524)
				(type default)
			)
			(layer "B.SilkS")
		)
		(fp_line
			(start 0.67945 -0.305054)
			(end 0.12065 -0.305054)
			(stroke
				(width 0.1)
				(type default)
			)
			(layer "B.Fab")
		)
		(fp_line
			(start 0.12065 -0.305054)
			(end 0.12065 -0.2794)
			(stroke
				(width 0.1)
				(type default)
			)
			(layer "B.Fab")
		)
		(fp_line
			(start -0.12065 -0.3048)
			(end -0.67945 -0.3048)
			(stroke
				(width 0.1)
				(type default)
			)
			(layer "B.Fab")
		)
		(fp_line
			(start -0.67945 -0.3048)
			(end -0.67945 0.3048)
			(stroke
				(width 0.1)
				(type default)
			)
			(layer "B.Fab")
		)
		(fp_line
			(start 0.12065 -0.2794)
			(end -0.12065 -0.2794)
			(stroke
				(width 0.1)
				(type default)
			)
			(layer "B.Fab")
		)
		(fp_line
			(start -0.12065 -0.2794)
			(end -0.12065 -0.3048)
			(stroke
				(width 0.1)
				(type default)
			)
			(layer "B.Fab")
		)
		(fp_line
			(start 0.12065 0.2794)
			(end 0.12065 0.3048)
			(stroke
				(width 0.1)
				(type default)
			)
			(layer "B.Fab")
		)
		(fp_line
			(start -0.120396 0.2794)
			(end 0.12065 0.2794)
			(stroke
				(width 0.1)
				(type default)
			)
			(layer "B.Fab")
		)
		(fp_line
			(start 0.67945 0.3048)
			(end 0.67945 -0.305054)
			(stroke
				(width 0.1)
				(type default)
			)
			(layer "B.Fab")
		)
		(fp_line
			(start 0.12065 0.3048)
			(end 0.67945 0.3048)
			(stroke
				(width 0.1)
				(type default)
			)
			(layer "B.Fab")
		)
		(fp_line
			(start -0.120396 0.3048)
			(end -0.120396 0.2794)
			(stroke
				(width 0.1)
				(type default)
			)
			(layer "B.Fab")
		)
		(fp_line
			(start -0.67945 0.3048)
			(end -0.120396 0.3048)
			(stroke
				(width 0.1)
				(type default)
			)
			(layer "B.Fab")
		)
		(pad "1" smd circle
			(at 0.40005 0 270)
			(size 0 0)
			(layers "B.Cu" "B.Mask" "B.Paste")
			(net "FAN_0_SS")
		)
		(pad "2" smd circle
			(at -0.40005 0 270)
			(size 0 0)
			(layers "B.Cu" "B.Mask" "B.Paste")
			(net "GND")
		)
	)
	(footprint ""
		(layer "B.Cu")
		(at 47.117 -258.572 90)
		(property "Reference" "PR6"
			(at 0 0 90)
			(layer "B.SilkS")
			(hide yes)
			(effects
				(font
					(size 1.27 1.27)
				)
				(justify mirror)
			)
		)
		(property "Value" ""
			(at 0 0 90)
			(layer "B.Fab")
			(effects
				(font
					(size 1.27 1.27)
				)
				(justify mirror)
			)
		)
		(duplicate_pad_numbers_are_jumpers no)
		(fp_line
			(start 0.7874 -0.4064)
			(end -0.7874 -0.4064)
			(stroke
				(width 0.1524)
				(type default)
			)
			(layer "B.SilkS")
		)
		(fp_line
			(start -0.7874 -0.4064)
			(end -0.7874 0.4064)
			(stroke
				(width 0.1524)
				(type default)
			)
			(layer "B.SilkS")
		)
		(fp_line
			(start 0.7874 0.4064)
			(end 0.7874 -0.4064)
			(stroke
				(width 0.1524)
				(type default)
			)
			(layer "B.SilkS")
		)
		(fp_line
			(start -0.7874 0.4064)
			(end 0.7874 0.4064)
			(stroke
				(width 0.1524)
				(type default)
			)
			(layer "B.SilkS")
		)
		(fp_line
			(start 0.67945 -0.305054)
			(end 0.12065 -0.305054)
			(stroke
				(width 0.1)
				(type default)
			)
			(layer "B.Fab")
		)
		(fp_line
			(start 0.12065 -0.305054)
			(end 0.12065 -0.2794)
			(stroke
				(width 0.1)
				(type default)
			)
			(layer "B.Fab")
		)
		(fp_line
			(start -0.12065 -0.3048)
			(end -0.67945 -0.3048)
			(stroke
				(width 0.1)
				(type default)
			)
			(layer "B.Fab")
		)
		(fp_line
			(start -0.67945 -0.3048)
			(end -0.67945 0.3048)
			(stroke
				(width 0.1)
				(type default)
			)
			(layer "B.Fab")
		)
		(fp_line
			(start 0.12065 -0.2794)
			(end -0.12065 -0.2794)
			(stroke
				(width 0.1)
				(type default)
			)
			(layer "B.Fab")
		)
		(fp_line
			(start -0.12065 -0.2794)
			(end -0.12065 -0.3048)
			(stroke
				(width 0.1)
				(type default)
			)
			(layer "B.Fab")
		)
		(fp_line
			(start 0.12065 0.2794)
			(end 0.12065 0.3048)
			(stroke
				(width 0.1)
				(type default)
			)
			(layer "B.Fab")
		)
		(fp_line
			(start -0.120396 0.2794)
			(end 0.12065 0.2794)
			(stroke
				(width 0.1)
				(type default)
			)
			(layer "B.Fab")
		)
		(fp_line
			(start 0.67945 0.3048)
			(end 0.67945 -0.305054)
			(stroke
				(width 0.1)
				(type default)
			)
			(layer "B.Fab")
		)
		(fp_line
			(start 0.12065 0.3048)
			(end 0.67945 0.3048)
			(stroke
				(width 0.1)
				(type default)
			)
			(layer "B.Fab")
		)
		(fp_line
			(start -0.120396 0.3048)
			(end -0.120396 0.2794)
			(stroke
				(width 0.1)
				(type default)
			)
			(layer "B.Fab")
		)
		(fp_line
			(start -0.67945 0.3048)
			(end -0.120396 0.3048)
			(stroke
				(width 0.1)
				(type default)
			)
			(layer "B.Fab")
		)
		(pad "1" smd circle
			(at 0.40005 0 270)
			(size 0 0)
			(layers "B.Cu" "B.Mask" "B.Paste")
			(net "FAN_0_CS")
		)
		(pad "2" smd circle
			(at -0.40005 0 270)
			(size 0 0)
			(layers "B.Cu" "B.Mask" "B.Paste")
			(net "GND")
		)
	)
	(footprint ""
		(layer "B.Cu")
		(at 9.667494 -258.562856 90)
		(property "Reference" "PC2125"
			(at 0 0 90)
			(layer "B.SilkS")
			(hide yes)
			(effects
				(font
					(size 1.27 1.27)
				)
				(justify mirror)
			)
		)
		(property "Value" ""
			(at 0 0 90)
			(layer "B.Fab")
			(effects
				(font
					(size 1.27 1.27)
				)
				(justify mirror)
			)
		)
		(duplicate_pad_numbers_are_jumpers no)
		(fp_line
			(start 0.7874 -0.4064)
			(end -0.7874 -0.4064)
			(stroke
				(width 0.1524)
				(type default)
			)
			(layer "B.SilkS")
		)
		(fp_line
			(start -0.7874 -0.4064)
			(end -0.7874 0.4064)
			(stroke
				(width 0.1524)
				(type default)
			)
			(layer "B.SilkS")
		)
		(fp_line
			(start 0.7874 0.4064)
			(end 0.7874 -0.4064)
			(stroke
				(width 0.1524)
				(type default)
			)
			(layer "B.SilkS")
		)
		(fp_line
			(start -0.7874 0.4064)
			(end 0.7874 0.4064)
			(stroke
				(width 0.1524)
				(type default)
			)
			(layer "B.SilkS")
		)
		(fp_line
			(start 0.67945 -0.305054)
			(end 0.12065 -0.305054)
			(stroke
				(width 0.1)
				(type default)
			)
			(layer "B.Fab")
		)
		(fp_line
			(start 0.12065 -0.305054)
			(end 0.12065 -0.2794)
			(stroke
				(width 0.1)
				(type default)
			)
			(layer "B.Fab")
		)
		(fp_line
			(start -0.12065 -0.3048)
			(end -0.67945 -0.3048)
			(stroke
				(width 0.1)
				(type default)
			)
			(layer "B.Fab")
		)
		(fp_line
			(start -0.67945 -0.3048)
			(end -0.67945 0.3048)
			(stroke
				(width 0.1)
				(type default)
			)
			(layer "B.Fab")
		)
		(fp_line
			(start 0.12065 -0.2794)
			(end -0.12065 -0.2794)
			(stroke
				(width 0.1)
				(type default)
			)
			(layer "B.Fab")
		)
		(fp_line
			(start -0.12065 -0.2794)
			(end -0.12065 -0.3048)
			(stroke
				(width 0.1)
				(type default)
			)
			(layer "B.Fab")
		)
		(fp_line
			(start 0.12065 0.2794)
			(end 0.12065 0.3048)
			(stroke
				(width 0.1)
				(type default)
			)
			(layer "B.Fab")
		)
		(fp_line
			(start -0.120396 0.2794)
			(end 0.12065 0.2794)
			(stroke
				(width 0.1)
				(type default)
			)
			(layer "B.Fab")
		)
		(fp_line
			(start 0.67945 0.3048)
			(end 0.67945 -0.305054)
			(stroke
				(width 0.1)
				(type default)
			)
			(layer "B.Fab")
		)
		(fp_line
			(start 0.12065 0.3048)
			(end 0.67945 0.3048)
			(stroke
				(width 0.1)
				(type default)
			)
			(layer "B.Fab")
		)
		(fp_line
			(start -0.120396 0.3048)
			(end -0.120396 0.2794)
			(stroke
				(width 0.1)
				(type default)
			)
			(layer "B.Fab")
		)
		(fp_line
			(start -0.67945 0.3048)
			(end -0.120396 0.3048)
			(stroke
				(width 0.1)
				(type default)
			)
			(layer "B.Fab")
		)
		(pad "1" smd circle
			(at 0.40005 0 270)
			(size 0 0)
			(layers "B.Cu" "B.Mask" "B.Paste")
			(net "FAN_7_TEMP")
		)
		(pad "2" smd circle
			(at -0.40005 0 270)
			(size 0 0)
			(layers "B.Cu" "B.Mask" "B.Paste")
			(net "GND")
		)
	)
	(footprint ""
		(layer "B.Cu")
		(at 3.81 -67.945 90)
		(property "Reference" "U392"
			(at -0.889 1.75133 270)
			(unlocked yes)
			(layer "B.SilkS")
			(effects
				(font
					(size 0.7874 0.5842)
					(thickness 0.1524)
				)
				(justify left mirror)
			)
		)
		(property "Value" ""
			(at 0 0 90)
			(layer "B.Fab")
			(effects
				(font
					(size 1.27 1.27)
				)
				(justify mirror)
			)
		)
		(duplicate_pad_numbers_are_jumpers no)
		(fp_line
			(start 1.3462 -1.1938)
			(end 1.3462 1.1684)
			(stroke
				(width 0.1524)
				(type default)
			)
			(layer "B.SilkS")
		)
		(fp_line
			(start -1.3462 -1.1938)
			(end 1.3462 -1.1938)
			(stroke
				(width 0.1524)
				(type default)
			)
			(layer "B.SilkS")
		)
		(fp_line
			(start 1.3462 1.1938)
			(end -1.3462 1.1938)
			(stroke
				(width 0.1524)
				(type default)
			)
			(layer "B.SilkS")
		)
		(fp_line
			(start -1.3462 1.1938)
			(end -1.3462 -1.1938)
			(stroke
				(width 0.1524)
				(type default)
			)
			(layer "B.SilkS")
		)
		(fp_poly
			(pts
				(xy 1.305306 -1.378712) (xy 1.947164 -1.59258) (xy 1.519174 -2.020316)
			)
			(stroke
				(width 0)
				(type default)
			)
			(fill yes)
			(layer "B.SilkS")
		)
		(fp_line
			(start 0.674878 -1.124966)
			(end 0.674878 1.124966)
			(stroke
				(width 0.1)
				(type default)
			)
			(layer "B.Fab")
		)
		(fp_line
			(start -0.674878 -1.124966)
			(end 0.674878 -1.124966)
			(stroke
				(width 0.1)
				(type default)
			)
			(layer "B.Fab")
		)
		(fp_line
			(start 0.674878 1.124966)
			(end -0.674878 1.124966)
			(stroke
				(width 0.1)
				(type default)
			)
			(layer "B.Fab")
		)
		(fp_line
			(start -0.674878 1.124966)
			(end -0.674878 -1.124966)
			(stroke
				(width 0.1)
				(type default)
			)
			(layer "B.Fab")
		)
		(fp_poly
			(pts
				(xy 1.447038 -0.760476) (xy 2.052066 -0.457962) (xy 2.052066 -1.06299)
			)
			(stroke
				(width 0)
				(type default)
			)
			(fill yes)
			(layer "B.Fab")
		)
		(pad "1" smd rect
			(at 0.899922 -0.750062 270)
			(size 0.6096 0.6096)
			(layers "B.Cu" "B.Mask" "B.Paste")
			(net "NC_U392_P1")
		)
		(pad "2" smd rect
			(at 0.899922 0 180)
			(size 0.4064 0.6096)
			(layers "B.Cu" "B.Mask" "B.Paste")
			(net "FAN_4_PRSNT_BUF_N")
		)
		(pad "3" smd rect
			(at 0.899922 0.750062 270)
			(size 0.6096 0.6096)
			(layers "B.Cu" "B.Mask" "B.Paste")
			(net "GND")
		)
		(pad "4" smd rect
			(at -0.899922 0.750062 270)
			(size 0.6096 0.6096)
			(layers "B.Cu" "B.Mask" "B.Paste")
			(net "FAN_4_PRESENT")
		)
		(pad "5" smd rect
			(at -0.899922 -0.750062 270)
			(size 0.6096 0.6096)
			(layers "B.Cu" "B.Mask" "B.Paste")
			(net "P3V3_AUX")
		)
	)
	(footprint ""
		(layer "B.Cu")
		(at 4.699 -249.428 -90)
		(property "Reference" "PC53"
			(at 0 0 90)
			(layer "B.SilkS")
			(hide yes)
			(effects
				(font
					(size 1.27 1.27)
				)
				(justify mirror)
			)
		)
		(property "Value" ""
			(at 0 0 90)
			(layer "B.Fab")
			(effects
				(font
					(size 1.27 1.27)
				)
				(justify mirror)
			)
		)
		(duplicate_pad_numbers_are_jumpers no)
		(fp_line
			(start -0.7874 0.4064)
			(end 0.7874 0.4064)
			(stroke
				(width 0.1524)
				(type default)
			)
			(layer "B.SilkS")
		)
		(fp_line
			(start 0.7874 0.4064)
			(end 0.7874 -0.4064)
			(stroke
				(width 0.1524)
				(type default)
			)
			(layer "B.SilkS")
		)
		(fp_line
			(start -0.7874 -0.4064)
			(end -0.7874 0.4064)
			(stroke
				(width 0.1524)
				(type default)
			)
			(layer "B.SilkS")
		)
		(fp_line
			(start 0.7874 -0.4064)
			(end -0.7874 -0.4064)
			(stroke
				(width 0.1524)
				(type default)
			)
			(layer "B.SilkS")
		)
		(fp_line
			(start -0.67945 0.3048)
			(end -0.120396 0.3048)
			(stroke
				(width 0.1)
				(type default)
			)
			(layer "B.Fab")
		)
		(fp_line
			(start -0.120396 0.3048)
			(end -0.120396 0.2794)
			(stroke
				(width 0.1)
				(type default)
			)
			(layer "B.Fab")
		)
		(fp_line
			(start 0.12065 0.3048)
			(end 0.67945 0.3048)
			(stroke
				(width 0.1)
				(type default)
			)
			(layer "B.Fab")
		)
		(fp_line
			(start 0.67945 0.3048)
			(end 0.67945 -0.305054)
			(stroke
				(width 0.1)
				(type default)
			)
			(layer "B.Fab")
		)
		(fp_line
			(start -0.120396 0.2794)
			(end 0.12065 0.2794)
			(stroke
				(width 0.1)
				(type default)
			)
			(layer "B.Fab")
		)
		(fp_line
			(start 0.12065 0.2794)
			(end 0.12065 0.3048)
			(stroke
				(width 0.1)
				(type default)
			)
			(layer "B.Fab")
		)
		(fp_line
			(start -0.12065 -0.2794)
			(end -0.12065 -0.3048)
			(stroke
				(width 0.1)
				(type default)
			)
			(layer "B.Fab")
		)
		(fp_line
			(start 0.12065 -0.2794)
			(end -0.12065 -0.2794)
			(stroke
				(width 0.1)
				(type default)
			)
			(layer "B.Fab")
		)
		(fp_line
			(start -0.67945 -0.3048)
			(end -0.67945 0.3048)
			(stroke
				(width 0.1)
				(type default)
			)
			(layer "B.Fab")
		)
		(fp_line
			(start -0.12065 -0.3048)
			(end -0.67945 -0.3048)
			(stroke
				(width 0.1)
				(type default)
			)
			(layer "B.Fab")
		)
		(fp_line
			(start 0.12065 -0.305054)
			(end 0.12065 -0.2794)
			(stroke
				(width 0.1)
				(type default)
			)
			(layer "B.Fab")
		)
		(fp_line
			(start 0.67945 -0.305054)
			(end 0.12065 -0.305054)
			(stroke
				(width 0.1)
				(type default)
			)
			(layer "B.Fab")
		)
		(pad "1" smd circle
			(at 0.40005 0 90)
			(size 0 0)
			(layers "B.Cu" "B.Mask" "B.Paste")
			(net "FAN_6_TIMER")
		)
		(pad "2" smd circle
			(at -0.40005 0 90)
			(size 0 0)
			(layers "B.Cu" "B.Mask" "B.Paste")
			(net "GND")
		)
	)
	(footprint ""
		(layer "B.Cu")
		(at 36.195 -250.23699 -90)
		(property "Reference" "PR33"
			(at 0 0 90)
			(layer "B.SilkS")
			(hide yes)
			(effects
				(font
					(size 1.27 1.27)
				)
				(justify mirror)
			)
		)
		(property "Value" ""
			(at 0 0 90)
			(layer "B.Fab")
			(effects
				(font
					(size 1.27 1.27)
				)
				(justify mirror)
			)
		)
		(duplicate_pad_numbers_are_jumpers no)
		(fp_line
			(start -0.7874 0.4064)
			(end 0.7874 0.4064)
			(stroke
				(width 0.1524)
				(type default)
			)
			(layer "B.SilkS")
		)
		(fp_line
			(start 0.7874 0.4064)
			(end 0.7874 -0.4064)
			(stroke
				(width 0.1524)
				(type default)
			)
			(layer "B.SilkS")
		)
		(fp_line
			(start -0.7874 -0.4064)
			(end -0.7874 0.4064)
			(stroke
				(width 0.1524)
				(type default)
			)
			(layer "B.SilkS")
		)
		(fp_line
			(start 0.7874 -0.4064)
			(end -0.7874 -0.4064)
			(stroke
				(width 0.1524)
				(type default)
			)
			(layer "B.SilkS")
		)
		(fp_line
			(start -0.67945 0.3048)
			(end -0.120396 0.3048)
			(stroke
				(width 0.1)
				(type default)
			)
			(layer "B.Fab")
		)
		(fp_line
			(start -0.120396 0.3048)
			(end -0.120396 0.2794)
			(stroke
				(width 0.1)
				(type default)
			)
			(layer "B.Fab")
		)
		(fp_line
			(start 0.12065 0.3048)
			(end 0.67945 0.3048)
			(stroke
				(width 0.1)
				(type default)
			)
			(layer "B.Fab")
		)
		(fp_line
			(start 0.67945 0.3048)
			(end 0.67945 -0.305054)
			(stroke
				(width 0.1)
				(type default)
			)
			(layer "B.Fab")
		)
		(fp_line
			(start -0.120396 0.2794)
			(end 0.12065 0.2794)
			(stroke
				(width 0.1)
				(type default)
			)
			(layer "B.Fab")
		)
		(fp_line
			(start 0.12065 0.2794)
			(end 0.12065 0.3048)
			(stroke
				(width 0.1)
				(type default)
			)
			(layer "B.Fab")
		)
		(fp_line
			(start -0.12065 -0.2794)
			(end -0.12065 -0.3048)
			(stroke
				(width 0.1)
				(type default)
			)
			(layer "B.Fab")
		)
		(fp_line
			(start 0.12065 -0.2794)
			(end -0.12065 -0.2794)
			(stroke
				(width 0.1)
				(type default)
			)
			(layer "B.Fab")
		)
		(fp_line
			(start -0.67945 -0.3048)
			(end -0.67945 0.3048)
			(stroke
				(width 0.1)
				(type default)
			)
			(layer "B.Fab")
		)
		(fp_line
			(start -0.12065 -0.3048)
			(end -0.67945 -0.3048)
			(stroke
				(width 0.1)
				(type default)
			)
			(layer "B.Fab")
		)
		(fp_line
			(start 0.12065 -0.305054)
			(end 0.12065 -0.2794)
			(stroke
				(width 0.1)
				(type default)
			)
			(layer "B.Fab")
		)
		(fp_line
			(start 0.67945 -0.305054)
			(end 0.12065 -0.305054)
			(stroke
				(width 0.1)
				(type default)
			)
			(layer "B.Fab")
		)
		(pad "1" smd circle
			(at 0.40005 0 90)
			(size 0 0)
			(layers "B.Cu" "B.Mask" "B.Paste")
			(net "FAN_1_CLREF")
		)
		(pad "2" smd circle
			(at -0.40005 0 90)
			(size 0 0)
			(layers "B.Cu" "B.Mask" "B.Paste")
			(net "GND")
		)
	)
	(footprint ""
		(layer "B.Cu")
		(at 17.653 -128.524 180)
		(property "Reference" "R5435"
			(at 0 0 0)
			(layer "B.SilkS")
			(hide yes)
			(effects
				(font
					(size 1.27 1.27)
				)
				(justify mirror)
			)
		)
		(property "Value" ""
			(at 0 0 0)
			(layer "B.Fab")
			(effects
				(font
					(size 1.27 1.27)
				)
				(justify mirror)
			)
		)
		(duplicate_pad_numbers_are_jumpers no)
		(fp_line
			(start 0.7874 0.4064)
			(end 0.7874 -0.4064)
			(stroke
				(width 0.1524)
				(type default)
			)
			(layer "B.SilkS")
		)
		(fp_line
			(start 0.7874 -0.4064)
			(end -0.7874 -0.4064)
			(stroke
				(width 0.1524)
				(type default)
			)
			(layer "B.SilkS")
		)
		(fp_line
			(start -0.7874 0.4064)
			(end 0.7874 0.4064)
			(stroke
				(width 0.1524)
				(type default)
			)
			(layer "B.SilkS")
		)
		(fp_line
			(start -0.7874 -0.4064)
			(end -0.7874 0.4064)
			(stroke
				(width 0.1524)
				(type default)
			)
			(layer "B.SilkS")
		)
		(fp_line
			(start 0.67945 0.3048)
			(end 0.67945 -0.305054)
			(stroke
				(width 0.1)
				(type default)
			)
			(layer "B.Fab")
		)
		(fp_line
			(start 0.67945 -0.305054)
			(end 0.12065 -0.305054)
			(stroke
				(width 0.1)
				(type default)
			)
			(layer "B.Fab")
		)
		(fp_line
			(start 0.12065 0.3048)
			(end 0.67945 0.3048)
			(stroke
				(width 0.1)
				(type default)
			)
			(layer "B.Fab")
		)
		(fp_line
			(start 0.12065 0.2794)
			(end 0.12065 0.3048)
			(stroke
				(width 0.1)
				(type default)
			)
			(layer "B.Fab")
		)
		(fp_line
			(start 0.12065 -0.2794)
			(end -0.12065 -0.2794)
			(stroke
				(width 0.1)
				(type default)
			)
			(layer "B.Fab")
		)
		(fp_line
			(start 0.12065 -0.305054)
			(end 0.12065 -0.2794)
			(stroke
				(width 0.1)
				(type default)
			)
			(layer "B.Fab")
		)
		(fp_line
			(start -0.120396 0.3048)
			(end -0.120396 0.2794)
			(stroke
				(width 0.1)
				(type default)
			)
			(layer "B.Fab")
		)
		(fp_line
			(start -0.120396 0.2794)
			(end 0.12065 0.2794)
			(stroke
				(width 0.1)
				(type default)
			)
			(layer "B.Fab")
		)
		(fp_line
			(start -0.12065 -0.2794)
			(end -0.12065 -0.3048)
			(stroke
				(width 0.1)
				(type default)
			)
			(layer "B.Fab")
		)
		(fp_line
			(start -0.12065 -0.3048)
			(end -0.67945 -0.3048)
			(stroke
				(width 0.1)
				(type default)
			)
			(layer "B.Fab")
		)
		(fp_line
			(start -0.67945 0.3048)
			(end -0.120396 0.3048)
			(stroke
				(width 0.1)
				(type default)
			)
			(layer "B.Fab")
		)
		(fp_line
			(start -0.67945 -0.3048)
			(end -0.67945 0.3048)
			(stroke
				(width 0.1)
				(type default)
			)
			(layer "B.Fab")
		)
		(pad "1" smd rect
			(at 0.40005 0 180)
			(size 0.4572 0.508)
			(layers "B.Cu" "B.Mask" "B.Paste")
			(net "FAN_4_TACH_OL")
		)
		(pad "2" smd rect
			(at -0.40005 0 180)
			(size 0.4572 0.508)
			(layers "B.Cu" "B.Mask" "B.Paste")
			(net "GND")
		)
	)
	(footprint ""
		(layer "B.Cu")
		(at 44.069 -236.924088 180)
		(property "Reference" "C2101"
			(at 0 0 0)
			(layer "B.SilkS")
			(hide yes)
			(effects
				(font
					(size 1.27 1.27)
				)
				(justify mirror)
			)
		)
		(property "Value" ""
			(at 0 0 0)
			(layer "B.Fab")
			(effects
				(font
					(size 1.27 1.27)
				)
				(justify mirror)
			)
		)
		(duplicate_pad_numbers_are_jumpers no)
		(fp_line
			(start 2.2098 0.9398)
			(end 2.2098 -0.9398)
			(stroke
				(width 0.1524)
				(type default)
			)
			(layer "B.SilkS")
		)
		(fp_line
			(start 2.2098 -0.9398)
			(end -2.2098 -0.9398)
			(stroke
				(width 0.1524)
				(type default)
			)
			(layer "B.SilkS")
		)
		(fp_line
			(start -2.2098 0.9398)
			(end 2.2098 0.9398)
			(stroke
				(width 0.1524)
				(type default)
			)
			(layer "B.SilkS")
		)
		(fp_line
			(start -2.2098 -0.9398)
			(end -2.2098 0.9398)
			(stroke
				(width 0.1524)
				(type default)
			)
			(layer "B.SilkS")
		)
		(fp_line
			(start 1.700022 0.899922)
			(end 1.700022 -0.899922)
			(stroke
				(width 0.1)
				(type default)
			)
			(layer "B.Fab")
		)
		(fp_line
			(start 1.700022 -0.899922)
			(end -1.700022 -0.899922)
			(stroke
				(width 0.1)
				(type default)
			)
			(layer "B.Fab")
		)
		(fp_line
			(start -1.700022 0.899922)
			(end 1.700022 0.899922)
			(stroke
				(width 0.1)
				(type default)
			)
			(layer "B.Fab")
		)
		(fp_line
			(start -1.700022 -0.899922)
			(end -1.700022 0.899922)
			(stroke
				(width 0.1)
				(type default)
			)
			(layer "B.Fab")
		)
		(pad "1" smd rect
			(at 1.4732 0 180)
			(size 1.1684 1.5748)
			(layers "B.Cu" "B.Mask" "B.Paste")
			(net "P52V_FAN_1")
		)
		(pad "2" smd rect
			(at -1.4732 0 180)
			(size 1.1684 1.5748)
			(layers "B.Cu" "B.Mask" "B.Paste")
			(net "GND")
		)
	)
	(footprint ""
		(layer "B.Cu")
		(at 17.287494 -73.971912 90)
		(property "Reference" "PC46"
			(at 0 0 90)
			(layer "B.SilkS")
			(hide yes)
			(effects
				(font
					(size 1.27 1.27)
				)
				(justify mirror)
			)
		)
		(property "Value" ""
			(at 0 0 90)
			(layer "B.Fab")
			(effects
				(font
					(size 1.27 1.27)
				)
				(justify mirror)
			)
		)
		(duplicate_pad_numbers_are_jumpers no)
		(fp_line
			(start 0.7874 -0.4064)
			(end -0.7874 -0.4064)
			(stroke
				(width 0.1524)
				(type default)
			)
			(layer "B.SilkS")
		)
		(fp_line
			(start -0.7874 -0.4064)
			(end -0.7874 0.4064)
			(stroke
				(width 0.1524)
				(type default)
			)
			(layer "B.SilkS")
		)
		(fp_line
			(start 0.7874 0.4064)
			(end 0.7874 -0.4064)
			(stroke
				(width 0.1524)
				(type default)
			)
			(layer "B.SilkS")
		)
		(fp_line
			(start -0.7874 0.4064)
			(end 0.7874 0.4064)
			(stroke
				(width 0.1524)
				(type default)
			)
			(layer "B.SilkS")
		)
		(fp_line
			(start 0.67945 -0.305054)
			(end 0.12065 -0.305054)
			(stroke
				(width 0.1)
				(type default)
			)
			(layer "B.Fab")
		)
		(fp_line
			(start 0.12065 -0.305054)
			(end 0.12065 -0.2794)
			(stroke
				(width 0.1)
				(type default)
			)
			(layer "B.Fab")
		)
		(fp_line
			(start -0.12065 -0.3048)
			(end -0.67945 -0.3048)
			(stroke
				(width 0.1)
				(type default)
			)
			(layer "B.Fab")
		)
		(fp_line
			(start -0.67945 -0.3048)
			(end -0.67945 0.3048)
			(stroke
				(width 0.1)
				(type default)
			)
			(layer "B.Fab")
		)
		(fp_line
			(start 0.12065 -0.2794)
			(end -0.12065 -0.2794)
			(stroke
				(width 0.1)
				(type default)
			)
			(layer "B.Fab")
		)
		(fp_line
			(start -0.12065 -0.2794)
			(end -0.12065 -0.3048)
			(stroke
				(width 0.1)
				(type default)
			)
			(layer "B.Fab")
		)
		(fp_line
			(start 0.12065 0.2794)
			(end 0.12065 0.3048)
			(stroke
				(width 0.1)
				(type default)
			)
			(layer "B.Fab")
		)
		(fp_line
			(start -0.120396 0.2794)
			(end 0.12065 0.2794)
			(stroke
				(width 0.1)
				(type default)
			)
			(layer "B.Fab")
		)
		(fp_line
			(start 0.67945 0.3048)
			(end 0.67945 -0.305054)
			(stroke
				(width 0.1)
				(type default)
			)
			(layer "B.Fab")
		)
		(fp_line
			(start 0.12065 0.3048)
			(end 0.67945 0.3048)
			(stroke
				(width 0.1)
				(type default)
			)
			(layer "B.Fab")
		)
		(fp_line
			(start -0.120396 0.3048)
			(end -0.120396 0.2794)
			(stroke
				(width 0.1)
				(type default)
			)
			(layer "B.Fab")
		)
		(fp_line
			(start -0.67945 0.3048)
			(end -0.120396 0.3048)
			(stroke
				(width 0.1)
				(type default)
			)
			(layer "B.Fab")
		)
		(pad "1" smd circle
			(at 0.40005 0 270)
			(size 0 0)
			(layers "B.Cu" "B.Mask" "B.Paste")
			(net "FAN_5_SS")
		)
		(pad "2" smd circle
			(at -0.40005 0 270)
			(size 0 0)
			(layers "B.Cu" "B.Mask" "B.Paste")
			(net "GND")
		)
	)
	(footprint ""
		(layer "B.Cu")
		(at 11.715242 -258.562856 90)
		(property "Reference" "PC57"
			(at 0 0 90)
			(layer "B.SilkS")
			(hide yes)
			(effects
				(font
					(size 1.27 1.27)
				)
				(justify mirror)
			)
		)
		(property "Value" ""
			(at 0 0 90)
			(layer "B.Fab")
			(effects
				(font
					(size 1.27 1.27)
				)
				(justify mirror)
			)
		)
		(duplicate_pad_numbers_are_jumpers no)
		(fp_line
			(start 0.7874 -0.4064)
			(end -0.7874 -0.4064)
			(stroke
				(width 0.1524)
				(type default)
			)
			(layer "B.SilkS")
		)
		(fp_line
			(start -0.7874 -0.4064)
			(end -0.7874 0.4064)
			(stroke
				(width 0.1524)
				(type default)
			)
			(layer "B.SilkS")
		)
		(fp_line
			(start 0.7874 0.4064)
			(end 0.7874 -0.4064)
			(stroke
				(width 0.1524)
				(type default)
			)
			(layer "B.SilkS")
		)
		(fp_line
			(start -0.7874 0.4064)
			(end 0.7874 0.4064)
			(stroke
				(width 0.1524)
				(type default)
			)
			(layer "B.SilkS")
		)
		(fp_line
			(start 0.67945 -0.305054)
			(end 0.12065 -0.305054)
			(stroke
				(width 0.1)
				(type default)
			)
			(layer "B.Fab")
		)
		(fp_line
			(start 0.12065 -0.305054)
			(end 0.12065 -0.2794)
			(stroke
				(width 0.1)
				(type default)
			)
			(layer "B.Fab")
		)
		(fp_line
			(start -0.12065 -0.3048)
			(end -0.67945 -0.3048)
			(stroke
				(width 0.1)
				(type default)
			)
			(layer "B.Fab")
		)
		(fp_line
			(start -0.67945 -0.3048)
			(end -0.67945 0.3048)
			(stroke
				(width 0.1)
				(type default)
			)
			(layer "B.Fab")
		)
		(fp_line
			(start 0.12065 -0.2794)
			(end -0.12065 -0.2794)
			(stroke
				(width 0.1)
				(type default)
			)
			(layer "B.Fab")
		)
		(fp_line
			(start -0.12065 -0.2794)
			(end -0.12065 -0.3048)
			(stroke
				(width 0.1)
				(type default)
			)
			(layer "B.Fab")
		)
		(fp_line
			(start 0.12065 0.2794)
			(end 0.12065 0.3048)
			(stroke
				(width 0.1)
				(type default)
			)
			(layer "B.Fab")
		)
		(fp_line
			(start -0.120396 0.2794)
			(end 0.12065 0.2794)
			(stroke
				(width 0.1)
				(type default)
			)
			(layer "B.Fab")
		)
		(fp_line
			(start 0.67945 0.3048)
			(end 0.67945 -0.305054)
			(stroke
				(width 0.1)
				(type default)
			)
			(layer "B.Fab")
		)
		(fp_line
			(start 0.12065 0.3048)
			(end 0.67945 0.3048)
			(stroke
				(width 0.1)
				(type default)
			)
			(layer "B.Fab")
		)
		(fp_line
			(start -0.120396 0.3048)
			(end -0.120396 0.2794)
			(stroke
				(width 0.1)
				(type default)
			)
			(layer "B.Fab")
		)
		(fp_line
			(start -0.67945 0.3048)
			(end -0.120396 0.3048)
			(stroke
				(width 0.1)
				(type default)
			)
			(layer "B.Fab")
		)
		(pad "1" smd circle
			(at 0.40005 0 270)
			(size 0 0)
			(layers "B.Cu" "B.Mask" "B.Paste")
			(net "FAN_7_P5V")
		)
		(pad "2" smd circle
			(at -0.40005 0 270)
			(size 0 0)
			(layers "B.Cu" "B.Mask" "B.Paste")
			(net "GND")
		)
	)
	(footprint ""
		(layer "B.Cu")
		(at 40.894 -128.905 180)
		(property "Reference" "R5432"
			(at 0 0 0)
			(layer "B.SilkS")
			(hide yes)
			(effects
				(font
					(size 1.27 1.27)
				)
				(justify mirror)
			)
		)
		(property "Value" ""
			(at 0 0 0)
			(layer "B.Fab")
			(effects
				(font
					(size 1.27 1.27)
				)
				(justify mirror)
			)
		)
		(duplicate_pad_numbers_are_jumpers no)
		(fp_line
			(start 0.7874 0.4064)
			(end 0.7874 -0.4064)
			(stroke
				(width 0.1524)
				(type default)
			)
			(layer "B.SilkS")
		)
		(fp_line
			(start 0.7874 -0.4064)
			(end -0.7874 -0.4064)
			(stroke
				(width 0.1524)
				(type default)
			)
			(layer "B.SilkS")
		)
		(fp_line
			(start -0.7874 0.4064)
			(end 0.7874 0.4064)
			(stroke
				(width 0.1524)
				(type default)
			)
			(layer "B.SilkS")
		)
		(fp_line
			(start -0.7874 -0.4064)
			(end -0.7874 0.4064)
			(stroke
				(width 0.1524)
				(type default)
			)
			(layer "B.SilkS")
		)
		(fp_line
			(start 0.67945 0.3048)
			(end 0.67945 -0.305054)
			(stroke
				(width 0.1)
				(type default)
			)
			(layer "B.Fab")
		)
		(fp_line
			(start 0.67945 -0.305054)
			(end 0.12065 -0.305054)
			(stroke
				(width 0.1)
				(type default)
			)
			(layer "B.Fab")
		)
		(fp_line
			(start 0.12065 0.3048)
			(end 0.67945 0.3048)
			(stroke
				(width 0.1)
				(type default)
			)
			(layer "B.Fab")
		)
		(fp_line
			(start 0.12065 0.2794)
			(end 0.12065 0.3048)
			(stroke
				(width 0.1)
				(type default)
			)
			(layer "B.Fab")
		)
		(fp_line
			(start 0.12065 -0.2794)
			(end -0.12065 -0.2794)
			(stroke
				(width 0.1)
				(type default)
			)
			(layer "B.Fab")
		)
		(fp_line
			(start 0.12065 -0.305054)
			(end 0.12065 -0.2794)
			(stroke
				(width 0.1)
				(type default)
			)
			(layer "B.Fab")
		)
		(fp_line
			(start -0.120396 0.3048)
			(end -0.120396 0.2794)
			(stroke
				(width 0.1)
				(type default)
			)
			(layer "B.Fab")
		)
		(fp_line
			(start -0.120396 0.2794)
			(end 0.12065 0.2794)
			(stroke
				(width 0.1)
				(type default)
			)
			(layer "B.Fab")
		)
		(fp_line
			(start -0.12065 -0.2794)
			(end -0.12065 -0.3048)
			(stroke
				(width 0.1)
				(type default)
			)
			(layer "B.Fab")
		)
		(fp_line
			(start -0.12065 -0.3048)
			(end -0.67945 -0.3048)
			(stroke
				(width 0.1)
				(type default)
			)
			(layer "B.Fab")
		)
		(fp_line
			(start -0.67945 0.3048)
			(end -0.120396 0.3048)
			(stroke
				(width 0.1)
				(type default)
			)
			(layer "B.Fab")
		)
		(fp_line
			(start -0.67945 -0.3048)
			(end -0.67945 0.3048)
			(stroke
				(width 0.1)
				(type default)
			)
			(layer "B.Fab")
		)
		(pad "1" smd rect
			(at 0.40005 0 180)
			(size 0.4572 0.508)
			(layers "B.Cu" "B.Mask" "B.Paste")
			(net "FAN_3_TACH_IL")
		)
		(pad "2" smd rect
			(at -0.40005 0 180)
			(size 0.4572 0.508)
			(layers "B.Cu" "B.Mask" "B.Paste")
			(net "GND")
		)
	)
	(footprint ""
		(layer "B.Cu")
		(at 34.163 -271.526)
		(property "Reference" "PC1"
			(at 0 0 0)
			(layer "B.SilkS")
			(hide yes)
			(effects
				(font
					(size 1.27 1.27)
				)
				(justify mirror)
			)
		)
		(property "Value" ""
			(at 0 0 0)
			(layer "B.Fab")
			(effects
				(font
					(size 1.27 1.27)
				)
				(justify mirror)
			)
		)
		(duplicate_pad_numbers_are_jumpers no)
		(fp_line
			(start -1.524 -0.762)
			(end -1.524 0.762)
			(stroke
				(width 0.1524)
				(type default)
			)
			(layer "B.SilkS")
		)
		(fp_line
			(start -1.524 0.762)
			(end 1.524 0.762)
			(stroke
				(width 0.1524)
				(type default)
			)
			(layer "B.SilkS")
		)
		(fp_line
			(start 1.524 -0.762)
			(end -1.524 -0.762)
			(stroke
				(width 0.1524)
				(type default)
			)
			(layer "B.SilkS")
		)
		(fp_line
			(start 1.524 0.762)
			(end 1.524 -0.762)
			(stroke
				(width 0.1524)
				(type default)
			)
			(layer "B.SilkS")
		)
		(fp_line
			(start -1.1049 -0.724916)
			(end 1.1049 -0.724916)
			(stroke
				(width 0.1)
				(type default)
			)
			(layer "B.Fab")
		)
		(fp_line
			(start -1.1049 0.724916)
			(end -1.1049 -0.724916)
			(stroke
				(width 0.1)
				(type default)
			)
			(layer "B.Fab")
		)
		(fp_line
			(start 1.1049 -0.724916)
			(end 1.1049 0.724916)
			(stroke
				(width 0.1)
				(type default)
			)
			(layer "B.Fab")
		)
		(fp_line
			(start 1.1049 0.724916)
			(end -1.1049 0.724916)
			(stroke
				(width 0.1)
				(type default)
			)
			(layer "B.Fab")
		)
		(pad "1" smd rect
			(at 0.889 0)
			(size 1.016 1.27)
			(layers "B.Cu" "B.Mask" "B.Paste")
			(net "P52V_FAN_0")
		)
		(pad "2" smd rect
			(at -0.889 0)
			(size 1.016 1.27)
			(layers "B.Cu" "B.Mask" "B.Paste")
			(net "GND")
		)
	)
	(footprint ""
		(layer "B.Cu")
		(at 17.414494 -258.572 90)
		(property "Reference" "PC58"
			(at 0 0 90)
			(layer "B.SilkS")
			(hide yes)
			(effects
				(font
					(size 1.27 1.27)
				)
				(justify mirror)
			)
		)
		(property "Value" ""
			(at 0 0 90)
			(layer "B.Fab")
			(effects
				(font
					(size 1.27 1.27)
				)
				(justify mirror)
			)
		)
		(duplicate_pad_numbers_are_jumpers no)
		(fp_line
			(start 0.7874 -0.4064)
			(end -0.7874 -0.4064)
			(stroke
				(width 0.1524)
				(type default)
			)
			(layer "B.SilkS")
		)
		(fp_line
			(start -0.7874 -0.4064)
			(end -0.7874 0.4064)
			(stroke
				(width 0.1524)
				(type default)
			)
			(layer "B.SilkS")
		)
		(fp_line
			(start 0.7874 0.4064)
			(end 0.7874 -0.4064)
			(stroke
				(width 0.1524)
				(type default)
			)
			(layer "B.SilkS")
		)
		(fp_line
			(start -0.7874 0.4064)
			(end 0.7874 0.4064)
			(stroke
				(width 0.1524)
				(type default)
			)
			(layer "B.SilkS")
		)
		(fp_line
			(start 0.67945 -0.305054)
			(end 0.12065 -0.305054)
			(stroke
				(width 0.1)
				(type default)
			)
			(layer "B.Fab")
		)
		(fp_line
			(start 0.12065 -0.305054)
			(end 0.12065 -0.2794)
			(stroke
				(width 0.1)
				(type default)
			)
			(layer "B.Fab")
		)
		(fp_line
			(start -0.12065 -0.3048)
			(end -0.67945 -0.3048)
			(stroke
				(width 0.1)
				(type default)
			)
			(layer "B.Fab")
		)
		(fp_line
			(start -0.67945 -0.3048)
			(end -0.67945 0.3048)
			(stroke
				(width 0.1)
				(type default)
			)
			(layer "B.Fab")
		)
		(fp_line
			(start 0.12065 -0.2794)
			(end -0.12065 -0.2794)
			(stroke
				(width 0.1)
				(type default)
			)
			(layer "B.Fab")
		)
		(fp_line
			(start -0.12065 -0.2794)
			(end -0.12065 -0.3048)
			(stroke
				(width 0.1)
				(type default)
			)
			(layer "B.Fab")
		)
		(fp_line
			(start 0.12065 0.2794)
			(end 0.12065 0.3048)
			(stroke
				(width 0.1)
				(type default)
			)
			(layer "B.Fab")
		)
		(fp_line
			(start -0.120396 0.2794)
			(end 0.12065 0.2794)
			(stroke
				(width 0.1)
				(type default)
			)
			(layer "B.Fab")
		)
		(fp_line
			(start 0.67945 0.3048)
			(end 0.67945 -0.305054)
			(stroke
				(width 0.1)
				(type default)
			)
			(layer "B.Fab")
		)
		(fp_line
			(start 0.12065 0.3048)
			(end 0.67945 0.3048)
			(stroke
				(width 0.1)
				(type default)
			)
			(layer "B.Fab")
		)
		(fp_line
			(start -0.120396 0.3048)
			(end -0.120396 0.2794)
			(stroke
				(width 0.1)
				(type default)
			)
			(layer "B.Fab")
		)
		(fp_line
			(start -0.67945 0.3048)
			(end -0.120396 0.3048)
			(stroke
				(width 0.1)
				(type default)
			)
			(layer "B.Fab")
		)
		(pad "1" smd circle
			(at 0.40005 0 270)
			(size 0 0)
			(layers "B.Cu" "B.Mask" "B.Paste")
			(net "FAN_7_SS")
		)
		(pad "2" smd circle
			(at -0.40005 0 270)
			(size 0 0)
			(layers "B.Cu" "B.Mask" "B.Paste")
			(net "GND")
		)
	)
	(footprint ""
		(layer "B.Cu")
		(at 9.82599 -78.416912 90)
		(property "Reference" "PC62"
			(at 0 0 90)
			(layer "B.SilkS")
			(hide yes)
			(effects
				(font
					(size 1.27 1.27)
				)
				(justify mirror)
			)
		)
		(property "Value" ""
			(at 0 0 90)
			(layer "B.Fab")
			(effects
				(font
					(size 1.27 1.27)
				)
				(justify mirror)
			)
		)
		(duplicate_pad_numbers_are_jumpers no)
		(fp_line
			(start 1.524 -0.762)
			(end -1.524 -0.762)
			(stroke
				(width 0.1524)
				(type default)
			)
			(layer "B.SilkS")
		)
		(fp_line
			(start -1.524 -0.762)
			(end -1.524 0.762)
			(stroke
				(width 0.1524)
				(type default)
			)
			(layer "B.SilkS")
		)
		(fp_line
			(start 1.524 0.762)
			(end 1.524 -0.762)
			(stroke
				(width 0.1524)
				(type default)
			)
			(layer "B.SilkS")
		)
		(fp_line
			(start -1.524 0.762)
			(end 1.524 0.762)
			(stroke
				(width 0.1524)
				(type default)
			)
			(layer "B.SilkS")
		)
		(fp_line
			(start 1.1049 -0.724916)
			(end 1.1049 0.724916)
			(stroke
				(width 0.1)
				(type default)
			)
			(layer "B.Fab")
		)
		(fp_line
			(start -1.1049 -0.724916)
			(end 1.1049 -0.724916)
			(stroke
				(width 0.1)
				(type default)
			)
			(layer "B.Fab")
		)
		(fp_line
			(start 1.1049 0.724916)
			(end -1.1049 0.724916)
			(stroke
				(width 0.1)
				(type default)
			)
			(layer "B.Fab")
		)
		(fp_line
			(start -1.1049 0.724916)
			(end -1.1049 -0.724916)
			(stroke
				(width 0.1)
				(type default)
			)
			(layer "B.Fab")
		)
		(pad "1" smd rect
			(at 0.889 0 90)
			(size 1.016 1.27)
			(layers "B.Cu" "B.Mask" "B.Paste")
			(net "P52V_HSC")
		)
		(pad "2" smd rect
			(at -0.889 0 90)
			(size 1.016 1.27)
			(layers "B.Cu" "B.Mask" "B.Paste")
			(net "GND")
		)
	)
	(footprint ""
		(layer "B.Cu")
		(at 34.417 -64.837056 -90)
		(property "Reference" "PC20"
			(at 0 0 90)
			(layer "B.SilkS")
			(hide yes)
			(effects
				(font
					(size 1.27 1.27)
				)
				(justify mirror)
			)
		)
		(property "Value" ""
			(at 0 0 90)
			(layer "B.Fab")
			(effects
				(font
					(size 1.27 1.27)
				)
				(justify mirror)
			)
		)
		(duplicate_pad_numbers_are_jumpers no)
		(fp_line
			(start -0.7874 0.4064)
			(end 0.7874 0.4064)
			(stroke
				(width 0.1524)
				(type default)
			)
			(layer "B.SilkS")
		)
		(fp_line
			(start 0.7874 0.4064)
			(end 0.7874 -0.4064)
			(stroke
				(width 0.1524)
				(type default)
			)
			(layer "B.SilkS")
		)
		(fp_line
			(start -0.7874 -0.4064)
			(end -0.7874 0.4064)
			(stroke
				(width 0.1524)
				(type default)
			)
			(layer "B.SilkS")
		)
		(fp_line
			(start 0.7874 -0.4064)
			(end -0.7874 -0.4064)
			(stroke
				(width 0.1524)
				(type default)
			)
			(layer "B.SilkS")
		)
		(fp_line
			(start -0.67945 0.3048)
			(end -0.120396 0.3048)
			(stroke
				(width 0.1)
				(type default)
			)
			(layer "B.Fab")
		)
		(fp_line
			(start -0.120396 0.3048)
			(end -0.120396 0.2794)
			(stroke
				(width 0.1)
				(type default)
			)
			(layer "B.Fab")
		)
		(fp_line
			(start 0.12065 0.3048)
			(end 0.67945 0.3048)
			(stroke
				(width 0.1)
				(type default)
			)
			(layer "B.Fab")
		)
		(fp_line
			(start 0.67945 0.3048)
			(end 0.67945 -0.305054)
			(stroke
				(width 0.1)
				(type default)
			)
			(layer "B.Fab")
		)
		(fp_line
			(start -0.120396 0.2794)
			(end 0.12065 0.2794)
			(stroke
				(width 0.1)
				(type default)
			)
			(layer "B.Fab")
		)
		(fp_line
			(start 0.12065 0.2794)
			(end 0.12065 0.3048)
			(stroke
				(width 0.1)
				(type default)
			)
			(layer "B.Fab")
		)
		(fp_line
			(start -0.12065 -0.2794)
			(end -0.12065 -0.3048)
			(stroke
				(width 0.1)
				(type default)
			)
			(layer "B.Fab")
		)
		(fp_line
			(start 0.12065 -0.2794)
			(end -0.12065 -0.2794)
			(stroke
				(width 0.1)
				(type default)
			)
			(layer "B.Fab")
		)
		(fp_line
			(start -0.67945 -0.3048)
			(end -0.67945 0.3048)
			(stroke
				(width 0.1)
				(type default)
			)
			(layer "B.Fab")
		)
		(fp_line
			(start -0.12065 -0.3048)
			(end -0.67945 -0.3048)
			(stroke
				(width 0.1)
				(type default)
			)
			(layer "B.Fab")
		)
		(fp_line
			(start 0.12065 -0.305054)
			(end 0.12065 -0.2794)
			(stroke
				(width 0.1)
				(type default)
			)
			(layer "B.Fab")
		)
		(fp_line
			(start 0.67945 -0.305054)
			(end 0.12065 -0.305054)
			(stroke
				(width 0.1)
				(type default)
			)
			(layer "B.Fab")
		)
		(pad "1" smd circle
			(at 0.40005 0 90)
			(size 0 0)
			(layers "B.Cu" "B.Mask" "B.Paste")
			(net "FAN_3_SS")
		)
		(pad "2" smd circle
			(at -0.40005 0 90)
			(size 0 0)
			(layers "B.Cu" "B.Mask" "B.Paste")
			(net "GND")
		)
	)
	(footprint ""
		(layer "B.Cu")
		(at 15.367 -258.572 90)
		(property "Reference" "PR77"
			(at 0 0 90)
			(layer "B.SilkS")
			(hide yes)
			(effects
				(font
					(size 1.27 1.27)
				)
				(justify mirror)
			)
		)
		(property "Value" ""
			(at 0 0 90)
			(layer "B.Fab")
			(effects
				(font
					(size 1.27 1.27)
				)
				(justify mirror)
			)
		)
		(duplicate_pad_numbers_are_jumpers no)
		(fp_line
			(start 0.7874 -0.4064)
			(end -0.7874 -0.4064)
			(stroke
				(width 0.1524)
				(type default)
			)
			(layer "B.SilkS")
		)
		(fp_line
			(start -0.7874 -0.4064)
			(end -0.7874 0.4064)
			(stroke
				(width 0.1524)
				(type default)
			)
			(layer "B.SilkS")
		)
		(fp_line
			(start 0.7874 0.4064)
			(end 0.7874 -0.4064)
			(stroke
				(width 0.1524)
				(type default)
			)
			(layer "B.SilkS")
		)
		(fp_line
			(start -0.7874 0.4064)
			(end 0.7874 0.4064)
			(stroke
				(width 0.1524)
				(type default)
			)
			(layer "B.SilkS")
		)
		(fp_line
			(start 0.67945 -0.305054)
			(end 0.12065 -0.305054)
			(stroke
				(width 0.1)
				(type default)
			)
			(layer "B.Fab")
		)
		(fp_line
			(start 0.12065 -0.305054)
			(end 0.12065 -0.2794)
			(stroke
				(width 0.1)
				(type default)
			)
			(layer "B.Fab")
		)
		(fp_line
			(start -0.12065 -0.3048)
			(end -0.67945 -0.3048)
			(stroke
				(width 0.1)
				(type default)
			)
			(layer "B.Fab")
		)
		(fp_line
			(start -0.67945 -0.3048)
			(end -0.67945 0.3048)
			(stroke
				(width 0.1)
				(type default)
			)
			(layer "B.Fab")
		)
		(fp_line
			(start 0.12065 -0.2794)
			(end -0.12065 -0.2794)
			(stroke
				(width 0.1)
				(type default)
			)
			(layer "B.Fab")
		)
		(fp_line
			(start -0.12065 -0.2794)
			(end -0.12065 -0.3048)
			(stroke
				(width 0.1)
				(type default)
			)
			(layer "B.Fab")
		)
		(fp_line
			(start 0.12065 0.2794)
			(end 0.12065 0.3048)
			(stroke
				(width 0.1)
				(type default)
			)
			(layer "B.Fab")
		)
		(fp_line
			(start -0.120396 0.2794)
			(end 0.12065 0.2794)
			(stroke
				(width 0.1)
				(type default)
			)
			(layer "B.Fab")
		)
		(fp_line
			(start 0.67945 0.3048)
			(end 0.67945 -0.305054)
			(stroke
				(width 0.1)
				(type default)
			)
			(layer "B.Fab")
		)
		(fp_line
			(start 0.12065 0.3048)
			(end 0.67945 0.3048)
			(stroke
				(width 0.1)
				(type default)
			)
			(layer "B.Fab")
		)
		(fp_line
			(start -0.120396 0.3048)
			(end -0.120396 0.2794)
			(stroke
				(width 0.1)
				(type default)
			)
			(layer "B.Fab")
		)
		(fp_line
			(start -0.67945 0.3048)
			(end -0.120396 0.3048)
			(stroke
				(width 0.1)
				(type default)
			)
			(layer "B.Fab")
		)
		(pad "1" smd circle
			(at 0.40005 0 270)
			(size 0 0)
			(layers "B.Cu" "B.Mask" "B.Paste")
			(net "FAN_7_CLREF")
		)
		(pad "2" smd circle
			(at -0.40005 0 270)
			(size 0 0)
			(layers "B.Cu" "B.Mask" "B.Paste")
			(net "GND")
		)
	)
	(footprint ""
		(layer "B.Cu")
		(at 15.113 -73.971912 90)
		(property "Reference" "PR61"
			(at 0 0 90)
			(layer "B.SilkS")
			(hide yes)
			(effects
				(font
					(size 1.27 1.27)
				)
				(justify mirror)
			)
		)
		(property "Value" ""
			(at 0 0 90)
			(layer "B.Fab")
			(effects
				(font
					(size 1.27 1.27)
				)
				(justify mirror)
			)
		)
		(duplicate_pad_numbers_are_jumpers no)
		(fp_line
			(start 0.7874 -0.4064)
			(end -0.7874 -0.4064)
			(stroke
				(width 0.1524)
				(type default)
			)
			(layer "B.SilkS")
		)
		(fp_line
			(start -0.7874 -0.4064)
			(end -0.7874 0.4064)
			(stroke
				(width 0.1524)
				(type default)
			)
			(layer "B.SilkS")
		)
		(fp_line
			(start 0.7874 0.4064)
			(end 0.7874 -0.4064)
			(stroke
				(width 0.1524)
				(type default)
			)
			(layer "B.SilkS")
		)
		(fp_line
			(start -0.7874 0.4064)
			(end 0.7874 0.4064)
			(stroke
				(width 0.1524)
				(type default)
			)
			(layer "B.SilkS")
		)
		(fp_line
			(start 0.67945 -0.305054)
			(end 0.12065 -0.305054)
			(stroke
				(width 0.1)
				(type default)
			)
			(layer "B.Fab")
		)
		(fp_line
			(start 0.12065 -0.305054)
			(end 0.12065 -0.2794)
			(stroke
				(width 0.1)
				(type default)
			)
			(layer "B.Fab")
		)
		(fp_line
			(start -0.12065 -0.3048)
			(end -0.67945 -0.3048)
			(stroke
				(width 0.1)
				(type default)
			)
			(layer "B.Fab")
		)
		(fp_line
			(start -0.67945 -0.3048)
			(end -0.67945 0.3048)
			(stroke
				(width 0.1)
				(type default)
			)
			(layer "B.Fab")
		)
		(fp_line
			(start 0.12065 -0.2794)
			(end -0.12065 -0.2794)
			(stroke
				(width 0.1)
				(type default)
			)
			(layer "B.Fab")
		)
		(fp_line
			(start -0.12065 -0.2794)
			(end -0.12065 -0.3048)
			(stroke
				(width 0.1)
				(type default)
			)
			(layer "B.Fab")
		)
		(fp_line
			(start 0.12065 0.2794)
			(end 0.12065 0.3048)
			(stroke
				(width 0.1)
				(type default)
			)
			(layer "B.Fab")
		)
		(fp_line
			(start -0.120396 0.2794)
			(end 0.12065 0.2794)
			(stroke
				(width 0.1)
				(type default)
			)
			(layer "B.Fab")
		)
		(fp_line
			(start 0.67945 0.3048)
			(end 0.67945 -0.305054)
			(stroke
				(width 0.1)
				(type default)
			)
			(layer "B.Fab")
		)
		(fp_line
			(start 0.12065 0.3048)
			(end 0.67945 0.3048)
			(stroke
				(width 0.1)
				(type default)
			)
			(layer "B.Fab")
		)
		(fp_line
			(start -0.120396 0.3048)
			(end -0.120396 0.2794)
			(stroke
				(width 0.1)
				(type default)
			)
			(layer "B.Fab")
		)
		(fp_line
			(start -0.67945 0.3048)
			(end -0.120396 0.3048)
			(stroke
				(width 0.1)
				(type default)
			)
			(layer "B.Fab")
		)
		(pad "1" smd circle
			(at 0.40005 0 270)
			(size 0 0)
			(layers "B.Cu" "B.Mask" "B.Paste")
			(net "FAN_5_CLREF")
		)
		(pad "2" smd circle
			(at -0.40005 0 270)
			(size 0 0)
			(layers "B.Cu" "B.Mask" "B.Paste")
			(net "GND")
		)
	)
	(footprint ""
		(layer "B.Cu")
		(at 47.7266 -171.5008)
		(property "Reference" ""
			(at 0 0 0)
			(layer "B.SilkS")
			(hide yes)
			(effects
				(font
					(size 1.27 1.27)
				)
				(justify mirror)
			)
		)
		(property "Value" ""
			(at 0 0 0)
			(layer "B.Fab")
			(effects
				(font
					(size 1.27 1.27)
				)
				(justify mirror)
			)
		)
		(duplicate_pad_numbers_are_jumpers no)
		(pad "1" smd circle
			(at 0 0 180)
			(size 0.9906 0.9906)
			(layers "B.Cu" "B.Mask" "B.Paste")
			(net "Net_124")
		)
		(zone
			(layer "B.Cu")
			(hatch none 0.5)
			(connect_pads
				(clearance 0)
			)
			(min_thickness 0.25)
			(keepout
				(tracks not_allowed)
				(vias allowed)
				(pads allowed)
				(copperpour not_allowed)
				(footprints allowed)
			)
			(placement
				(enabled no)
				(sheetname "")
			)
			(fill
				(thermal_gap 0.5)
				(thermal_bridge_width 0.5)
				(island_removal_mode 0)
			)
			(polygon
				(pts
					(arc
						(start 49.3522 -171.5008)
						(mid 46.101 -171.5008)
						(end 49.3522 -171.5008)
					)
				)
			)
		)
	)
	(footprint ""
		(layer "B.Cu")
		(at 42.037 -258.572 90)
		(property "Reference" "PR9"
			(at 0 0 90)
			(layer "B.SilkS")
			(hide yes)
			(effects
				(font
					(size 1.27 1.27)
				)
				(justify mirror)
			)
		)
		(property "Value" ""
			(at 0 0 90)
			(layer "B.Fab")
			(effects
				(font
					(size 1.27 1.27)
				)
				(justify mirror)
			)
		)
		(duplicate_pad_numbers_are_jumpers no)
		(fp_line
			(start 0.7874 -0.4064)
			(end -0.7874 -0.4064)
			(stroke
				(width 0.1524)
				(type default)
			)
			(layer "B.SilkS")
		)
		(fp_line
			(start -0.7874 -0.4064)
			(end -0.7874 0.4064)
			(stroke
				(width 0.1524)
				(type default)
			)
			(layer "B.SilkS")
		)
		(fp_line
			(start 0.7874 0.4064)
			(end 0.7874 -0.4064)
			(stroke
				(width 0.1524)
				(type default)
			)
			(layer "B.SilkS")
		)
		(fp_line
			(start -0.7874 0.4064)
			(end 0.7874 0.4064)
			(stroke
				(width 0.1524)
				(type default)
			)
			(layer "B.SilkS")
		)
		(fp_line
			(start 0.67945 -0.305054)
			(end 0.12065 -0.305054)
			(stroke
				(width 0.1)
				(type default)
			)
			(layer "B.Fab")
		)
		(fp_line
			(start 0.12065 -0.305054)
			(end 0.12065 -0.2794)
			(stroke
				(width 0.1)
				(type default)
			)
			(layer "B.Fab")
		)
		(fp_line
			(start -0.12065 -0.3048)
			(end -0.67945 -0.3048)
			(stroke
				(width 0.1)
				(type default)
			)
			(layer "B.Fab")
		)
		(fp_line
			(start -0.67945 -0.3048)
			(end -0.67945 0.3048)
			(stroke
				(width 0.1)
				(type default)
			)
			(layer "B.Fab")
		)
		(fp_line
			(start 0.12065 -0.2794)
			(end -0.12065 -0.2794)
			(stroke
				(width 0.1)
				(type default)
			)
			(layer "B.Fab")
		)
		(fp_line
			(start -0.12065 -0.2794)
			(end -0.12065 -0.3048)
			(stroke
				(width 0.1)
				(type default)
			)
			(layer "B.Fab")
		)
		(fp_line
			(start 0.12065 0.2794)
			(end 0.12065 0.3048)
			(stroke
				(width 0.1)
				(type default)
			)
			(layer "B.Fab")
		)
		(fp_line
			(start -0.120396 0.2794)
			(end 0.12065 0.2794)
			(stroke
				(width 0.1)
				(type default)
			)
			(layer "B.Fab")
		)
		(fp_line
			(start 0.67945 0.3048)
			(end 0.67945 -0.305054)
			(stroke
				(width 0.1)
				(type default)
			)
			(layer "B.Fab")
		)
		(fp_line
			(start 0.12065 0.3048)
			(end 0.67945 0.3048)
			(stroke
				(width 0.1)
				(type default)
			)
			(layer "B.Fab")
		)
		(fp_line
			(start -0.120396 0.3048)
			(end -0.120396 0.2794)
			(stroke
				(width 0.1)
				(type default)
			)
			(layer "B.Fab")
		)
		(fp_line
			(start -0.67945 0.3048)
			(end -0.120396 0.3048)
			(stroke
				(width 0.1)
				(type default)
			)
			(layer "B.Fab")
		)
		(pad "1" smd circle
			(at 0.40005 0 270)
			(size 0 0)
			(layers "B.Cu" "B.Mask" "B.Paste")
			(net "FAN_0_CLREF")
		)
		(pad "2" smd circle
			(at -0.40005 0 270)
			(size 0 0)
			(layers "B.Cu" "B.Mask" "B.Paste")
			(net "GND")
		)
	)
	(footprint ""
		(layer "B.Cu")
		(at 46.471332 -63.532512 90)
		(property "Reference" "PD14"
			(at -5.518912 3.692398 270)
			(unlocked yes)
			(layer "B.SilkS")
			(effects
				(font
					(size 0.7874 0.5842)
					(thickness 0.1524)
				)
				(justify left mirror)
			)
		)
		(property "Value" ""
			(at 0 0 90)
			(layer "B.Fab")
			(effects
				(font
					(size 1.27 1.27)
				)
				(justify mirror)
			)
		)
		(duplicate_pad_numbers_are_jumpers no)
		(fp_line
			(start 4.647184 -3.109976)
			(end 4.647184 3.109976)
			(stroke
				(width 0.1524)
				(type default)
			)
			(layer "B.SilkS")
		)
		(fp_line
			(start -5.536184 -3.109976)
			(end 4.647184 -3.109976)
			(stroke
				(width 0.1524)
				(type default)
			)
			(layer "B.SilkS")
		)
		(fp_line
			(start -0.762 -1.143)
			(end -0.762 0.889)
			(stroke
				(width 0.1524)
				(type default)
			)
			(layer "B.SilkS")
		)
		(fp_line
			(start 0.635 -0.889)
			(end 0.635 0.635)
			(stroke
				(width 0.1524)
				(type default)
			)
			(layer "B.SilkS")
		)
		(fp_line
			(start 1.397 -0.127)
			(end 0.635 -0.127)
			(stroke
				(width 0.1524)
				(type default)
			)
			(layer "B.SilkS")
		)
		(fp_line
			(start -0.635 -0.127)
			(end 0.635 -0.889)
			(stroke
				(width 0.1524)
				(type default)
			)
			(layer "B.SilkS")
		)
		(fp_line
			(start -0.635 -0.127)
			(end -1.397 -0.127)
			(stroke
				(width 0.1524)
				(type default)
			)
			(layer "B.SilkS")
		)
		(fp_line
			(start 0.635 0.635)
			(end -0.635 -0.127)
			(stroke
				(width 0.1524)
				(type default)
			)
			(layer "B.SilkS")
		)
		(fp_line
			(start 4.647184 3.109976)
			(end -5.536184 3.109976)
			(stroke
				(width 0.1524)
				(type default)
			)
			(layer "B.SilkS")
		)
		(fp_line
			(start -5.536184 3.109976)
			(end -5.536184 -3.109976)
			(stroke
				(width 0.1524)
				(type default)
			)
			(layer "B.SilkS")
		)
		(fp_poly
			(pts
				(xy -5.5118 -3.0988) (xy -5.5118 3.1496) (xy -4.572 3.1496) (xy -4.572 -3.0988)
			)
			(stroke
				(width 0)
				(type default)
			)
			(fill yes)
			(layer "B.SilkS")
		)
		(fp_line
			(start 3.554984 -3.109976)
			(end 3.554984 3.109976)
			(stroke
				(width 0.1)
				(type default)
			)
			(layer "B.Fab")
		)
		(fp_line
			(start -3.554984 -3.109976)
			(end 3.554984 -3.109976)
			(stroke
				(width 0.1)
				(type default)
			)
			(layer "B.Fab")
		)
		(fp_line
			(start 3.554984 3.109976)
			(end -3.554984 3.109976)
			(stroke
				(width 0.1)
				(type default)
			)
			(layer "B.Fab")
		)
		(fp_line
			(start -3.554984 3.109976)
			(end -3.554984 -3.109976)
			(stroke
				(width 0.1)
				(type default)
			)
			(layer "B.Fab")
		)
		(fp_text user "+"
			(at 6.1214 -0.32385 90)
			(unlocked yes)
			(layer "B.SilkS")
			(effects
				(font
					(size 1.905 1.4224)
					(thickness 0.1524)
				)
				(justify left mirror)
			)
		)
		(fp_text user "-"
			(at -5.493512 0.931418 90)
			(unlocked yes)
			(layer "B.SilkS")
			(effects
				(font
					(size 1.905 1.4224)
					(thickness 0.1524)
				)
				(justify left mirror)
			)
		)
		(fp_text user "-"
			(at -5.334 -0.34925 90)
			(unlocked yes)
			(layer "B.Fab")
			(effects
				(font
					(size 1.905 1.4224)
					(thickness 0.1524)
				)
				(justify left mirror)
			)
		)
		(fp_text user "+"
			(at 6.1214 -0.32385 90)
			(unlocked yes)
			(layer "B.Fab")
			(effects
				(font
					(size 1.905 1.4224)
					(thickness 0.1524)
				)
				(justify left mirror)
			)
		)
		(pad "A" smd rect
			(at 3.299968 0 270)
			(size 2.413 3.302)
			(layers "B.Cu" "B.Mask" "B.Paste")
			(net "GND")
		)
		(pad "C" smd rect
			(at -3.299968 0 270)
			(size 2.413 3.302)
			(layers "B.Cu" "B.Mask" "B.Paste")
			(net "P52V_HSC")
		)
	)
	(footprint ""
		(layer "B.Cu")
		(at 6.09473 -48.413924)
		(property "Reference" "C2109"
			(at 0 0 0)
			(layer "B.SilkS")
			(hide yes)
			(effects
				(font
					(size 1.27 1.27)
				)
				(justify mirror)
			)
		)
		(property "Value" ""
			(at 0 0 0)
			(layer "B.Fab")
			(effects
				(font
					(size 1.27 1.27)
				)
				(justify mirror)
			)
		)
		(duplicate_pad_numbers_are_jumpers no)
		(fp_line
			(start -2.2098 -0.9398)
			(end -2.2098 0.9398)
			(stroke
				(width 0.1524)
				(type default)
			)
			(layer "B.SilkS")
		)
		(fp_line
			(start -2.2098 0.9398)
			(end 2.2098 0.9398)
			(stroke
				(width 0.1524)
				(type default)
			)
			(layer "B.SilkS")
		)
		(fp_line
			(start 2.2098 -0.9398)
			(end -2.2098 -0.9398)
			(stroke
				(width 0.1524)
				(type default)
			)
			(layer "B.SilkS")
		)
		(fp_line
			(start 2.2098 0.9398)
			(end 2.2098 -0.9398)
			(stroke
				(width 0.1524)
				(type default)
			)
			(layer "B.SilkS")
		)
		(fp_line
			(start -1.700022 -0.899922)
			(end -1.700022 0.899922)
			(stroke
				(width 0.1)
				(type default)
			)
			(layer "B.Fab")
		)
		(fp_line
			(start -1.700022 0.899922)
			(end 1.700022 0.899922)
			(stroke
				(width 0.1)
				(type default)
			)
			(layer "B.Fab")
		)
		(fp_line
			(start 1.700022 -0.899922)
			(end -1.700022 -0.899922)
			(stroke
				(width 0.1)
				(type default)
			)
			(layer "B.Fab")
		)
		(fp_line
			(start 1.700022 0.899922)
			(end 1.700022 -0.899922)
			(stroke
				(width 0.1)
				(type default)
			)
			(layer "B.Fab")
		)
		(pad "1" smd rect
			(at 1.4732 0)
			(size 1.1684 1.5748)
			(layers "B.Cu" "B.Mask" "B.Paste")
			(net "P52V_FAN_4")
		)
		(pad "2" smd rect
			(at -1.4732 0)
			(size 1.1684 1.5748)
			(layers "B.Cu" "B.Mask" "B.Paste")
			(net "GND")
		)
	)
	(footprint ""
		(layer "B.Cu")
		(at 16.782796 -272.097754 180)
		(property "Reference" "C2118"
			(at 0 0 0)
			(layer "B.SilkS")
			(hide yes)
			(effects
				(font
					(size 1.27 1.27)
				)
				(justify mirror)
			)
		)
		(property "Value" ""
			(at 0 0 0)
			(layer "B.Fab")
			(effects
				(font
					(size 1.27 1.27)
				)
				(justify mirror)
			)
		)
		(duplicate_pad_numbers_are_jumpers no)
		(fp_line
			(start 2.2098 0.9398)
			(end 2.2098 -0.9398)
			(stroke
				(width 0.1524)
				(type default)
			)
			(layer "B.SilkS")
		)
		(fp_line
			(start 2.2098 -0.9398)
			(end -2.2098 -0.9398)
			(stroke
				(width 0.1524)
				(type default)
			)
			(layer "B.SilkS")
		)
		(fp_line
			(start -2.2098 0.9398)
			(end 2.2098 0.9398)
			(stroke
				(width 0.1524)
				(type default)
			)
			(layer "B.SilkS")
		)
		(fp_line
			(start -2.2098 -0.9398)
			(end -2.2098 0.9398)
			(stroke
				(width 0.1524)
				(type default)
			)
			(layer "B.SilkS")
		)
		(fp_line
			(start 1.700022 0.899922)
			(end 1.700022 -0.899922)
			(stroke
				(width 0.1)
				(type default)
			)
			(layer "B.Fab")
		)
		(fp_line
			(start 1.700022 -0.899922)
			(end -1.700022 -0.899922)
			(stroke
				(width 0.1)
				(type default)
			)
			(layer "B.Fab")
		)
		(fp_line
			(start -1.700022 0.899922)
			(end 1.700022 0.899922)
			(stroke
				(width 0.1)
				(type default)
			)
			(layer "B.Fab")
		)
		(fp_line
			(start -1.700022 -0.899922)
			(end -1.700022 0.899922)
			(stroke
				(width 0.1)
				(type default)
			)
			(layer "B.Fab")
		)
		(pad "1" smd rect
			(at 1.4732 0 180)
			(size 1.1684 1.5748)
			(layers "B.Cu" "B.Mask" "B.Paste")
			(net "P52V_FAN_7")
		)
		(pad "2" smd rect
			(at -1.4732 0 180)
			(size 1.1684 1.5748)
			(layers "B.Cu" "B.Mask" "B.Paste")
			(net "GND")
		)
	)
	(footprint ""
		(layer "B.Cu")
		(at 10.795 -249.428 -90)
		(property "Reference" "PC2124"
			(at 0 0 90)
			(layer "B.SilkS")
			(hide yes)
			(effects
				(font
					(size 1.27 1.27)
				)
				(justify mirror)
			)
		)
		(property "Value" ""
			(at 0 0 90)
			(layer "B.Fab")
			(effects
				(font
					(size 1.27 1.27)
				)
				(justify mirror)
			)
		)
		(duplicate_pad_numbers_are_jumpers no)
		(fp_line
			(start -0.7874 0.4064)
			(end 0.7874 0.4064)
			(stroke
				(width 0.1524)
				(type default)
			)
			(layer "B.SilkS")
		)
		(fp_line
			(start 0.7874 0.4064)
			(end 0.7874 -0.4064)
			(stroke
				(width 0.1524)
				(type default)
			)
			(layer "B.SilkS")
		)
		(fp_line
			(start -0.7874 -0.4064)
			(end -0.7874 0.4064)
			(stroke
				(width 0.1524)
				(type default)
			)
			(layer "B.SilkS")
		)
		(fp_line
			(start 0.7874 -0.4064)
			(end -0.7874 -0.4064)
			(stroke
				(width 0.1524)
				(type default)
			)
			(layer "B.SilkS")
		)
		(fp_line
			(start -0.67945 0.3048)
			(end -0.120396 0.3048)
			(stroke
				(width 0.1)
				(type default)
			)
			(layer "B.Fab")
		)
		(fp_line
			(start -0.120396 0.3048)
			(end -0.120396 0.2794)
			(stroke
				(width 0.1)
				(type default)
			)
			(layer "B.Fab")
		)
		(fp_line
			(start 0.12065 0.3048)
			(end 0.67945 0.3048)
			(stroke
				(width 0.1)
				(type default)
			)
			(layer "B.Fab")
		)
		(fp_line
			(start 0.67945 0.3048)
			(end 0.67945 -0.305054)
			(stroke
				(width 0.1)
				(type default)
			)
			(layer "B.Fab")
		)
		(fp_line
			(start -0.120396 0.2794)
			(end 0.12065 0.2794)
			(stroke
				(width 0.1)
				(type default)
			)
			(layer "B.Fab")
		)
		(fp_line
			(start 0.12065 0.2794)
			(end 0.12065 0.3048)
			(stroke
				(width 0.1)
				(type default)
			)
			(layer "B.Fab")
		)
		(fp_line
			(start -0.12065 -0.2794)
			(end -0.12065 -0.3048)
			(stroke
				(width 0.1)
				(type default)
			)
			(layer "B.Fab")
		)
		(fp_line
			(start 0.12065 -0.2794)
			(end -0.12065 -0.2794)
			(stroke
				(width 0.1)
				(type default)
			)
			(layer "B.Fab")
		)
		(fp_line
			(start -0.67945 -0.3048)
			(end -0.67945 0.3048)
			(stroke
				(width 0.1)
				(type default)
			)
			(layer "B.Fab")
		)
		(fp_line
			(start -0.12065 -0.3048)
			(end -0.67945 -0.3048)
			(stroke
				(width 0.1)
				(type default)
			)
			(layer "B.Fab")
		)
		(fp_line
			(start 0.12065 -0.305054)
			(end 0.12065 -0.2794)
			(stroke
				(width 0.1)
				(type default)
			)
			(layer "B.Fab")
		)
		(fp_line
			(start 0.67945 -0.305054)
			(end 0.12065 -0.305054)
			(stroke
				(width 0.1)
				(type default)
			)
			(layer "B.Fab")
		)
		(pad "1" smd circle
			(at 0.40005 0 90)
			(size 0 0)
			(layers "B.Cu" "B.Mask" "B.Paste")
			(net "FAN_6_TEMP")
		)
		(pad "2" smd circle
			(at -0.40005 0 90)
			(size 0 0)
			(layers "B.Cu" "B.Mask" "B.Paste")
			(net "GND")
		)
	)
	(footprint ""
		(layer "B.Cu")
		(at 6.223 -64.389 180)
		(property "Reference" "PR53"
			(at 0 0 0)
			(layer "B.SilkS")
			(hide yes)
			(effects
				(font
					(size 1.27 1.27)
				)
				(justify mirror)
			)
		)
		(property "Value" ""
			(at 0 0 0)
			(layer "B.Fab")
			(effects
				(font
					(size 1.27 1.27)
				)
				(justify mirror)
			)
		)
		(duplicate_pad_numbers_are_jumpers no)
		(fp_line
			(start 0.7874 0.4064)
			(end 0.7874 -0.4064)
			(stroke
				(width 0.1524)
				(type default)
			)
			(layer "B.SilkS")
		)
		(fp_line
			(start 0.7874 -0.4064)
			(end -0.7874 -0.4064)
			(stroke
				(width 0.1524)
				(type default)
			)
			(layer "B.SilkS")
		)
		(fp_line
			(start -0.7874 0.4064)
			(end 0.7874 0.4064)
			(stroke
				(width 0.1524)
				(type default)
			)
			(layer "B.SilkS")
		)
		(fp_line
			(start -0.7874 -0.4064)
			(end -0.7874 0.4064)
			(stroke
				(width 0.1524)
				(type default)
			)
			(layer "B.SilkS")
		)
		(fp_line
			(start 0.67945 0.3048)
			(end 0.67945 -0.305054)
			(stroke
				(width 0.1)
				(type default)
			)
			(layer "B.Fab")
		)
		(fp_line
			(start 0.67945 -0.305054)
			(end 0.12065 -0.305054)
			(stroke
				(width 0.1)
				(type default)
			)
			(layer "B.Fab")
		)
		(fp_line
			(start 0.12065 0.3048)
			(end 0.67945 0.3048)
			(stroke
				(width 0.1)
				(type default)
			)
			(layer "B.Fab")
		)
		(fp_line
			(start 0.12065 0.2794)
			(end 0.12065 0.3048)
			(stroke
				(width 0.1)
				(type default)
			)
			(layer "B.Fab")
		)
		(fp_line
			(start 0.12065 -0.2794)
			(end -0.12065 -0.2794)
			(stroke
				(width 0.1)
				(type default)
			)
			(layer "B.Fab")
		)
		(fp_line
			(start 0.12065 -0.305054)
			(end 0.12065 -0.2794)
			(stroke
				(width 0.1)
				(type default)
			)
			(layer "B.Fab")
		)
		(fp_line
			(start -0.120396 0.3048)
			(end -0.120396 0.2794)
			(stroke
				(width 0.1)
				(type default)
			)
			(layer "B.Fab")
		)
		(fp_line
			(start -0.120396 0.2794)
			(end 0.12065 0.2794)
			(stroke
				(width 0.1)
				(type default)
			)
			(layer "B.Fab")
		)
		(fp_line
			(start -0.12065 -0.2794)
			(end -0.12065 -0.3048)
			(stroke
				(width 0.1)
				(type default)
			)
			(layer "B.Fab")
		)
		(fp_line
			(start -0.12065 -0.3048)
			(end -0.67945 -0.3048)
			(stroke
				(width 0.1)
				(type default)
			)
			(layer "B.Fab")
		)
		(fp_line
			(start -0.67945 0.3048)
			(end -0.120396 0.3048)
			(stroke
				(width 0.1)
				(type default)
			)
			(layer "B.Fab")
		)
		(fp_line
			(start -0.67945 -0.3048)
			(end -0.67945 0.3048)
			(stroke
				(width 0.1)
				(type default)
			)
			(layer "B.Fab")
		)
		(pad "1" smd circle
			(at 0.40005 0)
			(size 0 0)
			(layers "B.Cu" "B.Mask" "B.Paste")
			(net "FAN_4_CLREF")
		)
		(pad "2" smd circle
			(at -0.40005 0)
			(size 0 0)
			(layers "B.Cu" "B.Mask" "B.Paste")
			(net "GND")
		)
	)
	(footprint ""
		(layer "B.Cu")
		(at 40.894 -134.62 180)
		(property "Reference" "R5426"
			(at 0 0 0)
			(layer "B.SilkS")
			(hide yes)
			(effects
				(font
					(size 1.27 1.27)
				)
				(justify mirror)
			)
		)
		(property "Value" ""
			(at 0 0 0)
			(layer "B.Fab")
			(effects
				(font
					(size 1.27 1.27)
				)
				(justify mirror)
			)
		)
		(duplicate_pad_numbers_are_jumpers no)
		(fp_line
			(start 0.7874 0.4064)
			(end 0.7874 -0.4064)
			(stroke
				(width 0.1524)
				(type default)
			)
			(layer "B.SilkS")
		)
		(fp_line
			(start 0.7874 -0.4064)
			(end -0.7874 -0.4064)
			(stroke
				(width 0.1524)
				(type default)
			)
			(layer "B.SilkS")
		)
		(fp_line
			(start -0.7874 0.4064)
			(end 0.7874 0.4064)
			(stroke
				(width 0.1524)
				(type default)
			)
			(layer "B.SilkS")
		)
		(fp_line
			(start -0.7874 -0.4064)
			(end -0.7874 0.4064)
			(stroke
				(width 0.1524)
				(type default)
			)
			(layer "B.SilkS")
		)
		(fp_line
			(start 0.67945 0.3048)
			(end 0.67945 -0.305054)
			(stroke
				(width 0.1)
				(type default)
			)
			(layer "B.Fab")
		)
		(fp_line
			(start 0.67945 -0.305054)
			(end 0.12065 -0.305054)
			(stroke
				(width 0.1)
				(type default)
			)
			(layer "B.Fab")
		)
		(fp_line
			(start 0.12065 0.3048)
			(end 0.67945 0.3048)
			(stroke
				(width 0.1)
				(type default)
			)
			(layer "B.Fab")
		)
		(fp_line
			(start 0.12065 0.2794)
			(end 0.12065 0.3048)
			(stroke
				(width 0.1)
				(type default)
			)
			(layer "B.Fab")
		)
		(fp_line
			(start 0.12065 -0.2794)
			(end -0.12065 -0.2794)
			(stroke
				(width 0.1)
				(type default)
			)
			(layer "B.Fab")
		)
		(fp_line
			(start 0.12065 -0.305054)
			(end 0.12065 -0.2794)
			(stroke
				(width 0.1)
				(type default)
			)
			(layer "B.Fab")
		)
		(fp_line
			(start -0.120396 0.3048)
			(end -0.120396 0.2794)
			(stroke
				(width 0.1)
				(type default)
			)
			(layer "B.Fab")
		)
		(fp_line
			(start -0.120396 0.2794)
			(end 0.12065 0.2794)
			(stroke
				(width 0.1)
				(type default)
			)
			(layer "B.Fab")
		)
		(fp_line
			(start -0.12065 -0.2794)
			(end -0.12065 -0.3048)
			(stroke
				(width 0.1)
				(type default)
			)
			(layer "B.Fab")
		)
		(fp_line
			(start -0.12065 -0.3048)
			(end -0.67945 -0.3048)
			(stroke
				(width 0.1)
				(type default)
			)
			(layer "B.Fab")
		)
		(fp_line
			(start -0.67945 0.3048)
			(end -0.120396 0.3048)
			(stroke
				(width 0.1)
				(type default)
			)
			(layer "B.Fab")
		)
		(fp_line
			(start -0.67945 -0.3048)
			(end -0.67945 0.3048)
			(stroke
				(width 0.1)
				(type default)
			)
			(layer "B.Fab")
		)
		(pad "1" smd rect
			(at 0.40005 0 180)
			(size 0.4572 0.508)
			(layers "B.Cu" "B.Mask" "B.Paste")
			(net "FAN_0_TACH_IL")
		)
		(pad "2" smd rect
			(at -0.40005 0 180)
			(size 0.4572 0.508)
			(layers "B.Cu" "B.Mask" "B.Paste")
			(net "GND")
		)
	)
	(footprint ""
		(layer "B.Cu")
		(at 44.6786 -54.8386 180)
		(property "Reference" "PC36"
			(at 0 0 0)
			(layer "B.SilkS")
			(hide yes)
			(effects
				(font
					(size 1.27 1.27)
				)
				(justify mirror)
			)
		)
		(property "Value" ""
			(at 0 0 0)
			(layer "B.Fab")
			(effects
				(font
					(size 1.27 1.27)
				)
				(justify mirror)
			)
		)
		(duplicate_pad_numbers_are_jumpers no)
		(fp_line
			(start 1.524 0.762)
			(end 1.524 -0.762)
			(stroke
				(width 0.1524)
				(type default)
			)
			(layer "B.SilkS")
		)
		(fp_line
			(start 1.524 -0.762)
			(end -1.524 -0.762)
			(stroke
				(width 0.1524)
				(type default)
			)
			(layer "B.SilkS")
		)
		(fp_line
			(start -1.524 0.762)
			(end 1.524 0.762)
			(stroke
				(width 0.1524)
				(type default)
			)
			(layer "B.SilkS")
		)
		(fp_line
			(start -1.524 -0.762)
			(end -1.524 0.762)
			(stroke
				(width 0.1524)
				(type default)
			)
			(layer "B.SilkS")
		)
		(fp_line
			(start 1.1049 0.724916)
			(end -1.1049 0.724916)
			(stroke
				(width 0.1)
				(type default)
			)
			(layer "B.Fab")
		)
		(fp_line
			(start 1.1049 -0.724916)
			(end 1.1049 0.724916)
			(stroke
				(width 0.1)
				(type default)
			)
			(layer "B.Fab")
		)
		(fp_line
			(start -1.1049 0.724916)
			(end -1.1049 -0.724916)
			(stroke
				(width 0.1)
				(type default)
			)
			(layer "B.Fab")
		)
		(fp_line
			(start -1.1049 -0.724916)
			(end 1.1049 -0.724916)
			(stroke
				(width 0.1)
				(type default)
			)
			(layer "B.Fab")
		)
		(pad "1" smd rect
			(at 0.889 0 180)
			(size 1.016 1.27)
			(layers "B.Cu" "B.Mask" "B.Paste")
			(net "P52V_FAN_3")
		)
		(pad "2" smd rect
			(at -0.889 0 180)
			(size 1.016 1.27)
			(layers "B.Cu" "B.Mask" "B.Paste")
			(net "GND")
		)
	)
	(footprint ""
		(layer "B.Cu")
		(at 10.329418 -60.382912 -90)
		(property "Reference" "PC61"
			(at 0 0 90)
			(layer "B.SilkS")
			(hide yes)
			(effects
				(font
					(size 1.27 1.27)
				)
				(justify mirror)
			)
		)
		(property "Value" ""
			(at 0 0 90)
			(layer "B.Fab")
			(effects
				(font
					(size 1.27 1.27)
				)
				(justify mirror)
			)
		)
		(duplicate_pad_numbers_are_jumpers no)
		(fp_line
			(start -1.524 0.762)
			(end 1.524 0.762)
			(stroke
				(width 0.1524)
				(type default)
			)
			(layer "B.SilkS")
		)
		(fp_line
			(start 1.524 0.762)
			(end 1.524 -0.762)
			(stroke
				(width 0.1524)
				(type default)
			)
			(layer "B.SilkS")
		)
		(fp_line
			(start -1.524 -0.762)
			(end -1.524 0.762)
			(stroke
				(width 0.1524)
				(type default)
			)
			(layer "B.SilkS")
		)
		(fp_line
			(start 1.524 -0.762)
			(end -1.524 -0.762)
			(stroke
				(width 0.1524)
				(type default)
			)
			(layer "B.SilkS")
		)
		(fp_line
			(start -1.1049 0.724916)
			(end -1.1049 -0.724916)
			(stroke
				(width 0.1)
				(type default)
			)
			(layer "B.Fab")
		)
		(fp_line
			(start 1.1049 0.724916)
			(end -1.1049 0.724916)
			(stroke
				(width 0.1)
				(type default)
			)
			(layer "B.Fab")
		)
		(fp_line
			(start -1.1049 -0.724916)
			(end 1.1049 -0.724916)
			(stroke
				(width 0.1)
				(type default)
			)
			(layer "B.Fab")
		)
		(fp_line
			(start 1.1049 -0.724916)
			(end 1.1049 0.724916)
			(stroke
				(width 0.1)
				(type default)
			)
			(layer "B.Fab")
		)
		(pad "1" smd rect
			(at 0.889 0 270)
			(size 1.016 1.27)
			(layers "B.Cu" "B.Mask" "B.Paste")
			(net "P52V_HSC")
		)
		(pad "2" smd rect
			(at -0.889 0 270)
			(size 1.016 1.27)
			(layers "B.Cu" "B.Mask" "B.Paste")
			(net "GND")
		)
	)
	(footprint ""
		(layer "B.Cu")
		(at 9.906 -171.831 180)
		(property "Reference" "C1939"
			(at 0 0 0)
			(layer "B.SilkS")
			(hide yes)
			(effects
				(font
					(size 1.27 1.27)
				)
				(justify mirror)
			)
		)
		(property "Value" ""
			(at 0 0 0)
			(layer "B.Fab")
			(effects
				(font
					(size 1.27 1.27)
				)
				(justify mirror)
			)
		)
		(duplicate_pad_numbers_are_jumpers no)
		(fp_line
			(start 0.7874 0.4064)
			(end 0.7874 -0.4064)
			(stroke
				(width 0.1524)
				(type default)
			)
			(layer "B.SilkS")
		)
		(fp_line
			(start 0.7874 -0.4064)
			(end -0.7874 -0.4064)
			(stroke
				(width 0.1524)
				(type default)
			)
			(layer "B.SilkS")
		)
		(fp_line
			(start -0.7874 0.4064)
			(end 0.7874 0.4064)
			(stroke
				(width 0.1524)
				(type default)
			)
			(layer "B.SilkS")
		)
		(fp_line
			(start -0.7874 -0.4064)
			(end -0.7874 0.4064)
			(stroke
				(width 0.1524)
				(type default)
			)
			(layer "B.SilkS")
		)
		(fp_line
			(start 0.67945 0.3048)
			(end 0.67945 -0.305054)
			(stroke
				(width 0.1)
				(type default)
			)
			(layer "B.Fab")
		)
		(fp_line
			(start 0.67945 -0.305054)
			(end 0.12065 -0.305054)
			(stroke
				(width 0.1)
				(type default)
			)
			(layer "B.Fab")
		)
		(fp_line
			(start 0.12065 0.3048)
			(end 0.67945 0.3048)
			(stroke
				(width 0.1)
				(type default)
			)
			(layer "B.Fab")
		)
		(fp_line
			(start 0.12065 0.2794)
			(end 0.12065 0.3048)
			(stroke
				(width 0.1)
				(type default)
			)
			(layer "B.Fab")
		)
		(fp_line
			(start 0.12065 -0.2794)
			(end -0.12065 -0.2794)
			(stroke
				(width 0.1)
				(type default)
			)
			(layer "B.Fab")
		)
		(fp_line
			(start 0.12065 -0.305054)
			(end 0.12065 -0.2794)
			(stroke
				(width 0.1)
				(type default)
			)
			(layer "B.Fab")
		)
		(fp_line
			(start -0.120396 0.3048)
			(end -0.120396 0.2794)
			(stroke
				(width 0.1)
				(type default)
			)
			(layer "B.Fab")
		)
		(fp_line
			(start -0.120396 0.2794)
			(end 0.12065 0.2794)
			(stroke
				(width 0.1)
				(type default)
			)
			(layer "B.Fab")
		)
		(fp_line
			(start -0.12065 -0.2794)
			(end -0.12065 -0.3048)
			(stroke
				(width 0.1)
				(type default)
			)
			(layer "B.Fab")
		)
		(fp_line
			(start -0.12065 -0.3048)
			(end -0.67945 -0.3048)
			(stroke
				(width 0.1)
				(type default)
			)
			(layer "B.Fab")
		)
		(fp_line
			(start -0.67945 0.3048)
			(end -0.120396 0.3048)
			(stroke
				(width 0.1)
				(type default)
			)
			(layer "B.Fab")
		)
		(fp_line
			(start -0.67945 -0.3048)
			(end -0.67945 0.3048)
			(stroke
				(width 0.1)
				(type default)
			)
			(layer "B.Fab")
		)
		(pad "1" smd circle
			(at 0.40005 0)
			(size 0 0)
			(layers "B.Cu" "B.Mask" "B.Paste")
			(net "P3V3_AUX")
		)
		(pad "2" smd circle
			(at -0.40005 0)
			(size 0 0)
			(layers "B.Cu" "B.Mask" "B.Paste")
			(net "GND")
		)
	)
	(footprint ""
		(layer "B.Cu")
		(at 35.1536 -93.479112)
		(property "Reference" "C2103"
			(at 0 0 0)
			(layer "B.SilkS")
			(hide yes)
			(effects
				(font
					(size 1.27 1.27)
				)
				(justify mirror)
			)
		)
		(property "Value" ""
			(at 0 0 0)
			(layer "B.Fab")
			(effects
				(font
					(size 1.27 1.27)
				)
				(justify mirror)
			)
		)
		(duplicate_pad_numbers_are_jumpers no)
		(fp_line
			(start -2.2098 -0.9398)
			(end -2.2098 0.9398)
			(stroke
				(width 0.1524)
				(type default)
			)
			(layer "B.SilkS")
		)
		(fp_line
			(start -2.2098 0.9398)
			(end 2.2098 0.9398)
			(stroke
				(width 0.1524)
				(type default)
			)
			(layer "B.SilkS")
		)
		(fp_line
			(start 2.2098 -0.9398)
			(end -2.2098 -0.9398)
			(stroke
				(width 0.1524)
				(type default)
			)
			(layer "B.SilkS")
		)
		(fp_line
			(start 2.2098 0.9398)
			(end 2.2098 -0.9398)
			(stroke
				(width 0.1524)
				(type default)
			)
			(layer "B.SilkS")
		)
		(fp_line
			(start -1.700022 -0.899922)
			(end -1.700022 0.899922)
			(stroke
				(width 0.1)
				(type default)
			)
			(layer "B.Fab")
		)
		(fp_line
			(start -1.700022 0.899922)
			(end 1.700022 0.899922)
			(stroke
				(width 0.1)
				(type default)
			)
			(layer "B.Fab")
		)
		(fp_line
			(start 1.700022 -0.899922)
			(end -1.700022 -0.899922)
			(stroke
				(width 0.1)
				(type default)
			)
			(layer "B.Fab")
		)
		(fp_line
			(start 1.700022 0.899922)
			(end 1.700022 -0.899922)
			(stroke
				(width 0.1)
				(type default)
			)
			(layer "B.Fab")
		)
		(pad "1" smd rect
			(at 1.4732 0)
			(size 1.1684 1.5748)
			(layers "B.Cu" "B.Mask" "B.Paste")
			(net "P52V_FAN_2")
		)
		(pad "2" smd rect
			(at -1.4732 0)
			(size 1.1684 1.5748)
			(layers "B.Cu" "B.Mask" "B.Paste")
			(net "GND")
		)
	)
	(footprint ""
		(layer "B.Cu")
		(at 43.0784 -43.085512)
		(property "Reference" "PD10"
			(at 4.826 3.894582 0)
			(unlocked yes)
			(layer "B.SilkS")
			(effects
				(font
					(size 0.7874 0.5842)
					(thickness 0.1524)
				)
				(justify left mirror)
			)
		)
		(property "Value" ""
			(at 0 0 0)
			(layer "B.Fab")
			(effects
				(font
					(size 1.27 1.27)
				)
				(justify mirror)
			)
		)
		(duplicate_pad_numbers_are_jumpers no)
		(fp_line
			(start -5.334 0)
			(end -5.334 -3.109976)
			(stroke
				(width 0.1524)
				(type default)
			)
			(layer "B.SilkS")
		)
		(fp_line
			(start -5.334 3.109976)
			(end -5.334 0)
			(stroke
				(width 0.1524)
				(type default)
			)
			(layer "B.SilkS")
		)
		(fp_line
			(start -5.334 3.109976)
			(end -4.8133 3.109976)
			(stroke
				(width 0.1524)
				(type default)
			)
			(layer "B.SilkS")
		)
		(fp_line
			(start -5.207 3.109976)
			(end -5.207 -3.109976)
			(stroke
				(width 0.1524)
				(type default)
			)
			(layer "B.SilkS")
		)
		(fp_line
			(start -5.1308 3.109976)
			(end -5.1308 -3.109976)
			(stroke
				(width 0.1524)
				(type default)
			)
			(layer "B.SilkS")
		)
		(fp_line
			(start -5.0292 3.109976)
			(end -5.0292 -3.109976)
			(stroke
				(width 0.1524)
				(type default)
			)
			(layer "B.SilkS")
		)
		(fp_line
			(start -4.9276 3.109976)
			(end -4.9276 -3.109976)
			(stroke
				(width 0.1524)
				(type default)
			)
			(layer "B.SilkS")
		)
		(fp_line
			(start -4.826 -3.109976)
			(end -4.826 0)
			(stroke
				(width 0.1524)
				(type default)
			)
			(layer "B.SilkS")
		)
		(fp_line
			(start -4.826 0)
			(end -4.826 3.109976)
			(stroke
				(width 0.1524)
				(type default)
			)
			(layer "B.SilkS")
		)
		(fp_line
			(start -4.826 3.109976)
			(end 4.826 3.109976)
			(stroke
				(width 0.1524)
				(type default)
			)
			(layer "B.SilkS")
		)
		(fp_line
			(start -4.8133 -3.109976)
			(end -5.3467 -3.109976)
			(stroke
				(width 0.1524)
				(type default)
			)
			(layer "B.SilkS")
		)
		(fp_line
			(start -1.143 0)
			(end -1.8034 0)
			(stroke
				(width 0.1524)
				(type default)
			)
			(layer "B.SilkS")
		)
		(fp_line
			(start -1.143 0)
			(end 1.016 -1.016)
			(stroke
				(width 0.1524)
				(type default)
			)
			(layer "B.SilkS")
		)
		(fp_line
			(start -1.143 1.397)
			(end -1.143 -1.397)
			(stroke
				(width 0.1524)
				(type default)
			)
			(layer "B.SilkS")
		)
		(fp_line
			(start 1.016 -1.016)
			(end 1.016 1.016)
			(stroke
				(width 0.1524)
				(type default)
			)
			(layer "B.SilkS")
		)
		(fp_line
			(start 1.016 1.016)
			(end -1.016 0)
			(stroke
				(width 0.1524)
				(type default)
			)
			(layer "B.SilkS")
		)
		(fp_line
			(start 1.0922 0)
			(end 1.7018 0)
			(stroke
				(width 0.1524)
				(type default)
			)
			(layer "B.SilkS")
		)
		(fp_line
			(start 4.826 -3.109976)
			(end -4.826 -3.109976)
			(stroke
				(width 0.1524)
				(type default)
			)
			(layer "B.SilkS")
		)
		(fp_line
			(start 4.826 0)
			(end 4.826 -3.109976)
			(stroke
				(width 0.1524)
				(type default)
			)
			(layer "B.SilkS")
		)
		(fp_line
			(start 4.826 3.109976)
			(end 4.826 0)
			(stroke
				(width 0.1524)
				(type default)
			)
			(layer "B.SilkS")
		)
		(fp_line
			(start -3.554984 -3.109976)
			(end -3.554984 3.109976)
			(stroke
				(width 0.1)
				(type default)
			)
			(layer "B.Fab")
		)
		(fp_line
			(start -3.554984 3.109976)
			(end 3.554984 3.109976)
			(stroke
				(width 0.1)
				(type default)
			)
			(layer "B.Fab")
		)
		(fp_line
			(start -1.143 0)
			(end -1.8034 0)
			(stroke
				(width 0.1)
				(type default)
			)
			(layer "B.Fab")
		)
		(fp_line
			(start -1.143 0)
			(end 1.016 -1.016)
			(stroke
				(width 0.1)
				(type default)
			)
			(layer "B.Fab")
		)
		(fp_line
			(start -1.143 1.397)
			(end -1.143 -1.397)
			(stroke
				(width 0.1)
				(type default)
			)
			(layer "B.Fab")
		)
		(fp_line
			(start 1.016 -1.016)
			(end 1.016 1.016)
			(stroke
				(width 0.1)
				(type default)
			)
			(layer "B.Fab")
		)
		(fp_line
			(start 1.016 1.016)
			(end -1.016 0)
			(stroke
				(width 0.1)
				(type default)
			)
			(layer "B.Fab")
		)
		(fp_line
			(start 1.0922 0)
			(end 1.7018 0)
			(stroke
				(width 0.1)
				(type default)
			)
			(layer "B.Fab")
		)
		(fp_line
			(start 3.554984 -3.109976)
			(end -3.554984 -3.109976)
			(stroke
				(width 0.1)
				(type default)
			)
			(layer "B.Fab")
		)
		(fp_line
			(start 3.554984 3.109976)
			(end 3.554984 -3.109976)
			(stroke
				(width 0.1)
				(type default)
			)
			(layer "B.Fab")
		)
		(fp_text user "-"
			(at -6.6802 0.22225 180)
			(unlocked yes)
			(layer "B.SilkS")
			(effects
				(font
					(size 1.905 1.4224)
					(thickness 0.1524)
				)
				(justify left mirror)
			)
		)
		(fp_text user "+"
			(at 5.5626 0.432562 180)
			(unlocked yes)
			(layer "B.SilkS")
			(effects
				(font
					(size 1.905 1.4224)
					(thickness 0.1524)
				)
				(justify left mirror)
			)
		)
		(fp_text user "-"
			(at -6.6802 0.22225 180)
			(unlocked yes)
			(layer "B.Fab")
			(effects
				(font
					(size 1.905 1.4224)
					(thickness 0.1524)
				)
				(justify left mirror)
			)
		)
		(fp_text user "+"
			(at 4.5466 0.19685 180)
			(unlocked yes)
			(layer "B.Fab")
			(effects
				(font
					(size 1.905 1.4224)
					(thickness 0.1524)
				)
				(justify left mirror)
			)
		)
		(pad "A" smd rect
			(at 3.400044 0)
			(size 2.5146 3.302)
			(layers "B.Cu" "B.Mask" "B.Paste")
			(net "GND")
		)
		(pad "C" smd rect
			(at -3.400044 0)
			(size 2.5146 3.302)
			(layers "B.Cu" "B.Mask" "B.Paste")
			(net "P52V_FAN_3")
		)
	)
	(footprint ""
		(layer "B.Cu")
		(at 40.767 -73.971912 90)
		(property "Reference" "PC31"
			(at 0 0 90)
			(layer "B.SilkS")
			(hide yes)
			(effects
				(font
					(size 1.27 1.27)
				)
				(justify mirror)
			)
		)
		(property "Value" ""
			(at 0 0 90)
			(layer "B.Fab")
			(effects
				(font
					(size 1.27 1.27)
				)
				(justify mirror)
			)
		)
		(duplicate_pad_numbers_are_jumpers no)
		(fp_line
			(start 0.7874 -0.4064)
			(end -0.7874 -0.4064)
			(stroke
				(width 0.1524)
				(type default)
			)
			(layer "B.SilkS")
		)
		(fp_line
			(start -0.7874 -0.4064)
			(end -0.7874 0.4064)
			(stroke
				(width 0.1524)
				(type default)
			)
			(layer "B.SilkS")
		)
		(fp_line
			(start 0.7874 0.4064)
			(end 0.7874 -0.4064)
			(stroke
				(width 0.1524)
				(type default)
			)
			(layer "B.SilkS")
		)
		(fp_line
			(start -0.7874 0.4064)
			(end 0.7874 0.4064)
			(stroke
				(width 0.1524)
				(type default)
			)
			(layer "B.SilkS")
		)
		(fp_line
			(start 0.67945 -0.305054)
			(end 0.12065 -0.305054)
			(stroke
				(width 0.1)
				(type default)
			)
			(layer "B.Fab")
		)
		(fp_line
			(start 0.12065 -0.305054)
			(end 0.12065 -0.2794)
			(stroke
				(width 0.1)
				(type default)
			)
			(layer "B.Fab")
		)
		(fp_line
			(start -0.12065 -0.3048)
			(end -0.67945 -0.3048)
			(stroke
				(width 0.1)
				(type default)
			)
			(layer "B.Fab")
		)
		(fp_line
			(start -0.67945 -0.3048)
			(end -0.67945 0.3048)
			(stroke
				(width 0.1)
				(type default)
			)
			(layer "B.Fab")
		)
		(fp_line
			(start 0.12065 -0.2794)
			(end -0.12065 -0.2794)
			(stroke
				(width 0.1)
				(type default)
			)
			(layer "B.Fab")
		)
		(fp_line
			(start -0.12065 -0.2794)
			(end -0.12065 -0.3048)
			(stroke
				(width 0.1)
				(type default)
			)
			(layer "B.Fab")
		)
		(fp_line
			(start 0.12065 0.2794)
			(end 0.12065 0.3048)
			(stroke
				(width 0.1)
				(type default)
			)
			(layer "B.Fab")
		)
		(fp_line
			(start -0.120396 0.2794)
			(end 0.12065 0.2794)
			(stroke
				(width 0.1)
				(type default)
			)
			(layer "B.Fab")
		)
		(fp_line
			(start 0.67945 0.3048)
			(end 0.67945 -0.305054)
			(stroke
				(width 0.1)
				(type default)
			)
			(layer "B.Fab")
		)
		(fp_line
			(start 0.12065 0.3048)
			(end 0.67945 0.3048)
			(stroke
				(width 0.1)
				(type default)
			)
			(layer "B.Fab")
		)
		(fp_line
			(start -0.120396 0.3048)
			(end -0.120396 0.2794)
			(stroke
				(width 0.1)
				(type default)
			)
			(layer "B.Fab")
		)
		(fp_line
			(start -0.67945 0.3048)
			(end -0.120396 0.3048)
			(stroke
				(width 0.1)
				(type default)
			)
			(layer "B.Fab")
		)
		(pad "1" smd circle
			(at 0.40005 0 270)
			(size 0 0)
			(layers "B.Cu" "B.Mask" "B.Paste")
			(net "FAN_2_P3V_R")
		)
		(pad "2" smd circle
			(at -0.40005 0 270)
			(size 0 0)
			(layers "B.Cu" "B.Mask" "B.Paste")
			(net "GND")
		)
	)
	(footprint ""
		(layer "B.Cu")
		(at 39.365428 -252.894846 180)
		(property "Reference" "U379"
			(at -3.432302 -0.037846 270)
			(unlocked yes)
			(layer "B.SilkS")
			(effects
				(font
					(size 0.7874 0.5842)
					(thickness 0.1524)
				)
				(justify mirror)
			)
		)
		(property "Value" ""
			(at 0 0 0)
			(layer "B.Fab")
			(effects
				(font
					(size 1.27 1.27)
				)
				(justify mirror)
			)
		)
		(duplicate_pad_numbers_are_jumpers no)
		(fp_line
			(start 1.7018 1.1176)
			(end 1.7018 -1.1176)
			(stroke
				(width 0.1524)
				(type default)
			)
			(layer "B.SilkS")
		)
		(fp_line
			(start 0.254 -1.1176)
			(end 1.7018 -1.1176)
			(stroke
				(width 0.1524)
				(type default)
			)
			(layer "B.SilkS")
		)
		(fp_line
			(start 0 -0.7112)
			(end 0.254 -1.1176)
			(stroke
				(width 0.1524)
				(type default)
			)
			(layer "B.SilkS")
		)
		(fp_line
			(start -0.254 -1.1176)
			(end 0 -0.7112)
			(stroke
				(width 0.1524)
				(type default)
			)
			(layer "B.SilkS")
		)
		(fp_line
			(start -1.7018 1.1176)
			(end 1.7018 1.1176)
			(stroke
				(width 0.1524)
				(type default)
			)
			(layer "B.SilkS")
		)
		(fp_line
			(start -1.7018 -1.1176)
			(end -0.254 -1.1176)
			(stroke
				(width 0.1524)
				(type default)
			)
			(layer "B.SilkS")
		)
		(fp_line
			(start -1.7018 -1.1176)
			(end -1.7018 1.1176)
			(stroke
				(width 0.1524)
				(type default)
			)
			(layer "B.SilkS")
		)
		(fp_poly
			(pts
				(xy 1.8161 -0.675386) (xy 2.4003 -0.446786) (xy 2.4003 -0.878586)
			)
			(stroke
				(width 0)
				(type default)
			)
			(fill yes)
			(layer "B.SilkS")
		)
		(fp_line
			(start 1.5494 1.1176)
			(end 1.5494 -1.1176)
			(stroke
				(width 0.1)
				(type default)
			)
			(layer "B.Fab")
		)
		(fp_line
			(start 0.254 -1.1176)
			(end 1.5494 -1.1176)
			(stroke
				(width 0.1)
				(type default)
			)
			(layer "B.Fab")
		)
		(fp_line
			(start -0.254 -1.1176)
			(end 0.254 -1.1176)
			(stroke
				(width 0.1)
				(type default)
			)
			(layer "B.Fab")
		)
		(fp_line
			(start -1.5494 1.1176)
			(end 1.5494 1.1176)
			(stroke
				(width 0.1)
				(type default)
			)
			(layer "B.Fab")
		)
		(fp_line
			(start -1.5494 -1.1176)
			(end -0.254 -1.1176)
			(stroke
				(width 0.1)
				(type default)
			)
			(layer "B.Fab")
		)
		(fp_line
			(start -1.5494 -1.1176)
			(end -1.5494 1.1176)
			(stroke
				(width 0.1)
				(type default)
			)
			(layer "B.Fab")
		)
		(fp_poly
			(pts
				(xy 1.8161 -0.675386) (xy 2.4003 -0.446786) (xy 2.4003 -0.878586)
			)
			(stroke
				(width 0)
				(type default)
			)
			(fill yes)
			(layer "B.Fab")
		)
		(pad "1" smd rect
			(at 0.962406 -0.649986 90)
			(size 0.3302 1.1684)
			(layers "B.Cu" "B.Mask" "B.Paste")
			(net "FAN_1_PRESENT_R")
		)
		(pad "2" smd rect
			(at 0.962406 0 90)
			(size 0.3302 1.1684)
			(layers "B.Cu" "B.Mask" "B.Paste")
			(net "P52V_FAN_1_BUFF_EN_R")
		)
		(pad "3" smd rect
			(at 0.962406 0.649986 90)
			(size 0.3302 1.1684)
			(layers "B.Cu" "B.Mask" "B.Paste")
			(net "GND")
		)
		(pad "4" smd rect
			(at -0.962406 0.649986 90)
			(size 0.3302 1.1684)
			(layers "B.Cu" "B.Mask" "B.Paste")
			(net "P52V_FAN_1_EN")
		)
		(pad "5" smd rect
			(at -0.962406 -0.649986 90)
			(size 0.3302 1.1684)
			(layers "B.Cu" "B.Mask" "B.Paste")
			(net "P3V3_AUX")
		)
	)
	(footprint ""
		(layer "B.Cu")
		(at 5.070348 -237.718346)
		(property "Reference" "PC49"
			(at 0 0 0)
			(layer "B.SilkS")
			(hide yes)
			(effects
				(font
					(size 1.27 1.27)
				)
				(justify mirror)
			)
		)
		(property "Value" ""
			(at 0 0 0)
			(layer "B.Fab")
			(effects
				(font
					(size 1.27 1.27)
				)
				(justify mirror)
			)
		)
		(duplicate_pad_numbers_are_jumpers no)
		(fp_line
			(start -1.524 -0.762)
			(end -1.524 0.762)
			(stroke
				(width 0.1524)
				(type default)
			)
			(layer "B.SilkS")
		)
		(fp_line
			(start -1.524 0.762)
			(end 1.524 0.762)
			(stroke
				(width 0.1524)
				(type default)
			)
			(layer "B.SilkS")
		)
		(fp_line
			(start 1.524 -0.762)
			(end -1.524 -0.762)
			(stroke
				(width 0.1524)
				(type default)
			)
			(layer "B.SilkS")
		)
		(fp_line
			(start 1.524 0.762)
			(end 1.524 -0.762)
			(stroke
				(width 0.1524)
				(type default)
			)
			(layer "B.SilkS")
		)
		(fp_line
			(start -1.1049 -0.724916)
			(end 1.1049 -0.724916)
			(stroke
				(width 0.1)
				(type default)
			)
			(layer "B.Fab")
		)
		(fp_line
			(start -1.1049 0.724916)
			(end -1.1049 -0.724916)
			(stroke
				(width 0.1)
				(type default)
			)
			(layer "B.Fab")
		)
		(fp_line
			(start 1.1049 -0.724916)
			(end 1.1049 0.724916)
			(stroke
				(width 0.1)
				(type default)
			)
			(layer "B.Fab")
		)
		(fp_line
			(start 1.1049 0.724916)
			(end -1.1049 0.724916)
			(stroke
				(width 0.1)
				(type default)
			)
			(layer "B.Fab")
		)
		(pad "1" smd rect
			(at 0.889 0)
			(size 1.016 1.27)
			(layers "B.Cu" "B.Mask" "B.Paste")
			(net "P52V_FAN_6")
		)
		(pad "2" smd rect
			(at -0.889 0)
			(size 1.016 1.27)
			(layers "B.Cu" "B.Mask" "B.Paste")
			(net "GND")
		)
	)
	(footprint ""
		(layer "B.Cu")
		(at 40.513 -258.572 90)
		(property "Reference" "PC3"
			(at 0 0 90)
			(layer "B.SilkS")
			(hide yes)
			(effects
				(font
					(size 1.27 1.27)
				)
				(justify mirror)
			)
		)
		(property "Value" ""
			(at 0 0 90)
			(layer "B.Fab")
			(effects
				(font
					(size 1.27 1.27)
				)
				(justify mirror)
			)
		)
		(duplicate_pad_numbers_are_jumpers no)
		(fp_line
			(start 0.7874 -0.4064)
			(end -0.7874 -0.4064)
			(stroke
				(width 0.1524)
				(type default)
			)
			(layer "B.SilkS")
		)
		(fp_line
			(start -0.7874 -0.4064)
			(end -0.7874 0.4064)
			(stroke
				(width 0.1524)
				(type default)
			)
			(layer "B.SilkS")
		)
		(fp_line
			(start 0.7874 0.4064)
			(end 0.7874 -0.4064)
			(stroke
				(width 0.1524)
				(type default)
			)
			(layer "B.SilkS")
		)
		(fp_line
			(start -0.7874 0.4064)
			(end 0.7874 0.4064)
			(stroke
				(width 0.1524)
				(type default)
			)
			(layer "B.SilkS")
		)
		(fp_line
			(start 0.67945 -0.305054)
			(end 0.12065 -0.305054)
			(stroke
				(width 0.1)
				(type default)
			)
			(layer "B.Fab")
		)
		(fp_line
			(start 0.12065 -0.305054)
			(end 0.12065 -0.2794)
			(stroke
				(width 0.1)
				(type default)
			)
			(layer "B.Fab")
		)
		(fp_line
			(start -0.12065 -0.3048)
			(end -0.67945 -0.3048)
			(stroke
				(width 0.1)
				(type default)
			)
			(layer "B.Fab")
		)
		(fp_line
			(start -0.67945 -0.3048)
			(end -0.67945 0.3048)
			(stroke
				(width 0.1)
				(type default)
			)
			(layer "B.Fab")
		)
		(fp_line
			(start 0.12065 -0.2794)
			(end -0.12065 -0.2794)
			(stroke
				(width 0.1)
				(type default)
			)
			(layer "B.Fab")
		)
		(fp_line
			(start -0.12065 -0.2794)
			(end -0.12065 -0.3048)
			(stroke
				(width 0.1)
				(type default)
			)
			(layer "B.Fab")
		)
		(fp_line
			(start 0.12065 0.2794)
			(end 0.12065 0.3048)
			(stroke
				(width 0.1)
				(type default)
			)
			(layer "B.Fab")
		)
		(fp_line
			(start -0.120396 0.2794)
			(end 0.12065 0.2794)
			(stroke
				(width 0.1)
				(type default)
			)
			(layer "B.Fab")
		)
		(fp_line
			(start 0.67945 0.3048)
			(end 0.67945 -0.305054)
			(stroke
				(width 0.1)
				(type default)
			)
			(layer "B.Fab")
		)
		(fp_line
			(start 0.12065 0.3048)
			(end 0.67945 0.3048)
			(stroke
				(width 0.1)
				(type default)
			)
			(layer "B.Fab")
		)
		(fp_line
			(start -0.120396 0.3048)
			(end -0.120396 0.2794)
			(stroke
				(width 0.1)
				(type default)
			)
			(layer "B.Fab")
		)
		(fp_line
			(start -0.67945 0.3048)
			(end -0.120396 0.3048)
			(stroke
				(width 0.1)
				(type default)
			)
			(layer "B.Fab")
		)
		(pad "1" smd circle
			(at 0.40005 0 270)
			(size 0 0)
			(layers "B.Cu" "B.Mask" "B.Paste")
			(net "FAN_0_P3V_R")
		)
		(pad "2" smd circle
			(at -0.40005 0 270)
			(size 0 0)
			(layers "B.Cu" "B.Mask" "B.Paste")
			(net "GND")
		)
	)
	(footprint ""
		(layer "B.Cu")
		(at 5.50799 -263.017 -90)
		(property "Reference" "PD18"
			(at -2.54 -3.73634 270)
			(unlocked yes)
			(layer "B.SilkS")
			(effects
				(font
					(size 0.7874 0.5842)
					(thickness 0.1524)
				)
				(justify left mirror)
			)
		)
		(property "Value" ""
			(at 0 0 90)
			(layer "B.Fab")
			(effects
				(font
					(size 1.27 1.27)
				)
				(justify mirror)
			)
		)
		(duplicate_pad_numbers_are_jumpers no)
		(fp_line
			(start -5.536184 3.109976)
			(end -5.536184 -3.109976)
			(stroke
				(width 0.1524)
				(type default)
			)
			(layer "B.SilkS")
		)
		(fp_line
			(start 4.647184 3.109976)
			(end -5.536184 3.109976)
			(stroke
				(width 0.1524)
				(type default)
			)
			(layer "B.SilkS")
		)
		(fp_line
			(start 0.635 0.635)
			(end -0.635 -0.127)
			(stroke
				(width 0.1524)
				(type default)
			)
			(layer "B.SilkS")
		)
		(fp_line
			(start -0.635 -0.127)
			(end -1.397 -0.127)
			(stroke
				(width 0.1524)
				(type default)
			)
			(layer "B.SilkS")
		)
		(fp_line
			(start -0.635 -0.127)
			(end 0.635 -0.889)
			(stroke
				(width 0.1524)
				(type default)
			)
			(layer "B.SilkS")
		)
		(fp_line
			(start 1.397 -0.127)
			(end 0.635 -0.127)
			(stroke
				(width 0.1524)
				(type default)
			)
			(layer "B.SilkS")
		)
		(fp_line
			(start 0.635 -0.889)
			(end 0.635 0.635)
			(stroke
				(width 0.1524)
				(type default)
			)
			(layer "B.SilkS")
		)
		(fp_line
			(start -0.762 -1.143)
			(end -0.762 0.889)
			(stroke
				(width 0.1524)
				(type default)
			)
			(layer "B.SilkS")
		)
		(fp_line
			(start -5.536184 -3.109976)
			(end 4.647184 -3.109976)
			(stroke
				(width 0.1524)
				(type default)
			)
			(layer "B.SilkS")
		)
		(fp_line
			(start 4.647184 -3.109976)
			(end 4.647184 3.109976)
			(stroke
				(width 0.1524)
				(type default)
			)
			(layer "B.SilkS")
		)
		(fp_poly
			(pts
				(xy -5.5118 -3.0988) (xy -5.5118 3.1496) (xy -4.572 3.1496) (xy -4.572 -3.0988)
			)
			(stroke
				(width 0)
				(type default)
			)
			(fill yes)
			(layer "B.SilkS")
		)
		(fp_line
			(start -3.554984 3.109976)
			(end -3.554984 -3.109976)
			(stroke
				(width 0.1)
				(type default)
			)
			(layer "B.Fab")
		)
		(fp_line
			(start 3.554984 3.109976)
			(end -3.554984 3.109976)
			(stroke
				(width 0.1)
				(type default)
			)
			(layer "B.Fab")
		)
		(fp_line
			(start -3.554984 -3.109976)
			(end 3.554984 -3.109976)
			(stroke
				(width 0.1)
				(type default)
			)
			(layer "B.Fab")
		)
		(fp_line
			(start 3.554984 -3.109976)
			(end 3.554984 3.109976)
			(stroke
				(width 0.1)
				(type default)
			)
			(layer "B.Fab")
		)
		(fp_text user "+"
			(at 6.096 1.85674 270)
			(unlocked yes)
			(layer "B.SilkS")
			(effects
				(font
					(size 1.905 1.4224)
					(thickness 0.1524)
				)
				(justify left mirror)
			)
		)
		(fp_text user "-"
			(at -5.334 -2.08026 270)
			(unlocked yes)
			(layer "B.SilkS")
			(effects
				(font
					(size 1.905 1.4224)
					(thickness 0.1524)
				)
				(justify left mirror)
			)
		)
		(fp_text user "+"
			(at 6.1214 -0.32385 270)
			(unlocked yes)
			(layer "B.Fab")
			(effects
				(font
					(size 1.905 1.4224)
					(thickness 0.1524)
				)
				(justify left mirror)
			)
		)
		(fp_text user "-"
			(at -5.334 -0.34925 270)
			(unlocked yes)
			(layer "B.Fab")
			(effects
				(font
					(size 1.905 1.4224)
					(thickness 0.1524)
				)
				(justify left mirror)
			)
		)
		(pad "A" smd rect
			(at 3.299968 0 90)
			(size 2.413 3.302)
			(layers "B.Cu" "B.Mask" "B.Paste")
			(net "GND")
		)
		(pad "C" smd rect
			(at -3.299968 0 90)
			(size 2.413 3.302)
			(layers "B.Cu" "B.Mask" "B.Paste")
			(net "P52V_HSC")
		)
	)
	(footprint ""
		(layer "B.Cu")
		(at 42.418 -73.971912 -90)
		(property "Reference" "PC3120"
			(at 0 0 90)
			(layer "B.SilkS")
			(hide yes)
			(effects
				(font
					(size 1.27 1.27)
				)
				(justify mirror)
			)
		)
		(property "Value" ""
			(at 0 0 90)
			(layer "B.Fab")
			(effects
				(font
					(size 1.27 1.27)
				)
				(justify mirror)
			)
		)
		(duplicate_pad_numbers_are_jumpers no)
		(fp_line
			(start -0.7874 0.4064)
			(end 0.7874 0.4064)
			(stroke
				(width 0.1524)
				(type default)
			)
			(layer "B.SilkS")
		)
		(fp_line
			(start 0.7874 0.4064)
			(end 0.7874 -0.4064)
			(stroke
				(width 0.1524)
				(type default)
			)
			(layer "B.SilkS")
		)
		(fp_line
			(start -0.7874 -0.4064)
			(end -0.7874 0.4064)
			(stroke
				(width 0.1524)
				(type default)
			)
			(layer "B.SilkS")
		)
		(fp_line
			(start 0.7874 -0.4064)
			(end -0.7874 -0.4064)
			(stroke
				(width 0.1524)
				(type default)
			)
			(layer "B.SilkS")
		)
		(fp_line
			(start -0.67945 0.3048)
			(end -0.120396 0.3048)
			(stroke
				(width 0.1)
				(type default)
			)
			(layer "B.Fab")
		)
		(fp_line
			(start -0.120396 0.3048)
			(end -0.120396 0.2794)
			(stroke
				(width 0.1)
				(type default)
			)
			(layer "B.Fab")
		)
		(fp_line
			(start 0.12065 0.3048)
			(end 0.67945 0.3048)
			(stroke
				(width 0.1)
				(type default)
			)
			(layer "B.Fab")
		)
		(fp_line
			(start 0.67945 0.3048)
			(end 0.67945 -0.305054)
			(stroke
				(width 0.1)
				(type default)
			)
			(layer "B.Fab")
		)
		(fp_line
			(start -0.120396 0.2794)
			(end 0.12065 0.2794)
			(stroke
				(width 0.1)
				(type default)
			)
			(layer "B.Fab")
		)
		(fp_line
			(start 0.12065 0.2794)
			(end 0.12065 0.3048)
			(stroke
				(width 0.1)
				(type default)
			)
			(layer "B.Fab")
		)
		(fp_line
			(start -0.12065 -0.2794)
			(end -0.12065 -0.3048)
			(stroke
				(width 0.1)
				(type default)
			)
			(layer "B.Fab")
		)
		(fp_line
			(start 0.12065 -0.2794)
			(end -0.12065 -0.2794)
			(stroke
				(width 0.1)
				(type default)
			)
			(layer "B.Fab")
		)
		(fp_line
			(start -0.67945 -0.3048)
			(end -0.67945 0.3048)
			(stroke
				(width 0.1)
				(type default)
			)
			(layer "B.Fab")
		)
		(fp_line
			(start -0.12065 -0.3048)
			(end -0.67945 -0.3048)
			(stroke
				(width 0.1)
				(type default)
			)
			(layer "B.Fab")
		)
		(fp_line
			(start 0.12065 -0.305054)
			(end 0.12065 -0.2794)
			(stroke
				(width 0.1)
				(type default)
			)
			(layer "B.Fab")
		)
		(fp_line
			(start 0.67945 -0.305054)
			(end 0.12065 -0.305054)
			(stroke
				(width 0.1)
				(type default)
			)
			(layer "B.Fab")
		)
		(pad "1" smd circle
			(at 0.40005 0 90)
			(size 0 0)
			(layers "B.Cu" "B.Mask" "B.Paste")
			(net "GND")
		)
		(pad "2" smd circle
			(at -0.40005 0 90)
			(size 0 0)
			(layers "B.Cu" "B.Mask" "B.Paste")
			(net "FAN_2_CLREF")
		)
	)
	(footprint ""
		(layer "B.Cu")
		(at 37.587428 -263.017 90)
		(property "Reference" "PC8"
			(at 0 0 90)
			(layer "B.SilkS")
			(hide yes)
			(effects
				(font
					(size 1.27 1.27)
				)
				(justify mirror)
			)
		)
		(property "Value" ""
			(at 0 0 90)
			(layer "B.Fab")
			(effects
				(font
					(size 1.27 1.27)
				)
				(justify mirror)
			)
		)
		(duplicate_pad_numbers_are_jumpers no)
		(fp_line
			(start 1.524 -0.762)
			(end -1.524 -0.762)
			(stroke
				(width 0.1524)
				(type default)
			)
			(layer "B.SilkS")
		)
		(fp_line
			(start -1.524 -0.762)
			(end -1.524 0.762)
			(stroke
				(width 0.1524)
				(type default)
			)
			(layer "B.SilkS")
		)
		(fp_line
			(start 1.524 0.762)
			(end 1.524 -0.762)
			(stroke
				(width 0.1524)
				(type default)
			)
			(layer "B.SilkS")
		)
		(fp_line
			(start -1.524 0.762)
			(end 1.524 0.762)
			(stroke
				(width 0.1524)
				(type default)
			)
			(layer "B.SilkS")
		)
		(fp_line
			(start 1.1049 -0.724916)
			(end 1.1049 0.724916)
			(stroke
				(width 0.1)
				(type default)
			)
			(layer "B.Fab")
		)
		(fp_line
			(start -1.1049 -0.724916)
			(end 1.1049 -0.724916)
			(stroke
				(width 0.1)
				(type default)
			)
			(layer "B.Fab")
		)
		(fp_line
			(start 1.1049 0.724916)
			(end -1.1049 0.724916)
			(stroke
				(width 0.1)
				(type default)
			)
			(layer "B.Fab")
		)
		(fp_line
			(start -1.1049 0.724916)
			(end -1.1049 -0.724916)
			(stroke
				(width 0.1)
				(type default)
			)
			(layer "B.Fab")
		)
		(pad "1" smd rect
			(at 0.889 0 90)
			(size 1.016 1.27)
			(layers "B.Cu" "B.Mask" "B.Paste")
			(net "P52V_HSC")
		)
		(pad "2" smd rect
			(at -0.889 0 90)
			(size 1.016 1.27)
			(layers "B.Cu" "B.Mask" "B.Paste")
			(net "GND")
		)
	)
	(footprint ""
		(layer "B.Cu")
		(at 15.079218 -248.1326 90)
		(property "Reference" "PD17"
			(at -5.588 3.740912 270)
			(unlocked yes)
			(layer "B.SilkS")
			(effects
				(font
					(size 0.7874 0.5842)
					(thickness 0.1524)
				)
				(justify left mirror)
			)
		)
		(property "Value" ""
			(at 0 0 90)
			(layer "B.Fab")
			(effects
				(font
					(size 1.27 1.27)
				)
				(justify mirror)
			)
		)
		(duplicate_pad_numbers_are_jumpers no)
		(fp_line
			(start 4.647184 -3.109976)
			(end 4.647184 3.109976)
			(stroke
				(width 0.1524)
				(type default)
			)
			(layer "B.SilkS")
		)
		(fp_line
			(start -5.536184 -3.109976)
			(end 4.647184 -3.109976)
			(stroke
				(width 0.1524)
				(type default)
			)
			(layer "B.SilkS")
		)
		(fp_line
			(start -0.762 -1.143)
			(end -0.762 0.889)
			(stroke
				(width 0.1524)
				(type default)
			)
			(layer "B.SilkS")
		)
		(fp_line
			(start 0.635 -0.889)
			(end 0.635 0.635)
			(stroke
				(width 0.1524)
				(type default)
			)
			(layer "B.SilkS")
		)
		(fp_line
			(start 1.397 -0.127)
			(end 0.635 -0.127)
			(stroke
				(width 0.1524)
				(type default)
			)
			(layer "B.SilkS")
		)
		(fp_line
			(start -0.635 -0.127)
			(end 0.635 -0.889)
			(stroke
				(width 0.1524)
				(type default)
			)
			(layer "B.SilkS")
		)
		(fp_line
			(start -0.635 -0.127)
			(end -1.397 -0.127)
			(stroke
				(width 0.1524)
				(type default)
			)
			(layer "B.SilkS")
		)
		(fp_line
			(start 0.635 0.635)
			(end -0.635 -0.127)
			(stroke
				(width 0.1524)
				(type default)
			)
			(layer "B.SilkS")
		)
		(fp_line
			(start 4.647184 3.109976)
			(end -5.536184 3.109976)
			(stroke
				(width 0.1524)
				(type default)
			)
			(layer "B.SilkS")
		)
		(fp_line
			(start -5.536184 3.109976)
			(end -5.536184 -3.109976)
			(stroke
				(width 0.1524)
				(type default)
			)
			(layer "B.SilkS")
		)
		(fp_poly
			(pts
				(xy -5.5118 -3.0988) (xy -5.5118 3.1496) (xy -4.572 3.1496) (xy -4.572 -3.0988)
			)
			(stroke
				(width 0)
				(type default)
			)
			(fill yes)
			(layer "B.SilkS")
		)
		(fp_line
			(start 3.554984 -3.109976)
			(end 3.554984 3.109976)
			(stroke
				(width 0.1)
				(type default)
			)
			(layer "B.Fab")
		)
		(fp_line
			(start -3.554984 -3.109976)
			(end 3.554984 -3.109976)
			(stroke
				(width 0.1)
				(type default)
			)
			(layer "B.Fab")
		)
		(fp_line
			(start 3.554984 3.109976)
			(end -3.554984 3.109976)
			(stroke
				(width 0.1)
				(type default)
			)
			(layer "B.Fab")
		)
		(fp_line
			(start -3.554984 3.109976)
			(end -3.554984 -3.109976)
			(stroke
				(width 0.1)
				(type default)
			)
			(layer "B.Fab")
		)
		(fp_text user "+"
			(at 6.2484 -0.569468 90)
			(unlocked yes)
			(layer "B.SilkS")
			(effects
				(font
					(size 1.905 1.4224)
					(thickness 0.1524)
				)
				(justify left mirror)
			)
		)
		(fp_text user "-"
			(at -5.334 -0.34925 90)
			(unlocked yes)
			(layer "B.SilkS")
			(effects
				(font
					(size 1.905 1.4224)
					(thickness 0.1524)
				)
				(justify left mirror)
			)
		)
		(fp_text user "-"
			(at -5.334 -0.34925 90)
			(unlocked yes)
			(layer "B.Fab")
			(effects
				(font
					(size 1.905 1.4224)
					(thickness 0.1524)
				)
				(justify left mirror)
			)
		)
		(fp_text user "+"
			(at 6.1214 -0.32385 90)
			(unlocked yes)
			(layer "B.Fab")
			(effects
				(font
					(size 1.905 1.4224)
					(thickness 0.1524)
				)
				(justify left mirror)
			)
		)
		(pad "A" smd rect
			(at 3.299968 0 270)
			(size 2.413 3.302)
			(layers "B.Cu" "B.Mask" "B.Paste")
			(net "GND")
		)
		(pad "C" smd rect
			(at -3.299968 0 270)
			(size 2.413 3.302)
			(layers "B.Cu" "B.Mask" "B.Paste")
			(net "P52V_HSC")
		)
	)
	(footprint ""
		(layer "B.Cu")
		(at 37.31768 -244.39499)
		(property "Reference" "PU4"
			(at 5.22732 2.35966 0)
			(unlocked yes)
			(layer "B.SilkS")
			(effects
				(font
					(size 0.7874 0.5842)
					(thickness 0.1524)
				)
				(justify left mirror)
			)
		)
		(property "Value" ""
			(at 0 0 0)
			(layer "B.Fab")
			(effects
				(font
					(size 1.27 1.27)
				)
				(justify mirror)
			)
		)
		(duplicate_pad_numbers_are_jumpers no)
		(fp_line
			(start -2.549906 -2.549906)
			(end -2.4384 -2.549906)
			(stroke
				(width 0.1524)
				(type default)
			)
			(layer "B.SilkS")
		)
		(fp_line
			(start -2.549906 -2.2352)
			(end -2.549906 -2.549906)
			(stroke
				(width 0.1524)
				(type default)
			)
			(layer "B.SilkS")
		)
		(fp_line
			(start -2.549906 -1.4986)
			(end -2.549906 -1.7526)
			(stroke
				(width 0.1524)
				(type default)
			)
			(layer "B.SilkS")
		)
		(fp_line
			(start -2.549906 -0.6858)
			(end -2.549906 -0.9144)
			(stroke
				(width 0.1524)
				(type default)
			)
			(layer "B.SilkS")
		)
		(fp_line
			(start -2.549906 0.9144)
			(end -2.549906 -0.1016)
			(stroke
				(width 0.1524)
				(type default)
			)
			(layer "B.SilkS")
		)
		(fp_line
			(start -2.549906 1.7526)
			(end -2.549906 1.4986)
			(stroke
				(width 0.1524)
				(type default)
			)
			(layer "B.SilkS")
		)
		(fp_line
			(start -2.549906 2.549906)
			(end -2.549906 2.2352)
			(stroke
				(width 0.1524)
				(type default)
			)
			(layer "B.SilkS")
		)
		(fp_line
			(start -2.4384 2.549906)
			(end -2.549906 2.549906)
			(stroke
				(width 0.1524)
				(type default)
			)
			(layer "B.SilkS")
		)
		(fp_line
			(start -2.199894 2.9464)
			(end -2.199894 3.4544)
			(stroke
				(width 0.1524)
				(type default)
			)
			(layer "B.SilkS")
		)
		(fp_line
			(start -1.800098 -3.9624)
			(end -1.800098 -2.9464)
			(stroke
				(width 0.1524)
				(type default)
			)
			(layer "B.SilkS")
		)
		(fp_line
			(start -0.199898 2.9464)
			(end -0.199898 3.9624)
			(stroke
				(width 0.1524)
				(type default)
			)
			(layer "B.SilkS")
		)
		(fp_line
			(start 0.199898 -3.4544)
			(end 0.199898 -2.9464)
			(stroke
				(width 0.1524)
				(type default)
			)
			(layer "B.SilkS")
		)
		(fp_line
			(start 1.800098 2.9464)
			(end 1.800098 3.4544)
			(stroke
				(width 0.1524)
				(type default)
			)
			(layer "B.SilkS")
		)
		(fp_line
			(start 2.199894 -3.9624)
			(end 2.199894 -2.9464)
			(stroke
				(width 0.1524)
				(type default)
			)
			(layer "B.SilkS")
		)
		(fp_line
			(start 2.4384 -2.549906)
			(end 2.549906 -2.549906)
			(stroke
				(width 0.1524)
				(type default)
			)
			(layer "B.SilkS")
		)
		(fp_line
			(start 2.549906 -2.549906)
			(end 2.549906 -2.2352)
			(stroke
				(width 0.1524)
				(type default)
			)
			(layer "B.SilkS")
		)
		(fp_line
			(start 2.549906 -1.7526)
			(end 2.549906 -1.4986)
			(stroke
				(width 0.1524)
				(type default)
			)
			(layer "B.SilkS")
		)
		(fp_line
			(start 2.549906 -0.9144)
			(end 2.549906 0.1016)
			(stroke
				(width 0.1524)
				(type default)
			)
			(layer "B.SilkS")
		)
		(fp_line
			(start 2.549906 0.6858)
			(end 2.549906 0.9144)
			(stroke
				(width 0.1524)
				(type default)
			)
			(layer "B.SilkS")
		)
		(fp_line
			(start 2.549906 1.4986)
			(end 2.549906 1.7526)
			(stroke
				(width 0.1524)
				(type default)
			)
			(layer "B.SilkS")
		)
		(fp_line
			(start 2.549906 2.2352)
			(end 2.549906 2.549906)
			(stroke
				(width 0.1524)
				(type default)
			)
			(layer "B.SilkS")
		)
		(fp_line
			(start 2.549906 2.549906)
			(end 2.4384 2.549906)
			(stroke
				(width 0.1524)
				(type default)
			)
			(layer "B.SilkS")
		)
		(fp_poly
			(pts
				(xy 3.7084 -1.584706) (xy 2.939034 -1.199896) (xy 3.7084 -0.81534)
			)
			(stroke
				(width 0)
				(type default)
			)
			(fill yes)
			(layer "B.SilkS")
		)
		(fp_line
			(start -2.549906 -2.549906)
			(end 2.549906 -2.549906)
			(stroke
				(width 0.1)
				(type default)
			)
			(layer "B.Fab")
		)
		(fp_line
			(start -2.549906 2.549906)
			(end -2.549906 -2.549906)
			(stroke
				(width 0.1)
				(type default)
			)
			(layer "B.Fab")
		)
		(fp_line
			(start -2.199894 2.9464)
			(end -2.199894 3.4544)
			(stroke
				(width 0.1)
				(type default)
			)
			(layer "B.Fab")
		)
		(fp_line
			(start -1.800098 -3.9624)
			(end -1.800098 -2.9464)
			(stroke
				(width 0.1)
				(type default)
			)
			(layer "B.Fab")
		)
		(fp_line
			(start -0.199898 2.9464)
			(end -0.199898 3.9624)
			(stroke
				(width 0.1)
				(type default)
			)
			(layer "B.Fab")
		)
		(fp_line
			(start 0.199898 -3.4544)
			(end 0.199898 -2.9464)
			(stroke
				(width 0.1)
				(type default)
			)
			(layer "B.Fab")
		)
		(fp_line
			(start 1.800098 2.9464)
			(end 1.800098 3.4544)
			(stroke
				(width 0.1)
				(type default)
			)
			(layer "B.Fab")
		)
		(fp_line
			(start 2.199894 -3.9624)
			(end 2.199894 -2.9464)
			(stroke
				(width 0.1)
				(type default)
			)
			(layer "B.Fab")
		)
		(fp_line
			(start 2.549906 -2.549906)
			(end 2.549906 2.549906)
			(stroke
				(width 0.1)
				(type default)
			)
			(layer "B.Fab")
		)
		(fp_line
			(start 2.549906 2.549906)
			(end -2.549906 2.549906)
			(stroke
				(width 0.1)
				(type default)
			)
			(layer "B.Fab")
		)
		(fp_poly
			(pts
				(xy 3.7084 -1.584706) (xy 2.939034 -1.199896) (xy 3.7084 -0.81534)
			)
			(stroke
				(width 0)
				(type default)
			)
			(fill yes)
			(layer "B.Fab")
		)
		(fp_text user "16"
			(at -3.329432 1.2192 270)
			(unlocked yes)
			(layer "B.SilkS")
			(effects
				(font
					(size 0.635 0.4064)
					(thickness 0.1524)
				)
				(justify mirror)
			)
		)
		(fp_text user "18"
			(at -3.304032 -1.2192 270)
			(unlocked yes)
			(layer "B.SilkS")
			(effects
				(font
					(size 0.635 0.4064)
					(thickness 0.1524)
				)
				(justify mirror)
			)
		)
		(fp_text user "15"
			(at -2.8956 3.126232 0)
			(unlocked yes)
			(layer "B.SilkS")
			(effects
				(font
					(size 0.635 0.4064)
					(thickness 0.1524)
				)
				(justify mirror)
			)
		)
		(fp_text user "19"
			(at -2.8448 -3.096768 0)
			(unlocked yes)
			(layer "B.SilkS")
			(effects
				(font
					(size 0.635 0.4064)
					(thickness 0.1524)
				)
				(justify mirror)
			)
		)
		(fp_text user "4"
			(at 2.6416 3.151632 0)
			(unlocked yes)
			(layer "B.SilkS")
			(effects
				(font
					(size 0.635 0.4064)
					(thickness 0.1524)
				)
				(justify mirror)
			)
		)
		(fp_text user "30"
			(at 2.9464 -3.045968 0)
			(unlocked yes)
			(layer "B.SilkS")
			(effects
				(font
					(size 0.635 0.4064)
					(thickness 0.1524)
				)
				(justify mirror)
			)
		)
		(fp_text user "3"
			(at 3.299968 1.1938 270)
			(unlocked yes)
			(layer "B.SilkS")
			(effects
				(font
					(size 0.635 0.4064)
					(thickness 0.1524)
				)
				(justify mirror)
			)
		)
		(fp_text user "16"
			(at -3.329432 1.2192 270)
			(unlocked yes)
			(layer "B.Fab")
			(effects
				(font
					(size 0.635 0.4064)
					(thickness 0.1524)
				)
				(justify mirror)
			)
		)
		(fp_text user "18"
			(at -3.304032 -1.2192 270)
			(unlocked yes)
			(layer "B.Fab")
			(effects
				(font
					(size 0.635 0.4064)
					(thickness 0.1524)
				)
				(justify mirror)
			)
		)
		(fp_text user "15"
			(at -2.8956 3.126232 0)
			(unlocked yes)
			(layer "B.Fab")
			(effects
				(font
					(size 0.635 0.4064)
					(thickness 0.1524)
				)
				(justify mirror)
			)
		)
		(fp_text user "19"
			(at -2.8448 -3.096768 0)
			(unlocked yes)
			(layer "B.Fab")
			(effects
				(font
					(size 0.635 0.4064)
					(thickness 0.1524)
				)
				(justify mirror)
			)
		)
		(fp_text user "4"
			(at 2.6416 3.151632 0)
			(unlocked yes)
			(layer "B.Fab")
			(effects
				(font
					(size 0.635 0.4064)
					(thickness 0.1524)
				)
				(justify mirror)
			)
		)
		(fp_text user "30"
			(at 2.9464 -3.045968 0)
			(unlocked yes)
			(layer "B.Fab")
			(effects
				(font
					(size 0.635 0.4064)
					(thickness 0.1524)
				)
				(justify mirror)
			)
		)
		(fp_text user "3"
			(at 3.299968 1.1938 270)
			(unlocked yes)
			(layer "B.Fab")
			(effects
				(font
					(size 0.635 0.4064)
					(thickness 0.1524)
				)
				(justify mirror)
			)
		)
		(pad "1" smd circle
			(at 1.599946 -1.199896 270)
			(size 0 0)
			(layers "B.Cu" "B.Mask" "B.Paste")
			(net "P52V_HSC")
		)
		(pad "2" smd rect
			(at 1.549908 0.40005 90)
			(size 0.3048 2.5146)
			(layers "B.Cu" "B.Mask" "B.Paste")
			(net "P52V_HSC")
		)
		(pad "3" smd rect
			(at 1.549908 1.199896 90)
			(size 0.3048 2.5146)
			(layers "B.Cu" "B.Mask" "B.Paste")
			(net "P52V_FAN_1")
		)
		(pad "4" smd circle
			(at 2.199894 2.350008)
			(size 0 0)
			(layers "B.Cu" "B.Mask" "B.Paste")
			(net "P52V_FAN_1")
		)
		(pad "5" smd rect
			(at 1.800098 2.350008 180)
			(size 0.1778 0.9144)
			(layers "B.Cu" "B.Mask" "B.Paste")
			(net "P52V_FAN_1")
		)
		(pad "6" smd rect
			(at 1.400048 2.350008 180)
			(size 0.1778 0.9144)
			(layers "B.Cu" "B.Mask" "B.Paste")
			(net "P52V_FAN_1")
		)
		(pad "7" smd rect
			(at 0.999998 2.350008 180)
			(size 0.1778 0.9144)
			(layers "B.Cu" "B.Mask" "B.Paste")
			(net "P52V_FAN_1")
		)
		(pad "8" smd rect
			(at 0.599948 2.350008 180)
			(size 0.1778 0.9144)
			(layers "B.Cu" "B.Mask" "B.Paste")
			(net "P52V_FAN_1")
		)
		(pad "9" smd rect
			(at 0.199898 2.350008 180)
			(size 0.1778 0.9144)
			(layers "B.Cu" "B.Mask" "B.Paste")
			(net "P52V_FAN_1")
		)
		(pad "10" smd rect
			(at -0.199898 2.350008 180)
			(size 0.1778 0.9144)
			(layers "B.Cu" "B.Mask" "B.Paste")
			(net "P52V_FAN_1")
		)
		(pad "11" smd rect
			(at -0.599948 2.350008 180)
			(size 0.1778 0.9144)
			(layers "B.Cu" "B.Mask" "B.Paste")
			(net "P52V_FAN_1")
		)
		(pad "12" smd rect
			(at -0.999998 2.350008 180)
			(size 0.1778 0.9144)
			(layers "B.Cu" "B.Mask" "B.Paste")
			(net "P52V_FAN_1")
		)
		(pad "13" smd rect
			(at -1.400048 2.350008 180)
			(size 0.1778 0.9144)
			(layers "B.Cu" "B.Mask" "B.Paste")
			(net "P52V_FAN_1")
		)
		(pad "14" smd rect
			(at -1.800098 2.350008 180)
			(size 0.1778 0.9144)
			(layers "B.Cu" "B.Mask" "B.Paste")
			(net "P52V_FAN_1")
		)
		(pad "15" smd circle
			(at -2.199894 2.350008)
			(size 0 0)
			(layers "B.Cu" "B.Mask" "B.Paste")
			(net "P52V_FAN_1")
		)
		(pad "16" smd rect
			(at -1.549908 1.199896 90)
			(size 0.3048 2.5146)
			(layers "B.Cu" "B.Mask" "B.Paste")
			(net "P52V_FAN_1")
		)
		(pad "17" smd rect
			(at -1.549908 -0.40005 90)
			(size 0.3048 2.5146)
			(layers "B.Cu" "B.Mask" "B.Paste")
			(net "P52V_FAN_1")
		)
		(pad "18" smd rect
			(at -1.549908 -1.199896 90)
			(size 0.3048 2.5146)
			(layers "B.Cu" "B.Mask" "B.Paste")
			(net "P52V_HSC")
		)
		(pad "19" smd circle
			(at -2.199894 -2.350008 180)
			(size 0 0)
			(layers "B.Cu" "B.Mask" "B.Paste")
			(net "FAN_1_CS")
		)
		(pad "20" smd rect
			(at -1.800098 -2.350008 180)
			(size 0.1778 0.9144)
			(layers "B.Cu" "B.Mask" "B.Paste")
			(net "FAN_1_IMON")
		)
		(pad "21" smd rect
			(at -1.400048 -2.350008 180)
			(size 0.1778 0.9144)
			(layers "B.Cu" "B.Mask" "B.Paste")
			(net "FAN_1_SS")
		)
		(pad "22" smd rect
			(at -0.999998 -2.350008 180)
			(size 0.1778 0.9144)
			(layers "B.Cu" "B.Mask" "B.Paste")
			(net "FAN_1_FAULT")
		)
		(pad "23" smd rect
			(at -0.599948 -2.350008 180)
			(size 0.1778 0.9144)
			(layers "B.Cu" "B.Mask" "B.Paste")
			(net "FAN_1_TIMER")
		)
		(pad "24" smd rect
			(at -0.199898 -2.350008 180)
			(size 0.1778 0.9144)
			(layers "B.Cu" "B.Mask" "B.Paste")
			(net "FAN_1_CLREF")
		)
		(pad "25" smd rect
			(at 0.199898 -2.350008 180)
			(size 0.1778 0.9144)
			(layers "B.Cu" "B.Mask" "B.Paste")
			(net "GND")
		)
		(pad "26" smd rect
			(at 0.599948 -2.350008 180)
			(size 0.1778 0.9144)
			(layers "B.Cu" "B.Mask" "B.Paste")
			(net "FAN_1_ON")
		)
		(pad "27" smd rect
			(at 0.999998 -2.350008 180)
			(size 0.1778 0.9144)
			(layers "B.Cu" "B.Mask" "B.Paste")
			(net "FAN_1_P3V_R")
		)
		(pad "28" smd rect
			(at 1.400048 -2.350008 180)
			(size 0.1778 0.9144)
			(layers "B.Cu" "B.Mask" "B.Paste")
			(net "FAN_1_P5V")
		)
		(pad "29" smd rect
			(at 1.800098 -2.350008 180)
			(size 0.1778 0.9144)
			(layers "B.Cu" "B.Mask" "B.Paste")
			(net "FAN_1_TEMP")
		)
		(pad "30" smd circle
			(at 2.199894 -2.350008 180)
			(size 0 0)
			(layers "B.Cu" "B.Mask" "B.Paste")
			(net "FAN_1_MODE")
		)
	)
	(footprint ""
		(layer "B.Cu")
		(at 32.380428 -64.827912 -90)
		(property "Reference" "PR26"
			(at 0 0 90)
			(layer "B.SilkS")
			(hide yes)
			(effects
				(font
					(size 1.27 1.27)
				)
				(justify mirror)
			)
		)
		(property "Value" ""
			(at 0 0 90)
			(layer "B.Fab")
			(effects
				(font
					(size 1.27 1.27)
				)
				(justify mirror)
			)
		)
		(duplicate_pad_numbers_are_jumpers no)
		(fp_line
			(start -0.7874 0.4064)
			(end 0.7874 0.4064)
			(stroke
				(width 0.1524)
				(type default)
			)
			(layer "B.SilkS")
		)
		(fp_line
			(start 0.7874 0.4064)
			(end 0.7874 -0.4064)
			(stroke
				(width 0.1524)
				(type default)
			)
			(layer "B.SilkS")
		)
		(fp_line
			(start -0.7874 -0.4064)
			(end -0.7874 0.4064)
			(stroke
				(width 0.1524)
				(type default)
			)
			(layer "B.SilkS")
		)
		(fp_line
			(start 0.7874 -0.4064)
			(end -0.7874 -0.4064)
			(stroke
				(width 0.1524)
				(type default)
			)
			(layer "B.SilkS")
		)
		(fp_line
			(start -0.67945 0.3048)
			(end -0.120396 0.3048)
			(stroke
				(width 0.1)
				(type default)
			)
			(layer "B.Fab")
		)
		(fp_line
			(start -0.120396 0.3048)
			(end -0.120396 0.2794)
			(stroke
				(width 0.1)
				(type default)
			)
			(layer "B.Fab")
		)
		(fp_line
			(start 0.12065 0.3048)
			(end 0.67945 0.3048)
			(stroke
				(width 0.1)
				(type default)
			)
			(layer "B.Fab")
		)
		(fp_line
			(start 0.67945 0.3048)
			(end 0.67945 -0.305054)
			(stroke
				(width 0.1)
				(type default)
			)
			(layer "B.Fab")
		)
		(fp_line
			(start -0.120396 0.2794)
			(end 0.12065 0.2794)
			(stroke
				(width 0.1)
				(type default)
			)
			(layer "B.Fab")
		)
		(fp_line
			(start 0.12065 0.2794)
			(end 0.12065 0.3048)
			(stroke
				(width 0.1)
				(type default)
			)
			(layer "B.Fab")
		)
		(fp_line
			(start -0.12065 -0.2794)
			(end -0.12065 -0.3048)
			(stroke
				(width 0.1)
				(type default)
			)
			(layer "B.Fab")
		)
		(fp_line
			(start 0.12065 -0.2794)
			(end -0.12065 -0.2794)
			(stroke
				(width 0.1)
				(type default)
			)
			(layer "B.Fab")
		)
		(fp_line
			(start -0.67945 -0.3048)
			(end -0.67945 0.3048)
			(stroke
				(width 0.1)
				(type default)
			)
			(layer "B.Fab")
		)
		(fp_line
			(start -0.12065 -0.3048)
			(end -0.67945 -0.3048)
			(stroke
				(width 0.1)
				(type default)
			)
			(layer "B.Fab")
		)
		(fp_line
			(start 0.12065 -0.305054)
			(end 0.12065 -0.2794)
			(stroke
				(width 0.1)
				(type default)
			)
			(layer "B.Fab")
		)
		(fp_line
			(start 0.67945 -0.305054)
			(end 0.12065 -0.305054)
			(stroke
				(width 0.1)
				(type default)
			)
			(layer "B.Fab")
		)
		(pad "1" smd circle
			(at 0.40005 0 90)
			(size 0 0)
			(layers "B.Cu" "B.Mask" "B.Paste")
			(net "FAN_3_CS")
		)
		(pad "2" smd circle
			(at -0.40005 0 90)
			(size 0 0)
			(layers "B.Cu" "B.Mask" "B.Paste")
			(net "GND")
		)
	)
	(footprint ""
		(layer "B.Cu")
		(at 6.914642 -225.445828 180)
		(property "Reference" "PD12"
			(at 1.961642 -3.857498 0)
			(unlocked yes)
			(layer "B.SilkS")
			(effects
				(font
					(size 0.7874 0.5842)
					(thickness 0.1524)
				)
				(justify left mirror)
			)
		)
		(property "Value" ""
			(at 0 0 0)
			(layer "B.Fab")
			(effects
				(font
					(size 1.27 1.27)
				)
				(justify mirror)
			)
		)
		(duplicate_pad_numbers_are_jumpers no)
		(fp_line
			(start 4.826 3.109976)
			(end 4.826 0)
			(stroke
				(width 0.1524)
				(type default)
			)
			(layer "B.SilkS")
		)
		(fp_line
			(start 4.826 0)
			(end 4.826 -3.109976)
			(stroke
				(width 0.1524)
				(type default)
			)
			(layer "B.SilkS")
		)
		(fp_line
			(start 4.826 -3.109976)
			(end -4.826 -3.109976)
			(stroke
				(width 0.1524)
				(type default)
			)
			(layer "B.SilkS")
		)
		(fp_line
			(start 1.0922 0)
			(end 1.7018 0)
			(stroke
				(width 0.1524)
				(type default)
			)
			(layer "B.SilkS")
		)
		(fp_line
			(start 1.016 1.016)
			(end -1.016 0)
			(stroke
				(width 0.1524)
				(type default)
			)
			(layer "B.SilkS")
		)
		(fp_line
			(start 1.016 -1.016)
			(end 1.016 1.016)
			(stroke
				(width 0.1524)
				(type default)
			)
			(layer "B.SilkS")
		)
		(fp_line
			(start -1.143 1.397)
			(end -1.143 -1.397)
			(stroke
				(width 0.1524)
				(type default)
			)
			(layer "B.SilkS")
		)
		(fp_line
			(start -1.143 0)
			(end 1.016 -1.016)
			(stroke
				(width 0.1524)
				(type default)
			)
			(layer "B.SilkS")
		)
		(fp_line
			(start -1.143 0)
			(end -1.8034 0)
			(stroke
				(width 0.1524)
				(type default)
			)
			(layer "B.SilkS")
		)
		(fp_line
			(start -4.8133 -3.109976)
			(end -5.3467 -3.109976)
			(stroke
				(width 0.1524)
				(type default)
			)
			(layer "B.SilkS")
		)
		(fp_line
			(start -4.826 3.109976)
			(end 4.826 3.109976)
			(stroke
				(width 0.1524)
				(type default)
			)
			(layer "B.SilkS")
		)
		(fp_line
			(start -4.826 0)
			(end -4.826 3.109976)
			(stroke
				(width 0.1524)
				(type default)
			)
			(layer "B.SilkS")
		)
		(fp_line
			(start -4.826 -3.109976)
			(end -4.826 0)
			(stroke
				(width 0.1524)
				(type default)
			)
			(layer "B.SilkS")
		)
		(fp_line
			(start -4.9276 3.109976)
			(end -4.9276 -3.109976)
			(stroke
				(width 0.1524)
				(type default)
			)
			(layer "B.SilkS")
		)
		(fp_line
			(start -5.0292 3.109976)
			(end -5.0292 -3.109976)
			(stroke
				(width 0.1524)
				(type default)
			)
			(layer "B.SilkS")
		)
		(fp_line
			(start -5.1308 3.109976)
			(end -5.1308 -3.109976)
			(stroke
				(width 0.1524)
				(type default)
			)
			(layer "B.SilkS")
		)
		(fp_line
			(start -5.207 3.109976)
			(end -5.207 -3.109976)
			(stroke
				(width 0.1524)
				(type default)
			)
			(layer "B.SilkS")
		)
		(fp_line
			(start -5.334 3.109976)
			(end -4.8133 3.109976)
			(stroke
				(width 0.1524)
				(type default)
			)
			(layer "B.SilkS")
		)
		(fp_line
			(start -5.334 3.109976)
			(end -5.334 0)
			(stroke
				(width 0.1524)
				(type default)
			)
			(layer "B.SilkS")
		)
		(fp_line
			(start -5.334 0)
			(end -5.334 -3.109976)
			(stroke
				(width 0.1524)
				(type default)
			)
			(layer "B.SilkS")
		)
		(fp_line
			(start 3.554984 3.109976)
			(end 3.554984 -3.109976)
			(stroke
				(width 0.1)
				(type default)
			)
			(layer "B.Fab")
		)
		(fp_line
			(start 3.554984 -3.109976)
			(end -3.554984 -3.109976)
			(stroke
				(width 0.1)
				(type default)
			)
			(layer "B.Fab")
		)
		(fp_line
			(start 1.0922 0)
			(end 1.7018 0)
			(stroke
				(width 0.1)
				(type default)
			)
			(layer "B.Fab")
		)
		(fp_line
			(start 1.016 1.016)
			(end -1.016 0)
			(stroke
				(width 0.1)
				(type default)
			)
			(layer "B.Fab")
		)
		(fp_line
			(start 1.016 -1.016)
			(end 1.016 1.016)
			(stroke
				(width 0.1)
				(type default)
			)
			(layer "B.Fab")
		)
		(fp_line
			(start -1.143 1.397)
			(end -1.143 -1.397)
			(stroke
				(width 0.1)
				(type default)
			)
			(layer "B.Fab")
		)
		(fp_line
			(start -1.143 0)
			(end 1.016 -1.016)
			(stroke
				(width 0.1)
				(type default)
			)
			(layer "B.Fab")
		)
		(fp_line
			(start -1.143 0)
			(end -1.8034 0)
			(stroke
				(width 0.1)
				(type default)
			)
			(layer "B.Fab")
		)
		(fp_line
			(start -3.554984 3.109976)
			(end 3.554984 3.109976)
			(stroke
				(width 0.1)
				(type default)
			)
			(layer "B.Fab")
		)
		(fp_line
			(start -3.554984 -3.109976)
			(end -3.554984 3.109976)
			(stroke
				(width 0.1)
				(type default)
			)
			(layer "B.Fab")
		)
		(fp_text user "+"
			(at 4.5466 0.19685 0)
			(unlocked yes)
			(layer "B.SilkS")
			(effects
				(font
					(size 1.905 1.4224)
					(thickness 0.1524)
				)
				(justify left mirror)
			)
		)
		(fp_text user "-"
			(at -6.6802 0.22225 0)
			(unlocked yes)
			(layer "B.SilkS")
			(effects
				(font
					(size 1.905 1.4224)
					(thickness 0.1524)
				)
				(justify left mirror)
			)
		)
		(fp_text user "+"
			(at 4.5466 0.19685 0)
			(unlocked yes)
			(layer "B.Fab")
			(effects
				(font
					(size 1.905 1.4224)
					(thickness 0.1524)
				)
				(justify left mirror)
			)
		)
		(fp_text user "-"
			(at -6.6802 0.22225 0)
			(unlocked yes)
			(layer "B.Fab")
			(effects
				(font
					(size 1.905 1.4224)
					(thickness 0.1524)
				)
				(justify left mirror)
			)
		)
		(pad "A" smd rect
			(at 3.400044 0 180)
			(size 2.5146 3.302)
			(layers "B.Cu" "B.Mask" "B.Paste")
			(net "GND")
		)
		(pad "C" smd rect
			(at -3.400044 0 180)
			(size 2.5146 3.302)
			(layers "B.Cu" "B.Mask" "B.Paste")
			(net "P52V_FAN_6")
		)
	)
	(footprint ""
		(layer "B.Cu")
		(at 10.445242 -73.962768 90)
		(property "Reference" "PR60"
			(at 0 0 90)
			(layer "B.SilkS")
			(hide yes)
			(effects
				(font
					(size 1.27 1.27)
				)
				(justify mirror)
			)
		)
		(property "Value" ""
			(at 0 0 90)
			(layer "B.Fab")
			(effects
				(font
					(size 1.27 1.27)
				)
				(justify mirror)
			)
		)
		(duplicate_pad_numbers_are_jumpers no)
		(fp_line
			(start 0.7874 -0.4064)
			(end -0.7874 -0.4064)
			(stroke
				(width 0.1524)
				(type default)
			)
			(layer "B.SilkS")
		)
		(fp_line
			(start -0.7874 -0.4064)
			(end -0.7874 0.4064)
			(stroke
				(width 0.1524)
				(type default)
			)
			(layer "B.SilkS")
		)
		(fp_line
			(start 0.7874 0.4064)
			(end 0.7874 -0.4064)
			(stroke
				(width 0.1524)
				(type default)
			)
			(layer "B.SilkS")
		)
		(fp_line
			(start -0.7874 0.4064)
			(end 0.7874 0.4064)
			(stroke
				(width 0.1524)
				(type default)
			)
			(layer "B.SilkS")
		)
		(fp_line
			(start 0.67945 -0.305054)
			(end 0.12065 -0.305054)
			(stroke
				(width 0.1)
				(type default)
			)
			(layer "B.Fab")
		)
		(fp_line
			(start 0.12065 -0.305054)
			(end 0.12065 -0.2794)
			(stroke
				(width 0.1)
				(type default)
			)
			(layer "B.Fab")
		)
		(fp_line
			(start -0.12065 -0.3048)
			(end -0.67945 -0.3048)
			(stroke
				(width 0.1)
				(type default)
			)
			(layer "B.Fab")
		)
		(fp_line
			(start -0.67945 -0.3048)
			(end -0.67945 0.3048)
			(stroke
				(width 0.1)
				(type default)
			)
			(layer "B.Fab")
		)
		(fp_line
			(start 0.12065 -0.2794)
			(end -0.12065 -0.2794)
			(stroke
				(width 0.1)
				(type default)
			)
			(layer "B.Fab")
		)
		(fp_line
			(start -0.12065 -0.2794)
			(end -0.12065 -0.3048)
			(stroke
				(width 0.1)
				(type default)
			)
			(layer "B.Fab")
		)
		(fp_line
			(start 0.12065 0.2794)
			(end 0.12065 0.3048)
			(stroke
				(width 0.1)
				(type default)
			)
			(layer "B.Fab")
		)
		(fp_line
			(start -0.120396 0.2794)
			(end 0.12065 0.2794)
			(stroke
				(width 0.1)
				(type default)
			)
			(layer "B.Fab")
		)
		(fp_line
			(start 0.67945 0.3048)
			(end 0.67945 -0.305054)
			(stroke
				(width 0.1)
				(type default)
			)
			(layer "B.Fab")
		)
		(fp_line
			(start 0.12065 0.3048)
			(end 0.67945 0.3048)
			(stroke
				(width 0.1)
				(type default)
			)
			(layer "B.Fab")
		)
		(fp_line
			(start -0.120396 0.3048)
			(end -0.120396 0.2794)
			(stroke
				(width 0.1)
				(type default)
			)
			(layer "B.Fab")
		)
		(fp_line
			(start -0.67945 0.3048)
			(end -0.120396 0.3048)
			(stroke
				(width 0.1)
				(type default)
			)
			(layer "B.Fab")
		)
		(pad "1" smd circle
			(at 0.40005 0 270)
			(size 0 0)
			(layers "B.Cu" "B.Mask" "B.Paste")
			(net "FAN_5_TEMP")
		)
		(pad "2" smd circle
			(at -0.40005 0 270)
			(size 0 0)
			(layers "B.Cu" "B.Mask" "B.Paste")
			(net "GND")
		)
	)
	(footprint ""
		(layer "B.Cu")
		(at 44.667932 -71.177912 -90)
		(property "Reference" "U396"
			(at 1.378712 -2.981198 270)
			(unlocked yes)
			(layer "B.SilkS")
			(effects
				(font
					(size 0.7874 0.5842)
					(thickness 0.1524)
				)
				(justify left mirror)
			)
		)
		(property "Value" ""
			(at 0 0 90)
			(layer "B.Fab")
			(effects
				(font
					(size 1.27 1.27)
				)
				(justify mirror)
			)
		)
		(duplicate_pad_numbers_are_jumpers no)
		(fp_line
			(start -1.3462 1.1938)
			(end -1.3462 -1.1938)
			(stroke
				(width 0.1524)
				(type default)
			)
			(layer "B.SilkS")
		)
		(fp_line
			(start 1.3462 1.1938)
			(end -1.3462 1.1938)
			(stroke
				(width 0.1524)
				(type default)
			)
			(layer "B.SilkS")
		)
		(fp_line
			(start -1.3462 -1.1938)
			(end 1.3462 -1.1938)
			(stroke
				(width 0.1524)
				(type default)
			)
			(layer "B.SilkS")
		)
		(fp_line
			(start 1.3462 -1.1938)
			(end 1.3462 1.1684)
			(stroke
				(width 0.1524)
				(type default)
			)
			(layer "B.SilkS")
		)
		(fp_poly
			(pts
				(xy 1.447038 -0.760476) (xy 2.052066 -0.457962) (xy 2.052066 -1.06299)
			)
			(stroke
				(width 0)
				(type default)
			)
			(fill yes)
			(layer "B.SilkS")
		)
		(fp_line
			(start -0.674878 1.124966)
			(end -0.674878 -1.124966)
			(stroke
				(width 0.1)
				(type default)
			)
			(layer "B.Fab")
		)
		(fp_line
			(start 0.674878 1.124966)
			(end -0.674878 1.124966)
			(stroke
				(width 0.1)
				(type default)
			)
			(layer "B.Fab")
		)
		(fp_line
			(start -0.674878 -1.124966)
			(end 0.674878 -1.124966)
			(stroke
				(width 0.1)
				(type default)
			)
			(layer "B.Fab")
		)
		(fp_line
			(start 0.674878 -1.124966)
			(end 0.674878 1.124966)
			(stroke
				(width 0.1)
				(type default)
			)
			(layer "B.Fab")
		)
		(fp_poly
			(pts
				(xy 1.447038 -0.760476) (xy 2.052066 -0.457962) (xy 2.052066 -1.06299)
			)
			(stroke
				(width 0)
				(type default)
			)
			(fill yes)
			(layer "B.Fab")
		)
		(pad "1" smd rect
			(at 0.899922 -0.750062 90)
			(size 0.6096 0.6096)
			(layers "B.Cu" "B.Mask" "B.Paste")
			(net "NC_U396_P1")
		)
		(pad "2" smd rect
			(at 0.899922 0)
			(size 0.4064 0.6096)
			(layers "B.Cu" "B.Mask" "B.Paste")
			(net "FAN_2_PRSNT_BUF_N")
		)
		(pad "3" smd rect
			(at 0.899922 0.750062 90)
			(size 0.6096 0.6096)
			(layers "B.Cu" "B.Mask" "B.Paste")
			(net "GND")
		)
		(pad "4" smd rect
			(at -0.899922 0.750062 90)
			(size 0.6096 0.6096)
			(layers "B.Cu" "B.Mask" "B.Paste")
			(net "FAN_2_PRESENT")
		)
		(pad "5" smd rect
			(at -0.899922 -0.750062 90)
			(size 0.6096 0.6096)
			(layers "B.Cu" "B.Mask" "B.Paste")
			(net "P3V3_AUX")
		)
	)
	(footprint ""
		(layer "B.Cu")
		(at 40.894 -131.191 180)
		(property "Reference" "R5429"
			(at 0 0 0)
			(layer "B.SilkS")
			(hide yes)
			(effects
				(font
					(size 1.27 1.27)
				)
				(justify mirror)
			)
		)
		(property "Value" ""
			(at 0 0 0)
			(layer "B.Fab")
			(effects
				(font
					(size 1.27 1.27)
				)
				(justify mirror)
			)
		)
		(duplicate_pad_numbers_are_jumpers no)
		(fp_line
			(start 0.7874 0.4064)
			(end 0.7874 -0.4064)
			(stroke
				(width 0.1524)
				(type default)
			)
			(layer "B.SilkS")
		)
		(fp_line
			(start 0.7874 -0.4064)
			(end -0.7874 -0.4064)
			(stroke
				(width 0.1524)
				(type default)
			)
			(layer "B.SilkS")
		)
		(fp_line
			(start -0.7874 0.4064)
			(end 0.7874 0.4064)
			(stroke
				(width 0.1524)
				(type default)
			)
			(layer "B.SilkS")
		)
		(fp_line
			(start -0.7874 -0.4064)
			(end -0.7874 0.4064)
			(stroke
				(width 0.1524)
				(type default)
			)
			(layer "B.SilkS")
		)
		(fp_line
			(start 0.67945 0.3048)
			(end 0.67945 -0.305054)
			(stroke
				(width 0.1)
				(type default)
			)
			(layer "B.Fab")
		)
		(fp_line
			(start 0.67945 -0.305054)
			(end 0.12065 -0.305054)
			(stroke
				(width 0.1)
				(type default)
			)
			(layer "B.Fab")
		)
		(fp_line
			(start 0.12065 0.3048)
			(end 0.67945 0.3048)
			(stroke
				(width 0.1)
				(type default)
			)
			(layer "B.Fab")
		)
		(fp_line
			(start 0.12065 0.2794)
			(end 0.12065 0.3048)
			(stroke
				(width 0.1)
				(type default)
			)
			(layer "B.Fab")
		)
		(fp_line
			(start 0.12065 -0.2794)
			(end -0.12065 -0.2794)
			(stroke
				(width 0.1)
				(type default)
			)
			(layer "B.Fab")
		)
		(fp_line
			(start 0.12065 -0.305054)
			(end 0.12065 -0.2794)
			(stroke
				(width 0.1)
				(type default)
			)
			(layer "B.Fab")
		)
		(fp_line
			(start -0.120396 0.3048)
			(end -0.120396 0.2794)
			(stroke
				(width 0.1)
				(type default)
			)
			(layer "B.Fab")
		)
		(fp_line
			(start -0.120396 0.2794)
			(end 0.12065 0.2794)
			(stroke
				(width 0.1)
				(type default)
			)
			(layer "B.Fab")
		)
		(fp_line
			(start -0.12065 -0.2794)
			(end -0.12065 -0.3048)
			(stroke
				(width 0.1)
				(type default)
			)
			(layer "B.Fab")
		)
		(fp_line
			(start -0.12065 -0.3048)
			(end -0.67945 -0.3048)
			(stroke
				(width 0.1)
				(type default)
			)
			(layer "B.Fab")
		)
		(fp_line
			(start -0.67945 0.3048)
			(end -0.120396 0.3048)
			(stroke
				(width 0.1)
				(type default)
			)
			(layer "B.Fab")
		)
		(fp_line
			(start -0.67945 -0.3048)
			(end -0.67945 0.3048)
			(stroke
				(width 0.1)
				(type default)
			)
			(layer "B.Fab")
		)
		(pad "1" smd rect
			(at 0.40005 0 180)
			(size 0.4572 0.508)
			(layers "B.Cu" "B.Mask" "B.Paste")
			(net "FAN_1_TACH_OL")
		)
		(pad "2" smd rect
			(at -0.40005 0 180)
			(size 0.4572 0.508)
			(layers "B.Cu" "B.Mask" "B.Paste")
			(net "GND")
		)
	)
	(footprint ""
		(layer "B.Cu")
		(at 11.461242 -73.962768 90)
		(property "Reference" "PC45"
			(at 0 0 90)
			(layer "B.SilkS")
			(hide yes)
			(effects
				(font
					(size 1.27 1.27)
				)
				(justify mirror)
			)
		)
		(property "Value" ""
			(at 0 0 90)
			(layer "B.Fab")
			(effects
				(font
					(size 1.27 1.27)
				)
				(justify mirror)
			)
		)
		(duplicate_pad_numbers_are_jumpers no)
		(fp_line
			(start 0.7874 -0.4064)
			(end -0.7874 -0.4064)
			(stroke
				(width 0.1524)
				(type default)
			)
			(layer "B.SilkS")
		)
		(fp_line
			(start -0.7874 -0.4064)
			(end -0.7874 0.4064)
			(stroke
				(width 0.1524)
				(type default)
			)
			(layer "B.SilkS")
		)
		(fp_line
			(start 0.7874 0.4064)
			(end 0.7874 -0.4064)
			(stroke
				(width 0.1524)
				(type default)
			)
			(layer "B.SilkS")
		)
		(fp_line
			(start -0.7874 0.4064)
			(end 0.7874 0.4064)
			(stroke
				(width 0.1524)
				(type default)
			)
			(layer "B.SilkS")
		)
		(fp_line
			(start 0.67945 -0.305054)
			(end 0.12065 -0.305054)
			(stroke
				(width 0.1)
				(type default)
			)
			(layer "B.Fab")
		)
		(fp_line
			(start 0.12065 -0.305054)
			(end 0.12065 -0.2794)
			(stroke
				(width 0.1)
				(type default)
			)
			(layer "B.Fab")
		)
		(fp_line
			(start -0.12065 -0.3048)
			(end -0.67945 -0.3048)
			(stroke
				(width 0.1)
				(type default)
			)
			(layer "B.Fab")
		)
		(fp_line
			(start -0.67945 -0.3048)
			(end -0.67945 0.3048)
			(stroke
				(width 0.1)
				(type default)
			)
			(layer "B.Fab")
		)
		(fp_line
			(start 0.12065 -0.2794)
			(end -0.12065 -0.2794)
			(stroke
				(width 0.1)
				(type default)
			)
			(layer "B.Fab")
		)
		(fp_line
			(start -0.12065 -0.2794)
			(end -0.12065 -0.3048)
			(stroke
				(width 0.1)
				(type default)
			)
			(layer "B.Fab")
		)
		(fp_line
			(start 0.12065 0.2794)
			(end 0.12065 0.3048)
			(stroke
				(width 0.1)
				(type default)
			)
			(layer "B.Fab")
		)
		(fp_line
			(start -0.120396 0.2794)
			(end 0.12065 0.2794)
			(stroke
				(width 0.1)
				(type default)
			)
			(layer "B.Fab")
		)
		(fp_line
			(start 0.67945 0.3048)
			(end 0.67945 -0.305054)
			(stroke
				(width 0.1)
				(type default)
			)
			(layer "B.Fab")
		)
		(fp_line
			(start 0.12065 0.3048)
			(end 0.67945 0.3048)
			(stroke
				(width 0.1)
				(type default)
			)
			(layer "B.Fab")
		)
		(fp_line
			(start -0.120396 0.3048)
			(end -0.120396 0.2794)
			(stroke
				(width 0.1)
				(type default)
			)
			(layer "B.Fab")
		)
		(fp_line
			(start -0.67945 0.3048)
			(end -0.120396 0.3048)
			(stroke
				(width 0.1)
				(type default)
			)
			(layer "B.Fab")
		)
		(pad "1" smd circle
			(at 0.40005 0 270)
			(size 0 0)
			(layers "B.Cu" "B.Mask" "B.Paste")
			(net "FAN_5_P5V")
		)
		(pad "2" smd circle
			(at -0.40005 0 270)
			(size 0 0)
			(layers "B.Cu" "B.Mask" "B.Paste")
			(net "GND")
		)
	)
	(footprint ""
		(layer "B.Cu")
		(at 2.667 -249.428 90)
		(property "Reference" "PR70"
			(at 0 0 90)
			(layer "B.SilkS")
			(hide yes)
			(effects
				(font
					(size 1.27 1.27)
				)
				(justify mirror)
			)
		)
		(property "Value" ""
			(at 0 0 90)
			(layer "B.Fab")
			(effects
				(font
					(size 1.27 1.27)
				)
				(justify mirror)
			)
		)
		(duplicate_pad_numbers_are_jumpers no)
		(fp_line
			(start 0.7874 -0.4064)
			(end -0.7874 -0.4064)
			(stroke
				(width 0.1524)
				(type default)
			)
			(layer "B.SilkS")
		)
		(fp_line
			(start -0.7874 -0.4064)
			(end -0.7874 0.4064)
			(stroke
				(width 0.1524)
				(type default)
			)
			(layer "B.SilkS")
		)
		(fp_line
			(start 0.7874 0.4064)
			(end 0.7874 -0.4064)
			(stroke
				(width 0.1524)
				(type default)
			)
			(layer "B.SilkS")
		)
		(fp_line
			(start -0.7874 0.4064)
			(end 0.7874 0.4064)
			(stroke
				(width 0.1524)
				(type default)
			)
			(layer "B.SilkS")
		)
		(fp_line
			(start 0.67945 -0.305054)
			(end 0.12065 -0.305054)
			(stroke
				(width 0.1)
				(type default)
			)
			(layer "B.Fab")
		)
		(fp_line
			(start 0.12065 -0.305054)
			(end 0.12065 -0.2794)
			(stroke
				(width 0.1)
				(type default)
			)
			(layer "B.Fab")
		)
		(fp_line
			(start -0.12065 -0.3048)
			(end -0.67945 -0.3048)
			(stroke
				(width 0.1)
				(type default)
			)
			(layer "B.Fab")
		)
		(fp_line
			(start -0.67945 -0.3048)
			(end -0.67945 0.3048)
			(stroke
				(width 0.1)
				(type default)
			)
			(layer "B.Fab")
		)
		(fp_line
			(start 0.12065 -0.2794)
			(end -0.12065 -0.2794)
			(stroke
				(width 0.1)
				(type default)
			)
			(layer "B.Fab")
		)
		(fp_line
			(start -0.12065 -0.2794)
			(end -0.12065 -0.3048)
			(stroke
				(width 0.1)
				(type default)
			)
			(layer "B.Fab")
		)
		(fp_line
			(start 0.12065 0.2794)
			(end 0.12065 0.3048)
			(stroke
				(width 0.1)
				(type default)
			)
			(layer "B.Fab")
		)
		(fp_line
			(start -0.120396 0.2794)
			(end 0.12065 0.2794)
			(stroke
				(width 0.1)
				(type default)
			)
			(layer "B.Fab")
		)
		(fp_line
			(start 0.67945 0.3048)
			(end 0.67945 -0.305054)
			(stroke
				(width 0.1)
				(type default)
			)
			(layer "B.Fab")
		)
		(fp_line
			(start 0.12065 0.3048)
			(end 0.67945 0.3048)
			(stroke
				(width 0.1)
				(type default)
			)
			(layer "B.Fab")
		)
		(fp_line
			(start -0.120396 0.3048)
			(end -0.120396 0.2794)
			(stroke
				(width 0.1)
				(type default)
			)
			(layer "B.Fab")
		)
		(fp_line
			(start -0.67945 0.3048)
			(end -0.120396 0.3048)
			(stroke
				(width 0.1)
				(type default)
			)
			(layer "B.Fab")
		)
		(pad "1" smd circle
			(at 0.40005 0 270)
			(size 0 0)
			(layers "B.Cu" "B.Mask" "B.Paste")
			(net "GND")
		)
		(pad "2" smd circle
			(at -0.40005 0 270)
			(size 0 0)
			(layers "B.Cu" "B.Mask" "B.Paste")
			(net "FAN_6_IMON")
		)
	)
	(footprint ""
		(layer "B.Cu")
		(at 44.6786 -52.6796 180)
		(property "Reference" "C2107"
			(at 0 0 0)
			(layer "B.SilkS")
			(hide yes)
			(effects
				(font
					(size 1.27 1.27)
				)
				(justify mirror)
			)
		)
		(property "Value" ""
			(at 0 0 0)
			(layer "B.Fab")
			(effects
				(font
					(size 1.27 1.27)
				)
				(justify mirror)
			)
		)
		(duplicate_pad_numbers_are_jumpers no)
		(fp_line
			(start 2.2098 0.9398)
			(end 2.2098 -0.9398)
			(stroke
				(width 0.1524)
				(type default)
			)
			(layer "B.SilkS")
		)
		(fp_line
			(start 2.2098 -0.9398)
			(end -2.2098 -0.9398)
			(stroke
				(width 0.1524)
				(type default)
			)
			(layer "B.SilkS")
		)
		(fp_line
			(start -2.2098 0.9398)
			(end 2.2098 0.9398)
			(stroke
				(width 0.1524)
				(type default)
			)
			(layer "B.SilkS")
		)
		(fp_line
			(start -2.2098 -0.9398)
			(end -2.2098 0.9398)
			(stroke
				(width 0.1524)
				(type default)
			)
			(layer "B.SilkS")
		)
		(fp_line
			(start 1.700022 0.899922)
			(end 1.700022 -0.899922)
			(stroke
				(width 0.1)
				(type default)
			)
			(layer "B.Fab")
		)
		(fp_line
			(start 1.700022 -0.899922)
			(end -1.700022 -0.899922)
			(stroke
				(width 0.1)
				(type default)
			)
			(layer "B.Fab")
		)
		(fp_line
			(start -1.700022 0.899922)
			(end 1.700022 0.899922)
			(stroke
				(width 0.1)
				(type default)
			)
			(layer "B.Fab")
		)
		(fp_line
			(start -1.700022 -0.899922)
			(end -1.700022 0.899922)
			(stroke
				(width 0.1)
				(type default)
			)
			(layer "B.Fab")
		)
		(pad "1" smd rect
			(at 1.4732 0 180)
			(size 1.1684 1.5748)
			(layers "B.Cu" "B.Mask" "B.Paste")
			(net "P52V_FAN_3")
		)
		(pad "2" smd rect
			(at -1.4732 0 180)
			(size 1.1684 1.5748)
			(layers "B.Cu" "B.Mask" "B.Paste")
			(net "GND")
		)
	)
	(footprint ""
		(layer "B.Cu")
		(at 38.989 -250.23699 -90)
		(property "Reference" "PC25"
			(at 0 0 90)
			(layer "B.SilkS")
			(hide yes)
			(effects
				(font
					(size 1.27 1.27)
				)
				(justify mirror)
			)
		)
		(property "Value" ""
			(at 0 0 90)
			(layer "B.Fab")
			(effects
				(font
					(size 1.27 1.27)
				)
				(justify mirror)
			)
		)
		(duplicate_pad_numbers_are_jumpers no)
		(fp_line
			(start -0.7874 0.4064)
			(end 0.7874 0.4064)
			(stroke
				(width 0.1524)
				(type default)
			)
			(layer "B.SilkS")
		)
		(fp_line
			(start 0.7874 0.4064)
			(end 0.7874 -0.4064)
			(stroke
				(width 0.1524)
				(type default)
			)
			(layer "B.SilkS")
		)
		(fp_line
			(start -0.7874 -0.4064)
			(end -0.7874 0.4064)
			(stroke
				(width 0.1524)
				(type default)
			)
			(layer "B.SilkS")
		)
		(fp_line
			(start 0.7874 -0.4064)
			(end -0.7874 -0.4064)
			(stroke
				(width 0.1524)
				(type default)
			)
			(layer "B.SilkS")
		)
		(fp_line
			(start -0.67945 0.3048)
			(end -0.120396 0.3048)
			(stroke
				(width 0.1)
				(type default)
			)
			(layer "B.Fab")
		)
		(fp_line
			(start -0.120396 0.3048)
			(end -0.120396 0.2794)
			(stroke
				(width 0.1)
				(type default)
			)
			(layer "B.Fab")
		)
		(fp_line
			(start 0.12065 0.3048)
			(end 0.67945 0.3048)
			(stroke
				(width 0.1)
				(type default)
			)
			(layer "B.Fab")
		)
		(fp_line
			(start 0.67945 0.3048)
			(end 0.67945 -0.305054)
			(stroke
				(width 0.1)
				(type default)
			)
			(layer "B.Fab")
		)
		(fp_line
			(start -0.120396 0.2794)
			(end 0.12065 0.2794)
			(stroke
				(width 0.1)
				(type default)
			)
			(layer "B.Fab")
		)
		(fp_line
			(start 0.12065 0.2794)
			(end 0.12065 0.3048)
			(stroke
				(width 0.1)
				(type default)
			)
			(layer "B.Fab")
		)
		(fp_line
			(start -0.12065 -0.2794)
			(end -0.12065 -0.3048)
			(stroke
				(width 0.1)
				(type default)
			)
			(layer "B.Fab")
		)
		(fp_line
			(start 0.12065 -0.2794)
			(end -0.12065 -0.2794)
			(stroke
				(width 0.1)
				(type default)
			)
			(layer "B.Fab")
		)
		(fp_line
			(start -0.67945 -0.3048)
			(end -0.67945 0.3048)
			(stroke
				(width 0.1)
				(type default)
			)
			(layer "B.Fab")
		)
		(fp_line
			(start -0.12065 -0.3048)
			(end -0.67945 -0.3048)
			(stroke
				(width 0.1)
				(type default)
			)
			(layer "B.Fab")
		)
		(fp_line
			(start 0.12065 -0.305054)
			(end 0.12065 -0.2794)
			(stroke
				(width 0.1)
				(type default)
			)
			(layer "B.Fab")
		)
		(fp_line
			(start 0.67945 -0.305054)
			(end 0.12065 -0.305054)
			(stroke
				(width 0.1)
				(type default)
			)
			(layer "B.Fab")
		)
		(pad "1" smd circle
			(at 0.40005 0 90)
			(size 0 0)
			(layers "B.Cu" "B.Mask" "B.Paste")
			(net "FAN_1_P3V_R")
		)
		(pad "2" smd circle
			(at -0.40005 0 90)
			(size 0 0)
			(layers "B.Cu" "B.Mask" "B.Paste")
			(net "GND")
		)
	)
	(footprint ""
		(layer "B.Cu")
		(at 33.147 -250.23699 90)
		(property "Reference" "PR34"
			(at 0 0 90)
			(layer "B.SilkS")
			(hide yes)
			(effects
				(font
					(size 1.27 1.27)
				)
				(justify mirror)
			)
		)
		(property "Value" ""
			(at 0 0 90)
			(layer "B.Fab")
			(effects
				(font
					(size 1.27 1.27)
				)
				(justify mirror)
			)
		)
		(duplicate_pad_numbers_are_jumpers no)
		(fp_line
			(start 0.7874 -0.4064)
			(end -0.7874 -0.4064)
			(stroke
				(width 0.1524)
				(type default)
			)
			(layer "B.SilkS")
		)
		(fp_line
			(start -0.7874 -0.4064)
			(end -0.7874 0.4064)
			(stroke
				(width 0.1524)
				(type default)
			)
			(layer "B.SilkS")
		)
		(fp_line
			(start 0.7874 0.4064)
			(end 0.7874 -0.4064)
			(stroke
				(width 0.1524)
				(type default)
			)
			(layer "B.SilkS")
		)
		(fp_line
			(start -0.7874 0.4064)
			(end 0.7874 0.4064)
			(stroke
				(width 0.1524)
				(type default)
			)
			(layer "B.SilkS")
		)
		(fp_line
			(start 0.67945 -0.305054)
			(end 0.12065 -0.305054)
			(stroke
				(width 0.1)
				(type default)
			)
			(layer "B.Fab")
		)
		(fp_line
			(start 0.12065 -0.305054)
			(end 0.12065 -0.2794)
			(stroke
				(width 0.1)
				(type default)
			)
			(layer "B.Fab")
		)
		(fp_line
			(start -0.12065 -0.3048)
			(end -0.67945 -0.3048)
			(stroke
				(width 0.1)
				(type default)
			)
			(layer "B.Fab")
		)
		(fp_line
			(start -0.67945 -0.3048)
			(end -0.67945 0.3048)
			(stroke
				(width 0.1)
				(type default)
			)
			(layer "B.Fab")
		)
		(fp_line
			(start 0.12065 -0.2794)
			(end -0.12065 -0.2794)
			(stroke
				(width 0.1)
				(type default)
			)
			(layer "B.Fab")
		)
		(fp_line
			(start -0.12065 -0.2794)
			(end -0.12065 -0.3048)
			(stroke
				(width 0.1)
				(type default)
			)
			(layer "B.Fab")
		)
		(fp_line
			(start 0.12065 0.2794)
			(end 0.12065 0.3048)
			(stroke
				(width 0.1)
				(type default)
			)
			(layer "B.Fab")
		)
		(fp_line
			(start -0.120396 0.2794)
			(end 0.12065 0.2794)
			(stroke
				(width 0.1)
				(type default)
			)
			(layer "B.Fab")
		)
		(fp_line
			(start 0.67945 0.3048)
			(end 0.67945 -0.305054)
			(stroke
				(width 0.1)
				(type default)
			)
			(layer "B.Fab")
		)
		(fp_line
			(start 0.12065 0.3048)
			(end 0.67945 0.3048)
			(stroke
				(width 0.1)
				(type default)
			)
			(layer "B.Fab")
		)
		(fp_line
			(start -0.120396 0.3048)
			(end -0.120396 0.2794)
			(stroke
				(width 0.1)
				(type default)
			)
			(layer "B.Fab")
		)
		(fp_line
			(start -0.67945 0.3048)
			(end -0.120396 0.3048)
			(stroke
				(width 0.1)
				(type default)
			)
			(layer "B.Fab")
		)
		(pad "1" smd circle
			(at 0.40005 0 270)
			(size 0 0)
			(layers "B.Cu" "B.Mask" "B.Paste")
			(net "GND")
		)
		(pad "2" smd circle
			(at -0.40005 0 270)
			(size 0 0)
			(layers "B.Cu" "B.Mask" "B.Paste")
			(net "FAN_1_IMON")
		)
	)
	(footprint ""
		(layer "B.Cu")
		(at 9.906 -169.799 180)
		(property "Reference" "C55"
			(at 0 0 0)
			(layer "B.SilkS")
			(hide yes)
			(effects
				(font
					(size 1.27 1.27)
				)
				(justify mirror)
			)
		)
		(property "Value" ""
			(at 0 0 0)
			(layer "B.Fab")
			(effects
				(font
					(size 1.27 1.27)
				)
				(justify mirror)
			)
		)
		(duplicate_pad_numbers_are_jumpers no)
		(fp_line
			(start 0.7874 0.4064)
			(end 0.7874 -0.4064)
			(stroke
				(width 0.1524)
				(type default)
			)
			(layer "B.SilkS")
		)
		(fp_line
			(start 0.7874 -0.4064)
			(end -0.7874 -0.4064)
			(stroke
				(width 0.1524)
				(type default)
			)
			(layer "B.SilkS")
		)
		(fp_line
			(start -0.7874 0.4064)
			(end 0.7874 0.4064)
			(stroke
				(width 0.1524)
				(type default)
			)
			(layer "B.SilkS")
		)
		(fp_line
			(start -0.7874 -0.4064)
			(end -0.7874 0.4064)
			(stroke
				(width 0.1524)
				(type default)
			)
			(layer "B.SilkS")
		)
		(fp_line
			(start 0.67945 0.3048)
			(end 0.67945 -0.305054)
			(stroke
				(width 0.1)
				(type default)
			)
			(layer "B.Fab")
		)
		(fp_line
			(start 0.67945 -0.305054)
			(end 0.12065 -0.305054)
			(stroke
				(width 0.1)
				(type default)
			)
			(layer "B.Fab")
		)
		(fp_line
			(start 0.12065 0.3048)
			(end 0.67945 0.3048)
			(stroke
				(width 0.1)
				(type default)
			)
			(layer "B.Fab")
		)
		(fp_line
			(start 0.12065 0.2794)
			(end 0.12065 0.3048)
			(stroke
				(width 0.1)
				(type default)
			)
			(layer "B.Fab")
		)
		(fp_line
			(start 0.12065 -0.2794)
			(end -0.12065 -0.2794)
			(stroke
				(width 0.1)
				(type default)
			)
			(layer "B.Fab")
		)
		(fp_line
			(start 0.12065 -0.305054)
			(end 0.12065 -0.2794)
			(stroke
				(width 0.1)
				(type default)
			)
			(layer "B.Fab")
		)
		(fp_line
			(start -0.120396 0.3048)
			(end -0.120396 0.2794)
			(stroke
				(width 0.1)
				(type default)
			)
			(layer "B.Fab")
		)
		(fp_line
			(start -0.120396 0.2794)
			(end 0.12065 0.2794)
			(stroke
				(width 0.1)
				(type default)
			)
			(layer "B.Fab")
		)
		(fp_line
			(start -0.12065 -0.2794)
			(end -0.12065 -0.3048)
			(stroke
				(width 0.1)
				(type default)
			)
			(layer "B.Fab")
		)
		(fp_line
			(start -0.12065 -0.3048)
			(end -0.67945 -0.3048)
			(stroke
				(width 0.1)
				(type default)
			)
			(layer "B.Fab")
		)
		(fp_line
			(start -0.67945 0.3048)
			(end -0.120396 0.3048)
			(stroke
				(width 0.1)
				(type default)
			)
			(layer "B.Fab")
		)
		(fp_line
			(start -0.67945 -0.3048)
			(end -0.67945 0.3048)
			(stroke
				(width 0.1)
				(type default)
			)
			(layer "B.Fab")
		)
		(pad "1" smd circle
			(at 0.40005 0)
			(size 0 0)
			(layers "B.Cu" "B.Mask" "B.Paste")
			(net "P3V3_AUX")
		)
		(pad "2" smd circle
			(at -0.40005 0)
			(size 0 0)
			(layers "B.Cu" "B.Mask" "B.Paste")
			(net "GND")
		)
	)
	(footprint ""
		(layer "B.Cu")
		(at 30.48 -67.945)
		(property "Reference" ""
			(at 0 0 0)
			(layer "B.SilkS")
			(hide yes)
			(effects
				(font
					(size 1.27 1.27)
				)
				(justify mirror)
			)
		)
		(property "Value" ""
			(at 0 0 0)
			(layer "B.Fab")
			(effects
				(font
					(size 1.27 1.27)
				)
				(justify mirror)
			)
		)
		(duplicate_pad_numbers_are_jumpers no)
		(pad "1" smd circle
			(at 0 0 180)
			(size 0.9906 0.9906)
			(layers "B.Cu" "B.Mask" "B.Paste")
			(net "Net_125")
		)
		(zone
			(layer "B.Cu")
			(hatch none 0.5)
			(connect_pads
				(clearance 0)
			)
			(min_thickness 0.25)
			(keepout
				(tracks not_allowed)
				(vias allowed)
				(pads allowed)
				(copperpour not_allowed)
				(footprints allowed)
			)
			(placement
				(enabled no)
				(sheetname "")
			)
			(fill
				(thermal_gap 0.5)
				(thermal_bridge_width 0.5)
				(island_removal_mode 0)
			)
			(polygon
				(pts
					(arc
						(start 32.1056 -67.945)
						(mid 28.8544 -67.945)
						(end 32.1056 -67.945)
					)
				)
			)
		)
	)
	(footprint ""
		(layer "B.Cu")
		(at 46.101 -258.572 -90)
		(property "Reference" "PR10"
			(at 0 0 90)
			(layer "B.SilkS")
			(hide yes)
			(effects
				(font
					(size 1.27 1.27)
				)
				(justify mirror)
			)
		)
		(property "Value" ""
			(at 0 0 90)
			(layer "B.Fab")
			(effects
				(font
					(size 1.27 1.27)
				)
				(justify mirror)
			)
		)
		(duplicate_pad_numbers_are_jumpers no)
		(fp_line
			(start -0.7874 0.4064)
			(end 0.7874 0.4064)
			(stroke
				(width 0.1524)
				(type default)
			)
			(layer "B.SilkS")
		)
		(fp_line
			(start 0.7874 0.4064)
			(end 0.7874 -0.4064)
			(stroke
				(width 0.1524)
				(type default)
			)
			(layer "B.SilkS")
		)
		(fp_line
			(start -0.7874 -0.4064)
			(end -0.7874 0.4064)
			(stroke
				(width 0.1524)
				(type default)
			)
			(layer "B.SilkS")
		)
		(fp_line
			(start 0.7874 -0.4064)
			(end -0.7874 -0.4064)
			(stroke
				(width 0.1524)
				(type default)
			)
			(layer "B.SilkS")
		)
		(fp_line
			(start -0.67945 0.3048)
			(end -0.120396 0.3048)
			(stroke
				(width 0.1)
				(type default)
			)
			(layer "B.Fab")
		)
		(fp_line
			(start -0.120396 0.3048)
			(end -0.120396 0.2794)
			(stroke
				(width 0.1)
				(type default)
			)
			(layer "B.Fab")
		)
		(fp_line
			(start 0.12065 0.3048)
			(end 0.67945 0.3048)
			(stroke
				(width 0.1)
				(type default)
			)
			(layer "B.Fab")
		)
		(fp_line
			(start 0.67945 0.3048)
			(end 0.67945 -0.305054)
			(stroke
				(width 0.1)
				(type default)
			)
			(layer "B.Fab")
		)
		(fp_line
			(start -0.120396 0.2794)
			(end 0.12065 0.2794)
			(stroke
				(width 0.1)
				(type default)
			)
			(layer "B.Fab")
		)
		(fp_line
			(start 0.12065 0.2794)
			(end 0.12065 0.3048)
			(stroke
				(width 0.1)
				(type default)
			)
			(layer "B.Fab")
		)
		(fp_line
			(start -0.12065 -0.2794)
			(end -0.12065 -0.3048)
			(stroke
				(width 0.1)
				(type default)
			)
			(layer "B.Fab")
		)
		(fp_line
			(start 0.12065 -0.2794)
			(end -0.12065 -0.2794)
			(stroke
				(width 0.1)
				(type default)
			)
			(layer "B.Fab")
		)
		(fp_line
			(start -0.67945 -0.3048)
			(end -0.67945 0.3048)
			(stroke
				(width 0.1)
				(type default)
			)
			(layer "B.Fab")
		)
		(fp_line
			(start -0.12065 -0.3048)
			(end -0.67945 -0.3048)
			(stroke
				(width 0.1)
				(type default)
			)
			(layer "B.Fab")
		)
		(fp_line
			(start 0.12065 -0.305054)
			(end 0.12065 -0.2794)
			(stroke
				(width 0.1)
				(type default)
			)
			(layer "B.Fab")
		)
		(fp_line
			(start 0.67945 -0.305054)
			(end 0.12065 -0.305054)
			(stroke
				(width 0.1)
				(type default)
			)
			(layer "B.Fab")
		)
		(pad "1" smd circle
			(at 0.40005 0 90)
			(size 0 0)
			(layers "B.Cu" "B.Mask" "B.Paste")
			(net "GND")
		)
		(pad "2" smd circle
			(at -0.40005 0 90)
			(size 0 0)
			(layers "B.Cu" "B.Mask" "B.Paste")
			(net "FAN_0_IMON")
		)
	)
	(footprint ""
		(layer "B.Cu")
		(at 19.573494 -73.971912 90)
		(property "Reference" "PR58"
			(at 0 0 90)
			(layer "B.SilkS")
			(hide yes)
			(effects
				(font
					(size 1.27 1.27)
				)
				(justify mirror)
			)
		)
		(property "Value" ""
			(at 0 0 90)
			(layer "B.Fab")
			(effects
				(font
					(size 1.27 1.27)
				)
				(justify mirror)
			)
		)
		(duplicate_pad_numbers_are_jumpers no)
		(fp_line
			(start 0.7874 -0.4064)
			(end -0.7874 -0.4064)
			(stroke
				(width 0.1524)
				(type default)
			)
			(layer "B.SilkS")
		)
		(fp_line
			(start -0.7874 -0.4064)
			(end -0.7874 0.4064)
			(stroke
				(width 0.1524)
				(type default)
			)
			(layer "B.SilkS")
		)
		(fp_line
			(start 0.7874 0.4064)
			(end 0.7874 -0.4064)
			(stroke
				(width 0.1524)
				(type default)
			)
			(layer "B.SilkS")
		)
		(fp_line
			(start -0.7874 0.4064)
			(end 0.7874 0.4064)
			(stroke
				(width 0.1524)
				(type default)
			)
			(layer "B.SilkS")
		)
		(fp_line
			(start 0.67945 -0.305054)
			(end 0.12065 -0.305054)
			(stroke
				(width 0.1)
				(type default)
			)
			(layer "B.Fab")
		)
		(fp_line
			(start 0.12065 -0.305054)
			(end 0.12065 -0.2794)
			(stroke
				(width 0.1)
				(type default)
			)
			(layer "B.Fab")
		)
		(fp_line
			(start -0.12065 -0.3048)
			(end -0.67945 -0.3048)
			(stroke
				(width 0.1)
				(type default)
			)
			(layer "B.Fab")
		)
		(fp_line
			(start -0.67945 -0.3048)
			(end -0.67945 0.3048)
			(stroke
				(width 0.1)
				(type default)
			)
			(layer "B.Fab")
		)
		(fp_line
			(start 0.12065 -0.2794)
			(end -0.12065 -0.2794)
			(stroke
				(width 0.1)
				(type default)
			)
			(layer "B.Fab")
		)
		(fp_line
			(start -0.12065 -0.2794)
			(end -0.12065 -0.3048)
			(stroke
				(width 0.1)
				(type default)
			)
			(layer "B.Fab")
		)
		(fp_line
			(start 0.12065 0.2794)
			(end 0.12065 0.3048)
			(stroke
				(width 0.1)
				(type default)
			)
			(layer "B.Fab")
		)
		(fp_line
			(start -0.120396 0.2794)
			(end 0.12065 0.2794)
			(stroke
				(width 0.1)
				(type default)
			)
			(layer "B.Fab")
		)
		(fp_line
			(start 0.67945 0.3048)
			(end 0.67945 -0.305054)
			(stroke
				(width 0.1)
				(type default)
			)
			(layer "B.Fab")
		)
		(fp_line
			(start 0.12065 0.3048)
			(end 0.67945 0.3048)
			(stroke
				(width 0.1)
				(type default)
			)
			(layer "B.Fab")
		)
		(fp_line
			(start -0.120396 0.3048)
			(end -0.120396 0.2794)
			(stroke
				(width 0.1)
				(type default)
			)
			(layer "B.Fab")
		)
		(fp_line
			(start -0.67945 0.3048)
			(end -0.120396 0.3048)
			(stroke
				(width 0.1)
				(type default)
			)
			(layer "B.Fab")
		)
		(pad "1" smd rect
			(at 0.40005 0 90)
			(size 0.4572 0.508)
			(layers "B.Cu" "B.Mask" "B.Paste")
			(net "FAN_5_CS")
		)
		(pad "2" smd rect
			(at -0.40005 0 90)
			(size 0.4572 0.508)
			(layers "B.Cu" "B.Mask" "B.Paste")
			(net "GND")
		)
	)
	(footprint ""
		(layer "B.Cu")
		(at 39.968932 -71.304912)
		(property "Reference" "U381"
			(at -3.392932 -0.677418 0)
			(unlocked yes)
			(layer "B.SilkS")
			(effects
				(font
					(size 0.7874 0.5842)
					(thickness 0.1524)
				)
				(justify mirror)
			)
		)
		(property "Value" ""
			(at 0 0 0)
			(layer "B.Fab")
			(effects
				(font
					(size 1.27 1.27)
				)
				(justify mirror)
			)
		)
		(duplicate_pad_numbers_are_jumpers no)
		(fp_line
			(start -1.7018 -1.1176)
			(end -1.7018 1.1176)
			(stroke
				(width 0.1524)
				(type default)
			)
			(layer "B.SilkS")
		)
		(fp_line
			(start -1.7018 -1.1176)
			(end -0.254 -1.1176)
			(stroke
				(width 0.1524)
				(type default)
			)
			(layer "B.SilkS")
		)
		(fp_line
			(start -1.7018 1.1176)
			(end 1.7018 1.1176)
			(stroke
				(width 0.1524)
				(type default)
			)
			(layer "B.SilkS")
		)
		(fp_line
			(start -0.254 -1.1176)
			(end 0 -0.7112)
			(stroke
				(width 0.1524)
				(type default)
			)
			(layer "B.SilkS")
		)
		(fp_line
			(start 0 -0.7112)
			(end 0.254 -1.1176)
			(stroke
				(width 0.1524)
				(type default)
			)
			(layer "B.SilkS")
		)
		(fp_line
			(start 0.254 -1.1176)
			(end 1.7018 -1.1176)
			(stroke
				(width 0.1524)
				(type default)
			)
			(layer "B.SilkS")
		)
		(fp_line
			(start 1.7018 1.1176)
			(end 1.7018 -1.1176)
			(stroke
				(width 0.1524)
				(type default)
			)
			(layer "B.SilkS")
		)
		(fp_poly
			(pts
				(xy 1.8161 -0.675386) (xy 2.4003 -0.446786) (xy 2.4003 -0.878586)
			)
			(stroke
				(width 0)
				(type default)
			)
			(fill yes)
			(layer "B.SilkS")
		)
		(fp_line
			(start -1.5494 -1.1176)
			(end -1.5494 1.1176)
			(stroke
				(width 0.1)
				(type default)
			)
			(layer "B.Fab")
		)
		(fp_line
			(start -1.5494 -1.1176)
			(end -0.254 -1.1176)
			(stroke
				(width 0.1)
				(type default)
			)
			(layer "B.Fab")
		)
		(fp_line
			(start -1.5494 1.1176)
			(end 1.5494 1.1176)
			(stroke
				(width 0.1)
				(type default)
			)
			(layer "B.Fab")
		)
		(fp_line
			(start -0.254 -1.1176)
			(end 0.254 -1.1176)
			(stroke
				(width 0.1)
				(type default)
			)
			(layer "B.Fab")
		)
		(fp_line
			(start 0.254 -1.1176)
			(end 1.5494 -1.1176)
			(stroke
				(width 0.1)
				(type default)
			)
			(layer "B.Fab")
		)
		(fp_line
			(start 1.5494 1.1176)
			(end 1.5494 -1.1176)
			(stroke
				(width 0.1)
				(type default)
			)
			(layer "B.Fab")
		)
		(fp_poly
			(pts
				(xy 1.8161 -0.675386) (xy 2.4003 -0.446786) (xy 2.4003 -0.878586)
			)
			(stroke
				(width 0)
				(type default)
			)
			(fill yes)
			(layer "B.Fab")
		)
		(pad "1" smd rect
			(at 0.962406 -0.649986 270)
			(size 0.3302 1.1684)
			(layers "B.Cu" "B.Mask" "B.Paste")
			(net "FAN_2_PRESENT_R")
		)
		(pad "2" smd rect
			(at 0.962406 0 270)
			(size 0.3302 1.1684)
			(layers "B.Cu" "B.Mask" "B.Paste")
			(net "P52V_FAN_2_BUFF_EN_R")
		)
		(pad "3" smd rect
			(at 0.962406 0.649986 270)
			(size 0.3302 1.1684)
			(layers "B.Cu" "B.Mask" "B.Paste")
			(net "GND")
		)
		(pad "4" smd rect
			(at -0.962406 0.649986 270)
			(size 0.3302 1.1684)
			(layers "B.Cu" "B.Mask" "B.Paste")
			(net "P52V_FAN_2_EN")
		)
		(pad "5" smd rect
			(at -0.962406 -0.649986 270)
			(size 0.3302 1.1684)
			(layers "B.Cu" "B.Mask" "B.Paste")
			(net "P3V3_AUX")
		)
	)
	(footprint ""
		(layer "B.Cu")
		(at 17.653 -134.239 180)
		(property "Reference" "R5441"
			(at 0 0 0)
			(layer "B.SilkS")
			(hide yes)
			(effects
				(font
					(size 1.27 1.27)
				)
				(justify mirror)
			)
		)
		(property "Value" ""
			(at 0 0 0)
			(layer "B.Fab")
			(effects
				(font
					(size 1.27 1.27)
				)
				(justify mirror)
			)
		)
		(duplicate_pad_numbers_are_jumpers no)
		(fp_line
			(start 0.7874 0.4064)
			(end 0.7874 -0.4064)
			(stroke
				(width 0.1524)
				(type default)
			)
			(layer "B.SilkS")
		)
		(fp_line
			(start 0.7874 -0.4064)
			(end -0.7874 -0.4064)
			(stroke
				(width 0.1524)
				(type default)
			)
			(layer "B.SilkS")
		)
		(fp_line
			(start -0.7874 0.4064)
			(end 0.7874 0.4064)
			(stroke
				(width 0.1524)
				(type default)
			)
			(layer "B.SilkS")
		)
		(fp_line
			(start -0.7874 -0.4064)
			(end -0.7874 0.4064)
			(stroke
				(width 0.1524)
				(type default)
			)
			(layer "B.SilkS")
		)
		(fp_line
			(start 0.67945 0.3048)
			(end 0.67945 -0.305054)
			(stroke
				(width 0.1)
				(type default)
			)
			(layer "B.Fab")
		)
		(fp_line
			(start 0.67945 -0.305054)
			(end 0.12065 -0.305054)
			(stroke
				(width 0.1)
				(type default)
			)
			(layer "B.Fab")
		)
		(fp_line
			(start 0.12065 0.3048)
			(end 0.67945 0.3048)
			(stroke
				(width 0.1)
				(type default)
			)
			(layer "B.Fab")
		)
		(fp_line
			(start 0.12065 0.2794)
			(end 0.12065 0.3048)
			(stroke
				(width 0.1)
				(type default)
			)
			(layer "B.Fab")
		)
		(fp_line
			(start 0.12065 -0.2794)
			(end -0.12065 -0.2794)
			(stroke
				(width 0.1)
				(type default)
			)
			(layer "B.Fab")
		)
		(fp_line
			(start 0.12065 -0.305054)
			(end 0.12065 -0.2794)
			(stroke
				(width 0.1)
				(type default)
			)
			(layer "B.Fab")
		)
		(fp_line
			(start -0.120396 0.3048)
			(end -0.120396 0.2794)
			(stroke
				(width 0.1)
				(type default)
			)
			(layer "B.Fab")
		)
		(fp_line
			(start -0.120396 0.2794)
			(end 0.12065 0.2794)
			(stroke
				(width 0.1)
				(type default)
			)
			(layer "B.Fab")
		)
		(fp_line
			(start -0.12065 -0.2794)
			(end -0.12065 -0.3048)
			(stroke
				(width 0.1)
				(type default)
			)
			(layer "B.Fab")
		)
		(fp_line
			(start -0.12065 -0.3048)
			(end -0.67945 -0.3048)
			(stroke
				(width 0.1)
				(type default)
			)
			(layer "B.Fab")
		)
		(fp_line
			(start -0.67945 0.3048)
			(end -0.120396 0.3048)
			(stroke
				(width 0.1)
				(type default)
			)
			(layer "B.Fab")
		)
		(fp_line
			(start -0.67945 -0.3048)
			(end -0.67945 0.3048)
			(stroke
				(width 0.1)
				(type default)
			)
			(layer "B.Fab")
		)
		(pad "1" smd rect
			(at 0.40005 0 180)
			(size 0.4572 0.508)
			(layers "B.Cu" "B.Mask" "B.Paste")
			(net "FAN_7_TACH_OL")
		)
		(pad "2" smd rect
			(at -0.40005 0 180)
			(size 0.4572 0.508)
			(layers "B.Cu" "B.Mask" "B.Paste")
			(net "GND")
		)
	)
	(footprint ""
		(layer "B.Cu")
		(at 14.351 -258.572 -90)
		(property "Reference" "PC3125"
			(at 0 0 90)
			(layer "B.SilkS")
			(hide yes)
			(effects
				(font
					(size 1.27 1.27)
				)
				(justify mirror)
			)
		)
		(property "Value" ""
			(at 0 0 90)
			(layer "B.Fab")
			(effects
				(font
					(size 1.27 1.27)
				)
				(justify mirror)
			)
		)
		(duplicate_pad_numbers_are_jumpers no)
		(fp_line
			(start -0.7874 0.4064)
			(end 0.7874 0.4064)
			(stroke
				(width 0.1524)
				(type default)
			)
			(layer "B.SilkS")
		)
		(fp_line
			(start 0.7874 0.4064)
			(end 0.7874 -0.4064)
			(stroke
				(width 0.1524)
				(type default)
			)
			(layer "B.SilkS")
		)
		(fp_line
			(start -0.7874 -0.4064)
			(end -0.7874 0.4064)
			(stroke
				(width 0.1524)
				(type default)
			)
			(layer "B.SilkS")
		)
		(fp_line
			(start 0.7874 -0.4064)
			(end -0.7874 -0.4064)
			(stroke
				(width 0.1524)
				(type default)
			)
			(layer "B.SilkS")
		)
		(fp_line
			(start -0.67945 0.3048)
			(end -0.120396 0.3048)
			(stroke
				(width 0.1)
				(type default)
			)
			(layer "B.Fab")
		)
		(fp_line
			(start -0.120396 0.3048)
			(end -0.120396 0.2794)
			(stroke
				(width 0.1)
				(type default)
			)
			(layer "B.Fab")
		)
		(fp_line
			(start 0.12065 0.3048)
			(end 0.67945 0.3048)
			(stroke
				(width 0.1)
				(type default)
			)
			(layer "B.Fab")
		)
		(fp_line
			(start 0.67945 0.3048)
			(end 0.67945 -0.305054)
			(stroke
				(width 0.1)
				(type default)
			)
			(layer "B.Fab")
		)
		(fp_line
			(start -0.120396 0.2794)
			(end 0.12065 0.2794)
			(stroke
				(width 0.1)
				(type default)
			)
			(layer "B.Fab")
		)
		(fp_line
			(start 0.12065 0.2794)
			(end 0.12065 0.3048)
			(stroke
				(width 0.1)
				(type default)
			)
			(layer "B.Fab")
		)
		(fp_line
			(start -0.12065 -0.2794)
			(end -0.12065 -0.3048)
			(stroke
				(width 0.1)
				(type default)
			)
			(layer "B.Fab")
		)
		(fp_line
			(start 0.12065 -0.2794)
			(end -0.12065 -0.2794)
			(stroke
				(width 0.1)
				(type default)
			)
			(layer "B.Fab")
		)
		(fp_line
			(start -0.67945 -0.3048)
			(end -0.67945 0.3048)
			(stroke
				(width 0.1)
				(type default)
			)
			(layer "B.Fab")
		)
		(fp_line
			(start -0.12065 -0.3048)
			(end -0.67945 -0.3048)
			(stroke
				(width 0.1)
				(type default)
			)
			(layer "B.Fab")
		)
		(fp_line
			(start 0.12065 -0.305054)
			(end 0.12065 -0.2794)
			(stroke
				(width 0.1)
				(type default)
			)
			(layer "B.Fab")
		)
		(fp_line
			(start 0.67945 -0.305054)
			(end 0.12065 -0.305054)
			(stroke
				(width 0.1)
				(type default)
			)
			(layer "B.Fab")
		)
		(pad "1" smd circle
			(at 0.40005 0 90)
			(size 0 0)
			(layers "B.Cu" "B.Mask" "B.Paste")
			(net "GND")
		)
		(pad "2" smd circle
			(at -0.40005 0 90)
			(size 0 0)
			(layers "B.Cu" "B.Mask" "B.Paste")
			(net "FAN_7_CLREF")
		)
	)
	(footprint ""
		(layer "B.Cu")
		(at 42.229532 -246.163846 -90)
		(property "Reference" "PC9"
			(at 0 0 90)
			(layer "B.SilkS")
			(hide yes)
			(effects
				(font
					(size 1.27 1.27)
				)
				(justify mirror)
			)
		)
		(property "Value" ""
			(at 0 0 90)
			(layer "B.Fab")
			(effects
				(font
					(size 1.27 1.27)
				)
				(justify mirror)
			)
		)
		(duplicate_pad_numbers_are_jumpers no)
		(fp_line
			(start -1.524 0.762)
			(end 1.524 0.762)
			(stroke
				(width 0.1524)
				(type default)
			)
			(layer "B.SilkS")
		)
		(fp_line
			(start 1.524 0.762)
			(end 1.524 -0.762)
			(stroke
				(width 0.1524)
				(type default)
			)
			(layer "B.SilkS")
		)
		(fp_line
			(start -1.524 -0.762)
			(end -1.524 0.762)
			(stroke
				(width 0.1524)
				(type default)
			)
			(layer "B.SilkS")
		)
		(fp_line
			(start 1.524 -0.762)
			(end -1.524 -0.762)
			(stroke
				(width 0.1524)
				(type default)
			)
			(layer "B.SilkS")
		)
		(fp_line
			(start -1.1049 0.724916)
			(end -1.1049 -0.724916)
			(stroke
				(width 0.1)
				(type default)
			)
			(layer "B.Fab")
		)
		(fp_line
			(start 1.1049 0.724916)
			(end -1.1049 0.724916)
			(stroke
				(width 0.1)
				(type default)
			)
			(layer "B.Fab")
		)
		(fp_line
			(start -1.1049 -0.724916)
			(end 1.1049 -0.724916)
			(stroke
				(width 0.1)
				(type default)
			)
			(layer "B.Fab")
		)
		(fp_line
			(start 1.1049 -0.724916)
			(end 1.1049 0.724916)
			(stroke
				(width 0.1)
				(type default)
			)
			(layer "B.Fab")
		)
		(pad "1" smd rect
			(at 0.889 0 270)
			(size 1.016 1.27)
			(layers "B.Cu" "B.Mask" "B.Paste")
			(net "P52V_HSC")
		)
		(pad "2" smd rect
			(at -0.889 0 270)
			(size 1.016 1.27)
			(layers "B.Cu" "B.Mask" "B.Paste")
			(net "GND")
		)
	)
	(footprint ""
		(layer "B.Cu")
		(at 40.894 -126.619 180)
		(property "Reference" "R5433"
			(at 0 0 0)
			(layer "B.SilkS")
			(hide yes)
			(effects
				(font
					(size 1.27 1.27)
				)
				(justify mirror)
			)
		)
		(property "Value" ""
			(at 0 0 0)
			(layer "B.Fab")
			(effects
				(font
					(size 1.27 1.27)
				)
				(justify mirror)
			)
		)
		(duplicate_pad_numbers_are_jumpers no)
		(fp_line
			(start 0.7874 0.4064)
			(end 0.7874 -0.4064)
			(stroke
				(width 0.1524)
				(type default)
			)
			(layer "B.SilkS")
		)
		(fp_line
			(start 0.7874 -0.4064)
			(end -0.7874 -0.4064)
			(stroke
				(width 0.1524)
				(type default)
			)
			(layer "B.SilkS")
		)
		(fp_line
			(start -0.7874 0.4064)
			(end 0.7874 0.4064)
			(stroke
				(width 0.1524)
				(type default)
			)
			(layer "B.SilkS")
		)
		(fp_line
			(start -0.7874 -0.4064)
			(end -0.7874 0.4064)
			(stroke
				(width 0.1524)
				(type default)
			)
			(layer "B.SilkS")
		)
		(fp_line
			(start 0.67945 0.3048)
			(end 0.67945 -0.305054)
			(stroke
				(width 0.1)
				(type default)
			)
			(layer "B.Fab")
		)
		(fp_line
			(start 0.67945 -0.305054)
			(end 0.12065 -0.305054)
			(stroke
				(width 0.1)
				(type default)
			)
			(layer "B.Fab")
		)
		(fp_line
			(start 0.12065 0.3048)
			(end 0.67945 0.3048)
			(stroke
				(width 0.1)
				(type default)
			)
			(layer "B.Fab")
		)
		(fp_line
			(start 0.12065 0.2794)
			(end 0.12065 0.3048)
			(stroke
				(width 0.1)
				(type default)
			)
			(layer "B.Fab")
		)
		(fp_line
			(start 0.12065 -0.2794)
			(end -0.12065 -0.2794)
			(stroke
				(width 0.1)
				(type default)
			)
			(layer "B.Fab")
		)
		(fp_line
			(start 0.12065 -0.305054)
			(end 0.12065 -0.2794)
			(stroke
				(width 0.1)
				(type default)
			)
			(layer "B.Fab")
		)
		(fp_line
			(start -0.120396 0.3048)
			(end -0.120396 0.2794)
			(stroke
				(width 0.1)
				(type default)
			)
			(layer "B.Fab")
		)
		(fp_line
			(start -0.120396 0.2794)
			(end 0.12065 0.2794)
			(stroke
				(width 0.1)
				(type default)
			)
			(layer "B.Fab")
		)
		(fp_line
			(start -0.12065 -0.2794)
			(end -0.12065 -0.3048)
			(stroke
				(width 0.1)
				(type default)
			)
			(layer "B.Fab")
		)
		(fp_line
			(start -0.12065 -0.3048)
			(end -0.67945 -0.3048)
			(stroke
				(width 0.1)
				(type default)
			)
			(layer "B.Fab")
		)
		(fp_line
			(start -0.67945 0.3048)
			(end -0.120396 0.3048)
			(stroke
				(width 0.1)
				(type default)
			)
			(layer "B.Fab")
		)
		(fp_line
			(start -0.67945 -0.3048)
			(end -0.67945 0.3048)
			(stroke
				(width 0.1)
				(type default)
			)
			(layer "B.Fab")
		)
		(pad "1" smd rect
			(at 0.40005 0 180)
			(size 0.4572 0.508)
			(layers "B.Cu" "B.Mask" "B.Paste")
			(net "FAN_3_TACH_OL")
		)
		(pad "2" smd rect
			(at -0.40005 0 180)
			(size 0.4572 0.508)
			(layers "B.Cu" "B.Mask" "B.Paste")
			(net "GND")
		)
	)
	(footprint ""
		(layer "B.Cu")
		(at 34.666428 -253.021846 90)
		(property "Reference" "U395"
			(at -1.307846 -2.943098 270)
			(unlocked yes)
			(layer "B.SilkS")
			(effects
				(font
					(size 0.7874 0.5842)
					(thickness 0.1524)
				)
				(justify left mirror)
			)
		)
		(property "Value" ""
			(at 0 0 90)
			(layer "B.Fab")
			(effects
				(font
					(size 1.27 1.27)
				)
				(justify mirror)
			)
		)
		(duplicate_pad_numbers_are_jumpers no)
		(fp_line
			(start 1.3462 -1.1938)
			(end 1.3462 1.1684)
			(stroke
				(width 0.1524)
				(type default)
			)
			(layer "B.SilkS")
		)
		(fp_line
			(start -1.3462 -1.1938)
			(end 1.3462 -1.1938)
			(stroke
				(width 0.1524)
				(type default)
			)
			(layer "B.SilkS")
		)
		(fp_line
			(start 1.3462 1.1938)
			(end -1.3462 1.1938)
			(stroke
				(width 0.1524)
				(type default)
			)
			(layer "B.SilkS")
		)
		(fp_line
			(start -1.3462 1.1938)
			(end -1.3462 -1.1938)
			(stroke
				(width 0.1524)
				(type default)
			)
			(layer "B.SilkS")
		)
		(fp_poly
			(pts
				(xy 1.447038 -0.760476) (xy 2.052066 -0.457962) (xy 2.052066 -1.06299)
			)
			(stroke
				(width 0)
				(type default)
			)
			(fill yes)
			(layer "B.SilkS")
		)
		(fp_line
			(start 0.674878 -1.124966)
			(end 0.674878 1.124966)
			(stroke
				(width 0.1)
				(type default)
			)
			(layer "B.Fab")
		)
		(fp_line
			(start -0.674878 -1.124966)
			(end 0.674878 -1.124966)
			(stroke
				(width 0.1)
				(type default)
			)
			(layer "B.Fab")
		)
		(fp_line
			(start 0.674878 1.124966)
			(end -0.674878 1.124966)
			(stroke
				(width 0.1)
				(type default)
			)
			(layer "B.Fab")
		)
		(fp_line
			(start -0.674878 1.124966)
			(end -0.674878 -1.124966)
			(stroke
				(width 0.1)
				(type default)
			)
			(layer "B.Fab")
		)
		(fp_poly
			(pts
				(xy 1.447038 -0.760476) (xy 2.052066 -0.457962) (xy 2.052066 -1.06299)
			)
			(stroke
				(width 0)
				(type default)
			)
			(fill yes)
			(layer "B.Fab")
		)
		(pad "1" smd rect
			(at 0.899922 -0.750062 270)
			(size 0.6096 0.6096)
			(layers "B.Cu" "B.Mask" "B.Paste")
			(net "NC_U395_P1")
		)
		(pad "2" smd rect
			(at 0.899922 0 180)
			(size 0.4064 0.6096)
			(layers "B.Cu" "B.Mask" "B.Paste")
			(net "FAN_1_PRSNT_BUF_N")
		)
		(pad "3" smd rect
			(at 0.899922 0.750062 270)
			(size 0.6096 0.6096)
			(layers "B.Cu" "B.Mask" "B.Paste")
			(net "GND")
		)
		(pad "4" smd rect
			(at -0.899922 0.750062 270)
			(size 0.6096 0.6096)
			(layers "B.Cu" "B.Mask" "B.Paste")
			(net "FAN_1_PRESENT")
		)
		(pad "5" smd rect
			(at -0.899922 -0.750062 270)
			(size 0.6096 0.6096)
			(layers "B.Cu" "B.Mask" "B.Paste")
			(net "P3V3_AUX")
		)
	)
	(footprint ""
		(layer "B.Cu")
		(at 46.191932 -90.371168 -90)
		(property "Reference" "PD9"
			(at 4.874768 3.800602 270)
			(unlocked yes)
			(layer "B.SilkS")
			(effects
				(font
					(size 0.7874 0.5842)
					(thickness 0.1524)
				)
				(justify left mirror)
			)
		)
		(property "Value" ""
			(at 0 0 90)
			(layer "B.Fab")
			(effects
				(font
					(size 1.27 1.27)
				)
				(justify mirror)
			)
		)
		(duplicate_pad_numbers_are_jumpers no)
		(fp_line
			(start -5.334 3.109976)
			(end -4.8133 3.109976)
			(stroke
				(width 0.1524)
				(type default)
			)
			(layer "B.SilkS")
		)
		(fp_line
			(start -5.334 3.109976)
			(end -5.334 0)
			(stroke
				(width 0.1524)
				(type default)
			)
			(layer "B.SilkS")
		)
		(fp_line
			(start -5.207 3.109976)
			(end -5.207 -3.109976)
			(stroke
				(width 0.1524)
				(type default)
			)
			(layer "B.SilkS")
		)
		(fp_line
			(start -5.1308 3.109976)
			(end -5.1308 -3.109976)
			(stroke
				(width 0.1524)
				(type default)
			)
			(layer "B.SilkS")
		)
		(fp_line
			(start -5.0292 3.109976)
			(end -5.0292 -3.109976)
			(stroke
				(width 0.1524)
				(type default)
			)
			(layer "B.SilkS")
		)
		(fp_line
			(start -4.9276 3.109976)
			(end -4.9276 -3.109976)
			(stroke
				(width 0.1524)
				(type default)
			)
			(layer "B.SilkS")
		)
		(fp_line
			(start -4.826 3.109976)
			(end 4.826 3.109976)
			(stroke
				(width 0.1524)
				(type default)
			)
			(layer "B.SilkS")
		)
		(fp_line
			(start 4.826 3.109976)
			(end 4.826 0)
			(stroke
				(width 0.1524)
				(type default)
			)
			(layer "B.SilkS")
		)
		(fp_line
			(start -1.143 1.397)
			(end -1.143 -1.397)
			(stroke
				(width 0.1524)
				(type default)
			)
			(layer "B.SilkS")
		)
		(fp_line
			(start 1.016 1.016)
			(end -1.016 0)
			(stroke
				(width 0.1524)
				(type default)
			)
			(layer "B.SilkS")
		)
		(fp_line
			(start -5.334 0)
			(end -5.334 -3.109976)
			(stroke
				(width 0.1524)
				(type default)
			)
			(layer "B.SilkS")
		)
		(fp_line
			(start -4.826 0)
			(end -4.826 3.109976)
			(stroke
				(width 0.1524)
				(type default)
			)
			(layer "B.SilkS")
		)
		(fp_line
			(start -1.143 0)
			(end -1.8034 0)
			(stroke
				(width 0.1524)
				(type default)
			)
			(layer "B.SilkS")
		)
		(fp_line
			(start -1.143 0)
			(end 1.016 -1.016)
			(stroke
				(width 0.1524)
				(type default)
			)
			(layer "B.SilkS")
		)
		(fp_line
			(start 1.0922 0)
			(end 1.7018 0)
			(stroke
				(width 0.1524)
				(type default)
			)
			(layer "B.SilkS")
		)
		(fp_line
			(start 4.826 0)
			(end 4.826 -3.109976)
			(stroke
				(width 0.1524)
				(type default)
			)
			(layer "B.SilkS")
		)
		(fp_line
			(start 1.016 -1.016)
			(end 1.016 1.016)
			(stroke
				(width 0.1524)
				(type default)
			)
			(layer "B.SilkS")
		)
		(fp_line
			(start -4.826 -3.109976)
			(end -4.826 0)
			(stroke
				(width 0.1524)
				(type default)
			)
			(layer "B.SilkS")
		)
		(fp_line
			(start -4.8133 -3.109976)
			(end -5.3467 -3.109976)
			(stroke
				(width 0.1524)
				(type default)
			)
			(layer "B.SilkS")
		)
		(fp_line
			(start 4.826 -3.109976)
			(end -4.826 -3.109976)
			(stroke
				(width 0.1524)
				(type default)
			)
			(layer "B.SilkS")
		)
		(fp_line
			(start -3.554984 3.109976)
			(end 3.554984 3.109976)
			(stroke
				(width 0.1)
				(type default)
			)
			(layer "B.Fab")
		)
		(fp_line
			(start 3.554984 3.109976)
			(end 3.554984 -3.109976)
			(stroke
				(width 0.1)
				(type default)
			)
			(layer "B.Fab")
		)
		(fp_line
			(start -1.143 1.397)
			(end -1.143 -1.397)
			(stroke
				(width 0.1)
				(type default)
			)
			(layer "B.Fab")
		)
		(fp_line
			(start 1.016 1.016)
			(end -1.016 0)
			(stroke
				(width 0.1)
				(type default)
			)
			(layer "B.Fab")
		)
		(fp_line
			(start -1.143 0)
			(end -1.8034 0)
			(stroke
				(width 0.1)
				(type default)
			)
			(layer "B.Fab")
		)
		(fp_line
			(start -1.143 0)
			(end 1.016 -1.016)
			(stroke
				(width 0.1)
				(type default)
			)
			(layer "B.Fab")
		)
		(fp_line
			(start 1.0922 0)
			(end 1.7018 0)
			(stroke
				(width 0.1)
				(type default)
			)
			(layer "B.Fab")
		)
		(fp_line
			(start 1.016 -1.016)
			(end 1.016 1.016)
			(stroke
				(width 0.1)
				(type default)
			)
			(layer "B.Fab")
		)
		(fp_line
			(start -3.554984 -3.109976)
			(end -3.554984 3.109976)
			(stroke
				(width 0.1)
				(type default)
			)
			(layer "B.Fab")
		)
		(fp_line
			(start 3.554984 -3.109976)
			(end -3.554984 -3.109976)
			(stroke
				(width 0.1)
				(type default)
			)
			(layer "B.Fab")
		)
		(fp_text user "-"
			(at -6.682232 -1.210818 90)
			(unlocked yes)
			(layer "B.SilkS")
			(effects
				(font
					(size 1.905 1.4224)
					(thickness 0.1524)
				)
				(justify left mirror)
			)
		)
		(fp_text user "+"
			(at 4.747768 -1.718818 90)
			(unlocked yes)
			(layer "B.SilkS")
			(effects
				(font
					(size 1.905 1.4224)
					(thickness 0.1524)
				)
				(justify left mirror)
			)
		)
		(fp_text user "-"
			(at -6.6802 0.22225 90)
			(unlocked yes)
			(layer "B.Fab")
			(effects
				(font
					(size 1.905 1.4224)
					(thickness 0.1524)
				)
				(justify left mirror)
			)
		)
		(fp_text user "+"
			(at 4.5466 0.19685 90)
			(unlocked yes)
			(layer "B.Fab")
			(effects
				(font
					(size 1.905 1.4224)
					(thickness 0.1524)
				)
				(justify left mirror)
			)
		)
		(pad "A" smd rect
			(at 3.400044 0 270)
			(size 2.5146 3.302)
			(layers "B.Cu" "B.Mask" "B.Paste")
			(net "GND")
		)
		(pad "C" smd rect
			(at -3.400044 0 270)
			(size 2.5146 3.302)
			(layers "B.Cu" "B.Mask" "B.Paste")
			(net "P52V_FAN_2")
		)
	)
	(footprint ""
		(layer "B.Cu")
		(at 9.413494 -73.962768 90)
		(property "Reference" "PC2123"
			(at 0 0 90)
			(layer "B.SilkS")
			(hide yes)
			(effects
				(font
					(size 1.27 1.27)
				)
				(justify mirror)
			)
		)
		(property "Value" ""
			(at 0 0 90)
			(layer "B.Fab")
			(effects
				(font
					(size 1.27 1.27)
				)
				(justify mirror)
			)
		)
		(duplicate_pad_numbers_are_jumpers no)
		(fp_line
			(start 0.7874 -0.4064)
			(end -0.7874 -0.4064)
			(stroke
				(width 0.1524)
				(type default)
			)
			(layer "B.SilkS")
		)
		(fp_line
			(start -0.7874 -0.4064)
			(end -0.7874 0.4064)
			(stroke
				(width 0.1524)
				(type default)
			)
			(layer "B.SilkS")
		)
		(fp_line
			(start 0.7874 0.4064)
			(end 0.7874 -0.4064)
			(stroke
				(width 0.1524)
				(type default)
			)
			(layer "B.SilkS")
		)
		(fp_line
			(start -0.7874 0.4064)
			(end 0.7874 0.4064)
			(stroke
				(width 0.1524)
				(type default)
			)
			(layer "B.SilkS")
		)
		(fp_line
			(start 0.67945 -0.305054)
			(end 0.12065 -0.305054)
			(stroke
				(width 0.1)
				(type default)
			)
			(layer "B.Fab")
		)
		(fp_line
			(start 0.12065 -0.305054)
			(end 0.12065 -0.2794)
			(stroke
				(width 0.1)
				(type default)
			)
			(layer "B.Fab")
		)
		(fp_line
			(start -0.12065 -0.3048)
			(end -0.67945 -0.3048)
			(stroke
				(width 0.1)
				(type default)
			)
			(layer "B.Fab")
		)
		(fp_line
			(start -0.67945 -0.3048)
			(end -0.67945 0.3048)
			(stroke
				(width 0.1)
				(type default)
			)
			(layer "B.Fab")
		)
		(fp_line
			(start 0.12065 -0.2794)
			(end -0.12065 -0.2794)
			(stroke
				(width 0.1)
				(type default)
			)
			(layer "B.Fab")
		)
		(fp_line
			(start -0.12065 -0.2794)
			(end -0.12065 -0.3048)
			(stroke
				(width 0.1)
				(type default)
			)
			(layer "B.Fab")
		)
		(fp_line
			(start 0.12065 0.2794)
			(end 0.12065 0.3048)
			(stroke
				(width 0.1)
				(type default)
			)
			(layer "B.Fab")
		)
		(fp_line
			(start -0.120396 0.2794)
			(end 0.12065 0.2794)
			(stroke
				(width 0.1)
				(type default)
			)
			(layer "B.Fab")
		)
		(fp_line
			(start 0.67945 0.3048)
			(end 0.67945 -0.305054)
			(stroke
				(width 0.1)
				(type default)
			)
			(layer "B.Fab")
		)
		(fp_line
			(start 0.12065 0.3048)
			(end 0.67945 0.3048)
			(stroke
				(width 0.1)
				(type default)
			)
			(layer "B.Fab")
		)
		(fp_line
			(start -0.120396 0.3048)
			(end -0.120396 0.2794)
			(stroke
				(width 0.1)
				(type default)
			)
			(layer "B.Fab")
		)
		(fp_line
			(start -0.67945 0.3048)
			(end -0.120396 0.3048)
			(stroke
				(width 0.1)
				(type default)
			)
			(layer "B.Fab")
		)
		(pad "1" smd circle
			(at 0.40005 0 270)
			(size 0 0)
			(layers "B.Cu" "B.Mask" "B.Paste")
			(net "FAN_5_TEMP")
		)
		(pad "2" smd circle
			(at -0.40005 0 270)
			(size 0 0)
			(layers "B.Cu" "B.Mask" "B.Paste")
			(net "GND")
		)
	)
	(footprint ""
		(layer "B.Cu")
		(at 42.27068 -64.837056 -90)
		(property "Reference" "PC2121"
			(at 0 0 90)
			(layer "B.SilkS")
			(hide yes)
			(effects
				(font
					(size 1.27 1.27)
				)
				(justify mirror)
			)
		)
		(property "Value" ""
			(at 0 0 90)
			(layer "B.Fab")
			(effects
				(font
					(size 1.27 1.27)
				)
				(justify mirror)
			)
		)
		(duplicate_pad_numbers_are_jumpers no)
		(fp_line
			(start -0.7874 0.4064)
			(end 0.7874 0.4064)
			(stroke
				(width 0.1524)
				(type default)
			)
			(layer "B.SilkS")
		)
		(fp_line
			(start 0.7874 0.4064)
			(end 0.7874 -0.4064)
			(stroke
				(width 0.1524)
				(type default)
			)
			(layer "B.SilkS")
		)
		(fp_line
			(start -0.7874 -0.4064)
			(end -0.7874 0.4064)
			(stroke
				(width 0.1524)
				(type default)
			)
			(layer "B.SilkS")
		)
		(fp_line
			(start 0.7874 -0.4064)
			(end -0.7874 -0.4064)
			(stroke
				(width 0.1524)
				(type default)
			)
			(layer "B.SilkS")
		)
		(fp_line
			(start -0.67945 0.3048)
			(end -0.120396 0.3048)
			(stroke
				(width 0.1)
				(type default)
			)
			(layer "B.Fab")
		)
		(fp_line
			(start -0.120396 0.3048)
			(end -0.120396 0.2794)
			(stroke
				(width 0.1)
				(type default)
			)
			(layer "B.Fab")
		)
		(fp_line
			(start 0.12065 0.3048)
			(end 0.67945 0.3048)
			(stroke
				(width 0.1)
				(type default)
			)
			(layer "B.Fab")
		)
		(fp_line
			(start 0.67945 0.3048)
			(end 0.67945 -0.305054)
			(stroke
				(width 0.1)
				(type default)
			)
			(layer "B.Fab")
		)
		(fp_line
			(start -0.120396 0.2794)
			(end 0.12065 0.2794)
			(stroke
				(width 0.1)
				(type default)
			)
			(layer "B.Fab")
		)
		(fp_line
			(start 0.12065 0.2794)
			(end 0.12065 0.3048)
			(stroke
				(width 0.1)
				(type default)
			)
			(layer "B.Fab")
		)
		(fp_line
			(start -0.12065 -0.2794)
			(end -0.12065 -0.3048)
			(stroke
				(width 0.1)
				(type default)
			)
			(layer "B.Fab")
		)
		(fp_line
			(start 0.12065 -0.2794)
			(end -0.12065 -0.2794)
			(stroke
				(width 0.1)
				(type default)
			)
			(layer "B.Fab")
		)
		(fp_line
			(start -0.67945 -0.3048)
			(end -0.67945 0.3048)
			(stroke
				(width 0.1)
				(type default)
			)
			(layer "B.Fab")
		)
		(fp_line
			(start -0.12065 -0.3048)
			(end -0.67945 -0.3048)
			(stroke
				(width 0.1)
				(type default)
			)
			(layer "B.Fab")
		)
		(fp_line
			(start 0.12065 -0.305054)
			(end 0.12065 -0.2794)
			(stroke
				(width 0.1)
				(type default)
			)
			(layer "B.Fab")
		)
		(fp_line
			(start 0.67945 -0.305054)
			(end 0.12065 -0.305054)
			(stroke
				(width 0.1)
				(type default)
			)
			(layer "B.Fab")
		)
		(pad "1" smd circle
			(at 0.40005 0 90)
			(size 0 0)
			(layers "B.Cu" "B.Mask" "B.Paste")
			(net "FAN_3_TEMP")
		)
		(pad "2" smd circle
			(at -0.40005 0 90)
			(size 0 0)
			(layers "B.Cu" "B.Mask" "B.Paste")
			(net "GND")
		)
	)
	(footprint ""
		(layer "B.Cu")
		(at 37.719 -73.962768 90)
		(property "Reference" "PC2120"
			(at 0 0 90)
			(layer "B.SilkS")
			(hide yes)
			(effects
				(font
					(size 1.27 1.27)
				)
				(justify mirror)
			)
		)
		(property "Value" ""
			(at 0 0 90)
			(layer "B.Fab")
			(effects
				(font
					(size 1.27 1.27)
				)
				(justify mirror)
			)
		)
		(duplicate_pad_numbers_are_jumpers no)
		(fp_line
			(start 0.7874 -0.4064)
			(end -0.7874 -0.4064)
			(stroke
				(width 0.1524)
				(type default)
			)
			(layer "B.SilkS")
		)
		(fp_line
			(start -0.7874 -0.4064)
			(end -0.7874 0.4064)
			(stroke
				(width 0.1524)
				(type default)
			)
			(layer "B.SilkS")
		)
		(fp_line
			(start 0.7874 0.4064)
			(end 0.7874 -0.4064)
			(stroke
				(width 0.1524)
				(type default)
			)
			(layer "B.SilkS")
		)
		(fp_line
			(start -0.7874 0.4064)
			(end 0.7874 0.4064)
			(stroke
				(width 0.1524)
				(type default)
			)
			(layer "B.SilkS")
		)
		(fp_line
			(start 0.67945 -0.305054)
			(end 0.12065 -0.305054)
			(stroke
				(width 0.1)
				(type default)
			)
			(layer "B.Fab")
		)
		(fp_line
			(start 0.12065 -0.305054)
			(end 0.12065 -0.2794)
			(stroke
				(width 0.1)
				(type default)
			)
			(layer "B.Fab")
		)
		(fp_line
			(start -0.12065 -0.3048)
			(end -0.67945 -0.3048)
			(stroke
				(width 0.1)
				(type default)
			)
			(layer "B.Fab")
		)
		(fp_line
			(start -0.67945 -0.3048)
			(end -0.67945 0.3048)
			(stroke
				(width 0.1)
				(type default)
			)
			(layer "B.Fab")
		)
		(fp_line
			(start 0.12065 -0.2794)
			(end -0.12065 -0.2794)
			(stroke
				(width 0.1)
				(type default)
			)
			(layer "B.Fab")
		)
		(fp_line
			(start -0.12065 -0.2794)
			(end -0.12065 -0.3048)
			(stroke
				(width 0.1)
				(type default)
			)
			(layer "B.Fab")
		)
		(fp_line
			(start 0.12065 0.2794)
			(end 0.12065 0.3048)
			(stroke
				(width 0.1)
				(type default)
			)
			(layer "B.Fab")
		)
		(fp_line
			(start -0.120396 0.2794)
			(end 0.12065 0.2794)
			(stroke
				(width 0.1)
				(type default)
			)
			(layer "B.Fab")
		)
		(fp_line
			(start 0.67945 0.3048)
			(end 0.67945 -0.305054)
			(stroke
				(width 0.1)
				(type default)
			)
			(layer "B.Fab")
		)
		(fp_line
			(start 0.12065 0.3048)
			(end 0.67945 0.3048)
			(stroke
				(width 0.1)
				(type default)
			)
			(layer "B.Fab")
		)
		(fp_line
			(start -0.120396 0.3048)
			(end -0.120396 0.2794)
			(stroke
				(width 0.1)
				(type default)
			)
			(layer "B.Fab")
		)
		(fp_line
			(start -0.67945 0.3048)
			(end -0.120396 0.3048)
			(stroke
				(width 0.1)
				(type default)
			)
			(layer "B.Fab")
		)
		(pad "1" smd circle
			(at 0.40005 0 270)
			(size 0 0)
			(layers "B.Cu" "B.Mask" "B.Paste")
			(net "FAN_2_TEMP")
		)
		(pad "2" smd circle
			(at -0.40005 0 270)
			(size 0 0)
			(layers "B.Cu" "B.Mask" "B.Paste")
			(net "GND")
		)
	)
	(footprint ""
		(layer "B.Cu")
		(at 46.482 -73.971912 -90)
		(property "Reference" "PR42"
			(at 0 0 90)
			(layer "B.SilkS")
			(hide yes)
			(effects
				(font
					(size 1.27 1.27)
				)
				(justify mirror)
			)
		)
		(property "Value" ""
			(at 0 0 90)
			(layer "B.Fab")
			(effects
				(font
					(size 1.27 1.27)
				)
				(justify mirror)
			)
		)
		(duplicate_pad_numbers_are_jumpers no)
		(fp_line
			(start -0.7874 0.4064)
			(end 0.7874 0.4064)
			(stroke
				(width 0.1524)
				(type default)
			)
			(layer "B.SilkS")
		)
		(fp_line
			(start 0.7874 0.4064)
			(end 0.7874 -0.4064)
			(stroke
				(width 0.1524)
				(type default)
			)
			(layer "B.SilkS")
		)
		(fp_line
			(start -0.7874 -0.4064)
			(end -0.7874 0.4064)
			(stroke
				(width 0.1524)
				(type default)
			)
			(layer "B.SilkS")
		)
		(fp_line
			(start 0.7874 -0.4064)
			(end -0.7874 -0.4064)
			(stroke
				(width 0.1524)
				(type default)
			)
			(layer "B.SilkS")
		)
		(fp_line
			(start -0.67945 0.3048)
			(end -0.120396 0.3048)
			(stroke
				(width 0.1)
				(type default)
			)
			(layer "B.Fab")
		)
		(fp_line
			(start -0.120396 0.3048)
			(end -0.120396 0.2794)
			(stroke
				(width 0.1)
				(type default)
			)
			(layer "B.Fab")
		)
		(fp_line
			(start 0.12065 0.3048)
			(end 0.67945 0.3048)
			(stroke
				(width 0.1)
				(type default)
			)
			(layer "B.Fab")
		)
		(fp_line
			(start 0.67945 0.3048)
			(end 0.67945 -0.305054)
			(stroke
				(width 0.1)
				(type default)
			)
			(layer "B.Fab")
		)
		(fp_line
			(start -0.120396 0.2794)
			(end 0.12065 0.2794)
			(stroke
				(width 0.1)
				(type default)
			)
			(layer "B.Fab")
		)
		(fp_line
			(start 0.12065 0.2794)
			(end 0.12065 0.3048)
			(stroke
				(width 0.1)
				(type default)
			)
			(layer "B.Fab")
		)
		(fp_line
			(start -0.12065 -0.2794)
			(end -0.12065 -0.3048)
			(stroke
				(width 0.1)
				(type default)
			)
			(layer "B.Fab")
		)
		(fp_line
			(start 0.12065 -0.2794)
			(end -0.12065 -0.2794)
			(stroke
				(width 0.1)
				(type default)
			)
			(layer "B.Fab")
		)
		(fp_line
			(start -0.67945 -0.3048)
			(end -0.67945 0.3048)
			(stroke
				(width 0.1)
				(type default)
			)
			(layer "B.Fab")
		)
		(fp_line
			(start -0.12065 -0.3048)
			(end -0.67945 -0.3048)
			(stroke
				(width 0.1)
				(type default)
			)
			(layer "B.Fab")
		)
		(fp_line
			(start 0.12065 -0.305054)
			(end 0.12065 -0.2794)
			(stroke
				(width 0.1)
				(type default)
			)
			(layer "B.Fab")
		)
		(fp_line
			(start 0.67945 -0.305054)
			(end 0.12065 -0.305054)
			(stroke
				(width 0.1)
				(type default)
			)
			(layer "B.Fab")
		)
		(pad "1" smd circle
			(at 0.40005 0 90)
			(size 0 0)
			(layers "B.Cu" "B.Mask" "B.Paste")
			(net "GND")
		)
		(pad "2" smd circle
			(at -0.40005 0 90)
			(size 0 0)
			(layers "B.Cu" "B.Mask" "B.Paste")
			(net "FAN_2_IMON")
		)
	)
	(footprint ""
		(layer "B.Cu")
		(at 37.465 -64.837056 90)
		(property "Reference" "PC3121"
			(at 0 0 90)
			(layer "B.SilkS")
			(hide yes)
			(effects
				(font
					(size 1.27 1.27)
				)
				(justify mirror)
			)
		)
		(property "Value" ""
			(at 0 0 90)
			(layer "B.Fab")
			(effects
				(font
					(size 1.27 1.27)
				)
				(justify mirror)
			)
		)
		(duplicate_pad_numbers_are_jumpers no)
		(fp_line
			(start 0.7874 -0.4064)
			(end -0.7874 -0.4064)
			(stroke
				(width 0.1524)
				(type default)
			)
			(layer "B.SilkS")
		)
		(fp_line
			(start -0.7874 -0.4064)
			(end -0.7874 0.4064)
			(stroke
				(width 0.1524)
				(type default)
			)
			(layer "B.SilkS")
		)
		(fp_line
			(start 0.7874 0.4064)
			(end 0.7874 -0.4064)
			(stroke
				(width 0.1524)
				(type default)
			)
			(layer "B.SilkS")
		)
		(fp_line
			(start -0.7874 0.4064)
			(end 0.7874 0.4064)
			(stroke
				(width 0.1524)
				(type default)
			)
			(layer "B.SilkS")
		)
		(fp_line
			(start 0.67945 -0.305054)
			(end 0.12065 -0.305054)
			(stroke
				(width 0.1)
				(type default)
			)
			(layer "B.Fab")
		)
		(fp_line
			(start 0.12065 -0.305054)
			(end 0.12065 -0.2794)
			(stroke
				(width 0.1)
				(type default)
			)
			(layer "B.Fab")
		)
		(fp_line
			(start -0.12065 -0.3048)
			(end -0.67945 -0.3048)
			(stroke
				(width 0.1)
				(type default)
			)
			(layer "B.Fab")
		)
		(fp_line
			(start -0.67945 -0.3048)
			(end -0.67945 0.3048)
			(stroke
				(width 0.1)
				(type default)
			)
			(layer "B.Fab")
		)
		(fp_line
			(start 0.12065 -0.2794)
			(end -0.12065 -0.2794)
			(stroke
				(width 0.1)
				(type default)
			)
			(layer "B.Fab")
		)
		(fp_line
			(start -0.12065 -0.2794)
			(end -0.12065 -0.3048)
			(stroke
				(width 0.1)
				(type default)
			)
			(layer "B.Fab")
		)
		(fp_line
			(start 0.12065 0.2794)
			(end 0.12065 0.3048)
			(stroke
				(width 0.1)
				(type default)
			)
			(layer "B.Fab")
		)
		(fp_line
			(start -0.120396 0.2794)
			(end 0.12065 0.2794)
			(stroke
				(width 0.1)
				(type default)
			)
			(layer "B.Fab")
		)
		(fp_line
			(start 0.67945 0.3048)
			(end 0.67945 -0.305054)
			(stroke
				(width 0.1)
				(type default)
			)
			(layer "B.Fab")
		)
		(fp_line
			(start 0.12065 0.3048)
			(end 0.67945 0.3048)
			(stroke
				(width 0.1)
				(type default)
			)
			(layer "B.Fab")
		)
		(fp_line
			(start -0.120396 0.3048)
			(end -0.120396 0.2794)
			(stroke
				(width 0.1)
				(type default)
			)
			(layer "B.Fab")
		)
		(fp_line
			(start -0.67945 0.3048)
			(end -0.120396 0.3048)
			(stroke
				(width 0.1)
				(type default)
			)
			(layer "B.Fab")
		)
		(pad "1" smd circle
			(at 0.40005 0 270)
			(size 0 0)
			(layers "B.Cu" "B.Mask" "B.Paste")
			(net "GND")
		)
		(pad "2" smd circle
			(at -0.40005 0 270)
			(size 0 0)
			(layers "B.Cu" "B.Mask" "B.Paste")
			(net "FAN_3_CLREF")
		)
	)
	(footprint ""
		(layer "B.Cu")
		(at 9.91997 -262.678672 90)
		(property "Reference" "PC64"
			(at 0 0 90)
			(layer "B.SilkS")
			(hide yes)
			(effects
				(font
					(size 1.27 1.27)
				)
				(justify mirror)
			)
		)
		(property "Value" ""
			(at 0 0 90)
			(layer "B.Fab")
			(effects
				(font
					(size 1.27 1.27)
				)
				(justify mirror)
			)
		)
		(duplicate_pad_numbers_are_jumpers no)
		(fp_line
			(start 1.524 -0.762)
			(end -1.524 -0.762)
			(stroke
				(width 0.1524)
				(type default)
			)
			(layer "B.SilkS")
		)
		(fp_line
			(start -1.524 -0.762)
			(end -1.524 0.762)
			(stroke
				(width 0.1524)
				(type default)
			)
			(layer "B.SilkS")
		)
		(fp_line
			(start 1.524 0.762)
			(end 1.524 -0.762)
			(stroke
				(width 0.1524)
				(type default)
			)
			(layer "B.SilkS")
		)
		(fp_line
			(start -1.524 0.762)
			(end 1.524 0.762)
			(stroke
				(width 0.1524)
				(type default)
			)
			(layer "B.SilkS")
		)
		(fp_line
			(start 1.1049 -0.724916)
			(end 1.1049 0.724916)
			(stroke
				(width 0.1)
				(type default)
			)
			(layer "B.Fab")
		)
		(fp_line
			(start -1.1049 -0.724916)
			(end 1.1049 -0.724916)
			(stroke
				(width 0.1)
				(type default)
			)
			(layer "B.Fab")
		)
		(fp_line
			(start 1.1049 0.724916)
			(end -1.1049 0.724916)
			(stroke
				(width 0.1)
				(type default)
			)
			(layer "B.Fab")
		)
		(fp_line
			(start -1.1049 0.724916)
			(end -1.1049 -0.724916)
			(stroke
				(width 0.1)
				(type default)
			)
			(layer "B.Fab")
		)
		(pad "1" smd rect
			(at 0.889 0 90)
			(size 1.016 1.27)
			(layers "B.Cu" "B.Mask" "B.Paste")
			(net "P52V_HSC")
		)
		(pad "2" smd rect
			(at -0.889 0 90)
			(size 1.016 1.27)
			(layers "B.Cu" "B.Mask" "B.Paste")
			(net "GND")
		)
	)
	(footprint ""
		(layer "B.Cu")
		(at 42.01668 -264.404856 180)
		(property "Reference" "PU1"
			(at -5.86232 -2.430526 0)
			(unlocked yes)
			(layer "B.SilkS")
			(effects
				(font
					(size 0.7874 0.5842)
					(thickness 0.1524)
				)
				(justify left mirror)
			)
		)
		(property "Value" ""
			(at 0 0 0)
			(layer "B.Fab")
			(effects
				(font
					(size 1.27 1.27)
				)
				(justify mirror)
			)
		)
		(duplicate_pad_numbers_are_jumpers no)
		(fp_line
			(start 2.549906 2.549906)
			(end 2.4384 2.549906)
			(stroke
				(width 0.1524)
				(type default)
			)
			(layer "B.SilkS")
		)
		(fp_line
			(start 2.549906 2.2352)
			(end 2.549906 2.549906)
			(stroke
				(width 0.1524)
				(type default)
			)
			(layer "B.SilkS")
		)
		(fp_line
			(start 2.549906 1.4986)
			(end 2.549906 1.7526)
			(stroke
				(width 0.1524)
				(type default)
			)
			(layer "B.SilkS")
		)
		(fp_line
			(start 2.549906 0.6858)
			(end 2.549906 0.9144)
			(stroke
				(width 0.1524)
				(type default)
			)
			(layer "B.SilkS")
		)
		(fp_line
			(start 2.549906 -0.9144)
			(end 2.549906 0.1016)
			(stroke
				(width 0.1524)
				(type default)
			)
			(layer "B.SilkS")
		)
		(fp_line
			(start 2.549906 -1.7526)
			(end 2.549906 -1.4986)
			(stroke
				(width 0.1524)
				(type default)
			)
			(layer "B.SilkS")
		)
		(fp_line
			(start 2.549906 -2.549906)
			(end 2.549906 -2.2352)
			(stroke
				(width 0.1524)
				(type default)
			)
			(layer "B.SilkS")
		)
		(fp_line
			(start 2.4384 -2.549906)
			(end 2.549906 -2.549906)
			(stroke
				(width 0.1524)
				(type default)
			)
			(layer "B.SilkS")
		)
		(fp_line
			(start 2.199894 -3.9624)
			(end 2.199894 -2.9464)
			(stroke
				(width 0.1524)
				(type default)
			)
			(layer "B.SilkS")
		)
		(fp_line
			(start 0.199898 -3.4544)
			(end 0.199898 -2.9464)
			(stroke
				(width 0.1524)
				(type default)
			)
			(layer "B.SilkS")
		)
		(fp_line
			(start -0.199898 2.9464)
			(end -0.199898 3.9624)
			(stroke
				(width 0.1524)
				(type default)
			)
			(layer "B.SilkS")
		)
		(fp_line
			(start -1.800098 -3.9624)
			(end -1.800098 -2.9464)
			(stroke
				(width 0.1524)
				(type default)
			)
			(layer "B.SilkS")
		)
		(fp_line
			(start -2.199894 2.9464)
			(end -2.199894 3.4544)
			(stroke
				(width 0.1524)
				(type default)
			)
			(layer "B.SilkS")
		)
		(fp_line
			(start -2.4384 2.549906)
			(end -2.549906 2.549906)
			(stroke
				(width 0.1524)
				(type default)
			)
			(layer "B.SilkS")
		)
		(fp_line
			(start -2.549906 2.549906)
			(end -2.549906 2.2352)
			(stroke
				(width 0.1524)
				(type default)
			)
			(layer "B.SilkS")
		)
		(fp_line
			(start -2.549906 1.7526)
			(end -2.549906 1.4986)
			(stroke
				(width 0.1524)
				(type default)
			)
			(layer "B.SilkS")
		)
		(fp_line
			(start -2.549906 0.9144)
			(end -2.549906 -0.1016)
			(stroke
				(width 0.1524)
				(type default)
			)
			(layer "B.SilkS")
		)
		(fp_line
			(start -2.549906 -0.6858)
			(end -2.549906 -0.9144)
			(stroke
				(width 0.1524)
				(type default)
			)
			(layer "B.SilkS")
		)
		(fp_line
			(start -2.549906 -1.4986)
			(end -2.549906 -1.7526)
			(stroke
				(width 0.1524)
				(type default)
			)
			(layer "B.SilkS")
		)
		(fp_line
			(start -2.549906 -2.2352)
			(end -2.549906 -2.549906)
			(stroke
				(width 0.1524)
				(type default)
			)
			(layer "B.SilkS")
		)
		(fp_line
			(start -2.549906 -2.549906)
			(end -2.4384 -2.549906)
			(stroke
				(width 0.1524)
				(type default)
			)
			(layer "B.SilkS")
		)
		(fp_poly
			(pts
				(xy 3.53568 -1.498346) (xy 2.939034 -1.199896) (xy 3.53568 -0.9017)
			)
			(stroke
				(width 0)
				(type default)
			)
			(fill yes)
			(layer "B.SilkS")
		)
		(fp_line
			(start 2.549906 2.549906)
			(end -2.549906 2.549906)
			(stroke
				(width 0.1)
				(type default)
			)
			(layer "B.Fab")
		)
		(fp_line
			(start 2.549906 -2.549906)
			(end 2.549906 2.549906)
			(stroke
				(width 0.1)
				(type default)
			)
			(layer "B.Fab")
		)
		(fp_line
			(start 2.199894 -3.9624)
			(end 2.199894 -2.9464)
			(stroke
				(width 0.1)
				(type default)
			)
			(layer "B.Fab")
		)
		(fp_line
			(start 1.800098 2.9464)
			(end 1.800098 3.4544)
			(stroke
				(width 0.1)
				(type default)
			)
			(layer "B.Fab")
		)
		(fp_line
			(start 0.199898 -3.4544)
			(end 0.199898 -2.9464)
			(stroke
				(width 0.1)
				(type default)
			)
			(layer "B.Fab")
		)
		(fp_line
			(start -0.199898 2.9464)
			(end -0.199898 3.9624)
			(stroke
				(width 0.1)
				(type default)
			)
			(layer "B.Fab")
		)
		(fp_line
			(start -1.800098 -3.9624)
			(end -1.800098 -2.9464)
			(stroke
				(width 0.1)
				(type default)
			)
			(layer "B.Fab")
		)
		(fp_line
			(start -2.199894 2.9464)
			(end -2.199894 3.4544)
			(stroke
				(width 0.1)
				(type default)
			)
			(layer "B.Fab")
		)
		(fp_line
			(start -2.549906 2.549906)
			(end -2.549906 -2.549906)
			(stroke
				(width 0.1)
				(type default)
			)
			(layer "B.Fab")
		)
		(fp_line
			(start -2.549906 -2.549906)
			(end 2.549906 -2.549906)
			(stroke
				(width 0.1)
				(type default)
			)
			(layer "B.Fab")
		)
		(fp_poly
			(pts
				(xy 3.7084 -1.584706) (xy 2.939034 -1.199896) (xy 3.7084 -0.81534)
			)
			(stroke
				(width 0)
				(type default)
			)
			(fill yes)
			(layer "B.Fab")
		)
		(fp_text user "3"
			(at 3.37693 1.152144 270)
			(unlocked yes)
			(layer "B.SilkS")
			(effects
				(font
					(size 0.635 0.4064)
					(thickness 0.1524)
				)
				(justify mirror)
			)
		)
		(fp_text user "30"
			(at 2.90068 -3.134106 0)
			(unlocked yes)
			(layer "B.SilkS")
			(effects
				(font
					(size 0.635 0.4064)
					(thickness 0.1524)
				)
				(justify mirror)
			)
		)
		(fp_text user "4"
			(at 2.64668 3.088894 0)
			(unlocked yes)
			(layer "B.SilkS")
			(effects
				(font
					(size 0.635 0.4064)
					(thickness 0.1524)
				)
				(justify mirror)
			)
		)
		(fp_text user "15"
			(at -2.94132 3.088894 0)
			(unlocked yes)
			(layer "B.SilkS")
			(effects
				(font
					(size 0.635 0.4064)
					(thickness 0.1524)
				)
				(justify mirror)
			)
		)
		(fp_text user "19"
			(at -3.06832 -3.134106 0)
			(unlocked yes)
			(layer "B.SilkS")
			(effects
				(font
					(size 0.635 0.4064)
					(thickness 0.1524)
				)
				(justify mirror)
			)
		)
		(fp_text user "16"
			(at -3.35407 1.152144 270)
			(unlocked yes)
			(layer "B.SilkS")
			(effects
				(font
					(size 0.635 0.4064)
					(thickness 0.1524)
				)
				(justify mirror)
			)
		)
		(fp_text user "18"
			(at -3.35407 -1.260856 270)
			(unlocked yes)
			(layer "B.SilkS")
			(effects
				(font
					(size 0.635 0.4064)
					(thickness 0.1524)
				)
				(justify mirror)
			)
		)
		(fp_text user "3"
			(at 3.299968 1.1938 90)
			(unlocked yes)
			(layer "B.Fab")
			(effects
				(font
					(size 0.635 0.4064)
					(thickness 0.1524)
				)
				(justify mirror)
			)
		)
		(fp_text user "30"
			(at 2.9464 -3.045968 180)
			(unlocked yes)
			(layer "B.Fab")
			(effects
				(font
					(size 0.635 0.4064)
					(thickness 0.1524)
				)
				(justify mirror)
			)
		)
		(fp_text user "4"
			(at 2.6416 3.151632 180)
			(unlocked yes)
			(layer "B.Fab")
			(effects
				(font
					(size 0.635 0.4064)
					(thickness 0.1524)
				)
				(justify mirror)
			)
		)
		(fp_text user "19"
			(at -2.8448 -3.096768 180)
			(unlocked yes)
			(layer "B.Fab")
			(effects
				(font
					(size 0.635 0.4064)
					(thickness 0.1524)
				)
				(justify mirror)
			)
		)
		(fp_text user "15"
			(at -2.8956 3.126232 180)
			(unlocked yes)
			(layer "B.Fab")
			(effects
				(font
					(size 0.635 0.4064)
					(thickness 0.1524)
				)
				(justify mirror)
			)
		)
		(fp_text user "18"
			(at -3.304032 -1.2192 90)
			(unlocked yes)
			(layer "B.Fab")
			(effects
				(font
					(size 0.635 0.4064)
					(thickness 0.1524)
				)
				(justify mirror)
			)
		)
		(fp_text user "16"
			(at -3.329432 1.2192 90)
			(unlocked yes)
			(layer "B.Fab")
			(effects
				(font
					(size 0.635 0.4064)
					(thickness 0.1524)
				)
				(justify mirror)
			)
		)
		(pad "1" smd circle
			(at 1.599946 -1.199896 90)
			(size 0 0)
			(layers "B.Cu" "B.Mask" "B.Paste")
			(net "P52V_HSC")
		)
		(pad "2" smd rect
			(at 1.549908 0.40005 270)
			(size 0.3048 2.5146)
			(layers "B.Cu" "B.Mask" "B.Paste")
			(net "P52V_HSC")
		)
		(pad "3" smd rect
			(at 1.549908 1.199896 270)
			(size 0.3048 2.5146)
			(layers "B.Cu" "B.Mask" "B.Paste")
			(net "P52V_FAN_0")
		)
		(pad "4" smd circle
			(at 2.199894 2.350008 180)
			(size 0 0)
			(layers "B.Cu" "B.Mask" "B.Paste")
			(net "P52V_FAN_0")
		)
		(pad "5" smd rect
			(at 1.800098 2.350008)
			(size 0.1778 0.9144)
			(layers "B.Cu" "B.Mask" "B.Paste")
			(net "P52V_FAN_0")
		)
		(pad "6" smd rect
			(at 1.400048 2.350008)
			(size 0.1778 0.9144)
			(layers "B.Cu" "B.Mask" "B.Paste")
			(net "P52V_FAN_0")
		)
		(pad "7" smd rect
			(at 0.999998 2.350008)
			(size 0.1778 0.9144)
			(layers "B.Cu" "B.Mask" "B.Paste")
			(net "P52V_FAN_0")
		)
		(pad "8" smd rect
			(at 0.599948 2.350008)
			(size 0.1778 0.9144)
			(layers "B.Cu" "B.Mask" "B.Paste")
			(net "P52V_FAN_0")
		)
		(pad "9" smd rect
			(at 0.199898 2.350008)
			(size 0.1778 0.9144)
			(layers "B.Cu" "B.Mask" "B.Paste")
			(net "P52V_FAN_0")
		)
		(pad "10" smd rect
			(at -0.199898 2.350008)
			(size 0.1778 0.9144)
			(layers "B.Cu" "B.Mask" "B.Paste")
			(net "P52V_FAN_0")
		)
		(pad "11" smd rect
			(at -0.599948 2.350008)
			(size 0.1778 0.9144)
			(layers "B.Cu" "B.Mask" "B.Paste")
			(net "P52V_FAN_0")
		)
		(pad "12" smd rect
			(at -0.999998 2.350008)
			(size 0.1778 0.9144)
			(layers "B.Cu" "B.Mask" "B.Paste")
			(net "P52V_FAN_0")
		)
		(pad "13" smd rect
			(at -1.400048 2.350008)
			(size 0.1778 0.9144)
			(layers "B.Cu" "B.Mask" "B.Paste")
			(net "P52V_FAN_0")
		)
		(pad "14" smd rect
			(at -1.800098 2.350008)
			(size 0.1778 0.9144)
			(layers "B.Cu" "B.Mask" "B.Paste")
			(net "P52V_FAN_0")
		)
		(pad "15" smd circle
			(at -2.199894 2.350008 180)
			(size 0 0)
			(layers "B.Cu" "B.Mask" "B.Paste")
			(net "P52V_FAN_0")
		)
		(pad "16" smd rect
			(at -1.549908 1.199896 270)
			(size 0.3048 2.5146)
			(layers "B.Cu" "B.Mask" "B.Paste")
			(net "P52V_FAN_0")
		)
		(pad "17" smd rect
			(at -1.549908 -0.40005 270)
			(size 0.3048 2.5146)
			(layers "B.Cu" "B.Mask" "B.Paste")
			(net "P52V_FAN_0")
		)
		(pad "18" smd rect
			(at -1.549908 -1.199896 270)
			(size 0.3048 2.5146)
			(layers "B.Cu" "B.Mask" "B.Paste")
			(net "P52V_HSC")
		)
		(pad "19" smd circle
			(at -2.199894 -2.350008)
			(size 0 0)
			(layers "B.Cu" "B.Mask" "B.Paste")
			(net "FAN_0_CS")
		)
		(pad "20" smd rect
			(at -1.800098 -2.350008)
			(size 0.1778 0.9144)
			(layers "B.Cu" "B.Mask" "B.Paste")
			(net "FAN_0_IMON")
		)
		(pad "21" smd rect
			(at -1.400048 -2.350008)
			(size 0.1778 0.9144)
			(layers "B.Cu" "B.Mask" "B.Paste")
			(net "FAN_0_SS")
		)
		(pad "22" smd rect
			(at -0.999998 -2.350008)
			(size 0.1778 0.9144)
			(layers "B.Cu" "B.Mask" "B.Paste")
			(net "FAN_0_FAULT")
		)
		(pad "23" smd rect
			(at -0.599948 -2.350008)
			(size 0.1778 0.9144)
			(layers "B.Cu" "B.Mask" "B.Paste")
			(net "FAN_0_TIMER")
		)
		(pad "24" smd rect
			(at -0.199898 -2.350008)
			(size 0.1778 0.9144)
			(layers "B.Cu" "B.Mask" "B.Paste")
			(net "FAN_0_CLREF")
		)
		(pad "25" smd rect
			(at 0.199898 -2.350008)
			(size 0.1778 0.9144)
			(layers "B.Cu" "B.Mask" "B.Paste")
			(net "GND")
		)
		(pad "26" smd rect
			(at 0.599948 -2.350008)
			(size 0.1778 0.9144)
			(layers "B.Cu" "B.Mask" "B.Paste")
			(net "FAN_0_ON")
		)
		(pad "27" smd rect
			(at 0.999998 -2.350008)
			(size 0.1778 0.9144)
			(layers "B.Cu" "B.Mask" "B.Paste")
			(net "FAN_0_P3V_R")
		)
		(pad "28" smd rect
			(at 1.400048 -2.350008)
			(size 0.1778 0.9144)
			(layers "B.Cu" "B.Mask" "B.Paste")
			(net "FAN_0_P5V")
		)
		(pad "29" smd rect
			(at 1.800098 -2.350008)
			(size 0.1778 0.9144)
			(layers "B.Cu" "B.Mask" "B.Paste")
			(net "FAN_0_TEMP")
		)
		(pad "30" smd circle
			(at 2.199894 -2.350008)
			(size 0 0)
			(layers "B.Cu" "B.Mask" "B.Paste")
			(net "FAN_0_MODE")
		)
	)
	(footprint ""
		(layer "B.Cu")
		(at 27.120088 -10.999978)
		(property "Reference" "GF1"
			(at 6.661912 -2.054352 0)
			(unlocked yes)
			(layer "B.SilkS")
			(effects
				(font
					(size 0.7874 0.5842)
					(thickness 0.1524)
				)
				(justify left mirror)
			)
		)
		(property "Value" ""
			(at 0 0 0)
			(layer "B.Fab")
			(effects
				(font
					(size 1.27 1.27)
				)
				(justify mirror)
			)
		)
		(duplicate_pad_numbers_are_jumpers no)
		(fp_line
			(start -8.26008 -0.350012)
			(end -8.26008 9.150096)
			(stroke
				(width 0.1524)
				(type default)
			)
			(layer "F.SilkS")
		)
		(fp_line
			(start -8.26008 9.150096)
			(end -6.759956 10.649966)
			(stroke
				(width 0.1524)
				(type default)
			)
			(layer "F.SilkS")
		)
		(fp_line
			(start -6.759956 10.649966)
			(end -1.849882 10.649966)
			(stroke
				(width 0.1524)
				(type default)
			)
			(layer "F.SilkS")
		)
		(fp_line
			(start -1.849882 10.649966)
			(end -0.350012 9.150096)
			(stroke
				(width 0.1524)
				(type default)
			)
			(layer "F.SilkS")
		)
		(fp_line
			(start -0.350012 9.150096)
			(end -0.350012 0)
			(stroke
				(width 0.1524)
				(type default)
			)
			(layer "F.SilkS")
		)
		(fp_line
			(start 0.350012 0)
			(end 0.350012 2.710688)
			(stroke
				(width 0.1524)
				(type default)
			)
			(layer "F.SilkS")
		)
		(fp_line
			(start 0.514858 9.314942)
			(end 1.849882 10.649966)
			(stroke
				(width 0.1524)
				(type default)
			)
			(layer "F.SilkS")
		)
		(fp_line
			(start 1.849882 10.649966)
			(end 4.219956 10.649966)
			(stroke
				(width 0.1524)
				(type default)
			)
			(layer "F.SilkS")
		)
		(fp_line
			(start 4.219956 10.649966)
			(end 5.72008 9.150096)
			(stroke
				(width 0.1524)
				(type default)
			)
			(layer "F.SilkS")
		)
		(fp_line
			(start 5.72008 -1.149604)
			(end -8.26008 -1.149604)
			(stroke
				(width 0.1524)
				(type default)
			)
			(layer "F.SilkS")
		)
		(fp_line
			(start 5.72008 9.150096)
			(end 5.72008 -0.350012)
			(stroke
				(width 0.1524)
				(type default)
			)
			(layer "F.SilkS")
		)
		(fp_arc
			(start -0.350012 0)
			(mid -0.247504 -0.247514)
			(end 0 -0.350012)
			(stroke
				(width 0.1524)
				(type default)
			)
			(layer "F.SilkS")
		)
		(fp_arc
			(start 0 -0.350012)
			(mid 0.247496 -0.247499)
			(end 0.350012 0)
			(stroke
				(width 0.1524)
				(type default)
			)
			(layer "F.SilkS")
		)
		(fp_line
			(start -8.26008 -0.350012)
			(end -8.26008 9.150096)
			(stroke
				(width 0.1524)
				(type default)
			)
			(layer "B.SilkS")
		)
		(fp_line
			(start -8.26008 9.150096)
			(end -6.759956 10.649966)
			(stroke
				(width 0.1524)
				(type default)
			)
			(layer "B.SilkS")
		)
		(fp_line
			(start -6.759956 10.649966)
			(end -1.849882 10.649966)
			(stroke
				(width 0.1524)
				(type default)
			)
			(layer "B.SilkS")
		)
		(fp_line
			(start -1.849882 10.649966)
			(end -0.350012 9.150096)
			(stroke
				(width 0.1524)
				(type default)
			)
			(layer "B.SilkS")
		)
		(fp_line
			(start -0.350012 9.150096)
			(end -0.350012 0)
			(stroke
				(width 0.1524)
				(type default)
			)
			(layer "B.SilkS")
		)
		(fp_line
			(start 0.350012 0)
			(end 0.350012 2.710688)
			(stroke
				(width 0.1524)
				(type default)
			)
			(layer "B.SilkS")
		)
		(fp_line
			(start 0.514858 9.314942)
			(end 1.849882 10.649966)
			(stroke
				(width 0.1524)
				(type default)
			)
			(layer "B.SilkS")
		)
		(fp_line
			(start 1.849882 10.649966)
			(end 4.219956 10.649966)
			(stroke
				(width 0.1524)
				(type default)
			)
			(layer "B.SilkS")
		)
		(fp_line
			(start 4.219956 10.649966)
			(end 5.72008 9.150096)
			(stroke
				(width 0.1524)
				(type default)
			)
			(layer "B.SilkS")
		)
		(fp_line
			(start 5.72008 -1.149604)
			(end -8.26008 -1.149604)
			(stroke
				(width 0.1524)
				(type default)
			)
			(layer "B.SilkS")
		)
		(fp_line
			(start 5.72008 9.150096)
			(end 5.72008 -0.350012)
			(stroke
				(width 0.1524)
				(type default)
			)
			(layer "B.SilkS")
		)
		(fp_arc
			(start -0.350012 0)
			(mid -0.247504 -0.247514)
			(end 0 -0.350012)
			(stroke
				(width 0.1524)
				(type default)
			)
			(layer "B.SilkS")
		)
		(fp_arc
			(start 0 -0.350012)
			(mid 0.247496 -0.247499)
			(end 0.350012 0)
			(stroke
				(width 0.1524)
				(type default)
			)
			(layer "B.SilkS")
		)
		(fp_line
			(start -8.26008 -0.350012)
			(end -8.26008 9.150096)
			(stroke
				(width 0.1)
				(type default)
			)
			(layer "B.Fab")
		)
		(fp_line
			(start -8.26008 9.150096)
			(end -6.759956 10.649966)
			(stroke
				(width 0.1)
				(type default)
			)
			(layer "B.Fab")
		)
		(fp_line
			(start -6.759956 10.649966)
			(end -1.849882 10.649966)
			(stroke
				(width 0.1)
				(type default)
			)
			(layer "B.Fab")
		)
		(fp_line
			(start -1.849882 10.649966)
			(end -0.350012 9.150096)
			(stroke
				(width 0.1)
				(type default)
			)
			(layer "B.Fab")
		)
		(fp_line
			(start -0.350012 9.150096)
			(end -0.350012 0)
			(stroke
				(width 0.1)
				(type default)
			)
			(layer "B.Fab")
		)
		(fp_line
			(start 0.350012 0)
			(end 0.350012 9.150096)
			(stroke
				(width 0.1)
				(type default)
			)
			(layer "B.Fab")
		)
		(fp_line
			(start 0.350012 9.150096)
			(end 1.849882 10.649966)
			(stroke
				(width 0.1)
				(type default)
			)
			(layer "B.Fab")
		)
		(fp_line
			(start 1.849882 10.649966)
			(end 4.219956 10.649966)
			(stroke
				(width 0.1)
				(type default)
			)
			(layer "B.Fab")
		)
		(fp_line
			(start 4.219956 10.649966)
			(end 5.72008 9.150096)
			(stroke
				(width 0.1)
				(type default)
			)
			(layer "B.Fab")
		)
		(fp_line
			(start 5.72008 -1.149604)
			(end -8.26008 -1.149604)
			(stroke
				(width 0.1)
				(type default)
			)
			(layer "B.Fab")
		)
		(fp_line
			(start 5.72008 9.150096)
			(end 5.72008 -0.350012)
			(stroke
				(width 0.1)
				(type default)
			)
			(layer "B.Fab")
		)
		(fp_arc
			(start -0.350012 0)
			(mid -0.247504 -0.247514)
			(end 0 -0.350012)
			(stroke
				(width 0.1)
				(type default)
			)
			(layer "B.Fab")
		)
		(fp_arc
			(start 0 -0.350012)
			(mid 0.247496 -0.247499)
			(end 0.350012 0)
			(stroke
				(width 0.1)
				(type default)
			)
			(layer "B.Fab")
		)
		(fp_line
			(start -8.26008 -0.350012)
			(end -8.26008 9.150096)
			(stroke
				(width 0.1)
				(type default)
			)
			(layer "F.Fab")
		)
		(fp_line
			(start -8.26008 9.150096)
			(end -6.759956 10.649966)
			(stroke
				(width 0.1)
				(type default)
			)
			(layer "F.Fab")
		)
		(fp_line
			(start -6.759956 10.649966)
			(end -1.849882 10.649966)
			(stroke
				(width 0.1)
				(type default)
			)
			(layer "F.Fab")
		)
		(fp_line
			(start -1.849882 10.649966)
			(end -0.350012 9.150096)
			(stroke
				(width 0.1)
				(type default)
			)
			(layer "F.Fab")
		)
		(fp_line
			(start -0.350012 9.150096)
			(end -0.350012 0)
			(stroke
				(width 0.1)
				(type default)
			)
			(layer "F.Fab")
		)
		(fp_line
			(start 0.350012 0)
			(end 0.350012 9.150096)
			(stroke
				(width 0.1)
				(type default)
			)
			(layer "F.Fab")
		)
		(fp_line
			(start 0.350012 9.150096)
			(end 1.849882 10.649966)
			(stroke
				(width 0.1)
				(type default)
			)
			(layer "F.Fab")
		)
		(fp_line
			(start 1.849882 10.649966)
			(end 4.219956 10.649966)
			(stroke
				(width 0.1)
				(type default)
			)
			(layer "F.Fab")
		)
		(fp_line
			(start 4.219956 10.649966)
			(end 5.72008 9.150096)
			(stroke
				(width 0.1)
				(type default)
			)
			(layer "F.Fab")
		)
		(fp_line
			(start 5.72008 -1.149604)
			(end -8.26008 -1.149604)
			(stroke
				(width 0.1)
				(type default)
			)
			(layer "F.Fab")
		)
		(fp_line
			(start 5.72008 9.150096)
			(end 5.72008 -0.350012)
			(stroke
				(width 0.1)
				(type default)
			)
			(layer "F.Fab")
		)
		(fp_arc
			(start -0.350012 0)
			(mid -0.247504 -0.247514)
			(end 0 -0.350012)
			(stroke
				(width 0.1)
				(type default)
			)
			(layer "F.Fab")
		)
		(fp_arc
			(start 0 -0.350012)
			(mid 0.247496 -0.247499)
			(end 0.350012 0)
			(stroke
				(width 0.1)
				(type default)
			)
			(layer "F.Fab")
		)
		(pad "P1_P2" smd rect
			(at 2.54 5.999988 180)
			(size 4.3942 6.2992)
			(layers "B.Cu" "B.Mask" "B.Paste")
			(net "P52V_HSC")
		)
		(pad "P3_P4" smd rect
			(at 2.54 5.999988 180)
			(size 4.3942 6.2992)
			(layers "B.Cu" "B.Mask" "B.Paste")
			(net "GND")
		)
		(pad "S1" smd rect
			(at -2.23012 6.649974 180)
			(size 0.8128 5.0038)
			(layers "B.Cu" "B.Mask" "B.Paste")
			(net "RST_SMB_PDB_N")
		)
		(pad "S2" smd rect
			(at -3.50012 6.649974 180)
			(size 0.8128 5.0038)
			(layers "B.Cu" "B.Mask" "B.Paste")
			(net "P52V_FAN_EN_R")
		)
		(pad "S3" smd rect
			(at -4.77012 6.649974 180)
			(size 0.8128 5.0038)
			(layers "B.Cu" "B.Mask" "B.Paste")
			(net "P12V_LED")
		)
		(pad "S4" smd rect
			(at -6.04012 6.649974 180)
			(size 0.8128 5.0038)
			(layers "B.Cu" "B.Mask" "B.Paste")
			(net "P3V3_AUX")
		)
		(pad "S5" smd rect
			(at -6.04012 6.649974 180)
			(size 0.8128 5.0038)
			(layers "B.Cu" "B.Mask" "B.Paste")
			(net "GND")
		)
		(pad "S6" smd rect
			(at -4.77012 6.649974 180)
			(size 0.8128 5.0038)
			(layers "B.Cu" "B.Mask" "B.Paste")
			(net "GND")
		)
		(pad "S7" smd rect
			(at -3.50012 6.649974 180)
			(size 0.8128 5.0038)
			(layers "B.Cu" "B.Mask" "B.Paste")
			(net "SMB_PDBV_FAN_R_SCL")
		)
		(pad "S8" smd rect
			(at -2.23012 6.649974 180)
			(size 0.8128 5.0038)
			(layers "B.Cu" "B.Mask" "B.Paste")
			(net "SMB_PDBV_FAN_R_SDA")
		)
		(zone
			(layer "F.Cu")
			(hatch none 0.5)
			(connect_pads
				(clearance 0)
			)
			(min_thickness 0.25)
			(keepout
				(tracks not_allowed)
				(vias allowed)
				(pads allowed)
				(copperpour not_allowed)
				(footprints allowed)
			)
			(placement
				(enabled no)
				(sheetname "")
			)
			(fill
				(thermal_gap 0.5)
				(thermal_bridge_width 0.5)
				(island_removal_mode 0)
			)
			(polygon
				(pts
					(xy 31.340044 -0.350012) (xy 32.840168 -1.849882) (xy 32.840168 -8.20039) (xy 31.857188 -8.20039)
					(xy 31.857188 -1.85039) (xy 27.462988 -1.85039) (xy 27.462988 -8.20039) (xy 27.412188 -8.20039)
					(xy 27.412188 -1.79959) (xy 27.520392 -1.79959) (xy 28.96997 -0.350012)
				)
			)
		)
		(zone
			(layer "F.Cu")
			(hatch none 0.5)
			(connect_pads
				(clearance 0)
			)
			(min_thickness 0.25)
			(keepout
				(tracks not_allowed)
				(vias allowed)
				(pads allowed)
				(copperpour not_allowed)
				(footprints allowed)
			)
			(placement
				(enabled no)
				(sheetname "")
			)
			(fill
				(thermal_gap 0.5)
				(thermal_bridge_width 0.5)
				(island_removal_mode 0)
			)
			(polygon
				(pts
					(xy 25.270206 -0.350012) (xy 26.770076 -1.849882) (xy 26.770076 -6.902704) (xy 25.296622 -6.902704)
					(xy 25.296622 -6.851904) (xy 25.296622 -1.848104) (xy 24.483568 -1.848104) (xy 24.483568 -6.851904)
					(xy 24.483568 -6.902704) (xy 24.026622 -6.902704) (xy 24.026622 -6.851904) (xy 24.026622 -1.848104)
					(xy 23.213568 -1.848104) (xy 23.213568 -6.851904) (xy 23.213568 -6.902704) (xy 22.756622 -6.902704)
					(xy 22.756622 -6.851904) (xy 22.756622 -1.848104) (xy 21.943568 -1.848104) (xy 21.943568 -6.851904)
					(xy 21.943568 -6.902704) (xy 21.486622 -6.902704) (xy 21.486622 -6.851904) (xy 21.486622 -1.848104)
					(xy 20.673568 -1.848104) (xy 20.673568 -6.851904) (xy 20.673568 -6.902704) (xy 18.860008 -6.902704)
					(xy 18.860008 -1.849882) (xy 20.360132 -0.350012)
				)
			)
		)
		(zone
			(layers "F.Cu" "B.Cu" "In1.Cu" "In2.Cu" "In3.Cu" "In4.Cu")
			(hatch none 0.5)
			(connect_pads
				(clearance 0)
			)
			(min_thickness 0.25)
			(keepout
				(tracks allowed)
				(vias not_allowed)
				(pads allowed)
				(copperpour not_allowed)
				(footprints allowed)
			)
			(placement
				(enabled no)
				(sheetname "")
			)
			(fill
				(thermal_gap 0.5)
				(thermal_bridge_width 0.5)
				(island_removal_mode 0)
			)
			(polygon
				(pts
					(xy 25.347168 -7.105904) (xy 25.347168 -1.797304) (xy 20.622768 -1.797304) (xy 20.622768 -7.105904)
				)
			)
		)
		(zone
			(layers "F.Cu" "B.Cu" "In1.Cu" "In2.Cu" "In3.Cu" "In4.Cu")
			(hatch none 0.5)
			(connect_pads
				(clearance 0)
			)
			(min_thickness 0.25)
			(keepout
				(tracks allowed)
				(vias not_allowed)
				(pads allowed)
				(copperpour not_allowed)
				(footprints allowed)
			)
			(placement
				(enabled no)
				(sheetname "")
			)
			(fill
				(thermal_gap 0.5)
				(thermal_bridge_width 0.5)
				(island_removal_mode 0)
			)
			(polygon
				(pts
					(xy 31.907988 -8.40359) (xy 31.907988 -1.79959) (xy 27.412188 -1.79959) (xy 27.412188 -8.40359)
				)
			)
		)
		(zone
			(layer "B.Cu")
			(hatch none 0.5)
			(connect_pads
				(clearance 0)
			)
			(min_thickness 0.25)
			(keepout
				(tracks not_allowed)
				(vias allowed)
				(pads allowed)
				(copperpour not_allowed)
				(footprints allowed)
			)
			(placement
				(enabled no)
				(sheetname "")
			)
			(fill
				(thermal_gap 0.5)
				(thermal_bridge_width 0.5)
				(island_removal_mode 0)
			)
			(polygon
				(pts
					(xy 31.340044 -0.350012) (xy 32.840168 -1.849882) (xy 32.840168 -8.20039) (xy 31.857188 -8.20039)
					(xy 31.857188 -1.85039) (xy 27.462988 -1.85039) (xy 27.462988 -8.20039) (xy 27.412188 -8.20039)
					(xy 27.412188 -1.79959) (xy 27.520392 -1.79959) (xy 28.96997 -0.350012)
				)
			)
		)
		(zone
			(layer "B.Cu")
			(hatch none 0.5)
			(connect_pads
				(clearance 0)
			)
			(min_thickness 0.25)
			(keepout
				(tracks not_allowed)
				(vias allowed)
				(pads allowed)
				(copperpour not_allowed)
				(footprints allowed)
			)
			(placement
				(enabled no)
				(sheetname "")
			)
			(fill
				(thermal_gap 0.5)
				(thermal_bridge_width 0.5)
				(island_removal_mode 0)
			)
			(polygon
				(pts
					(xy 25.270206 -0.350012) (xy 26.770076 -1.849882) (xy 26.770076 -6.902704) (xy 25.296622 -6.902704)
					(xy 25.296622 -6.851904) (xy 25.296622 -1.848104) (xy 24.483568 -1.848104) (xy 24.483568 -6.851904)
					(xy 24.483568 -6.902704) (xy 24.026622 -6.902704) (xy 24.026622 -6.851904) (xy 24.026622 -1.848104)
					(xy 23.213568 -1.848104) (xy 23.213568 -6.851904) (xy 23.213568 -6.902704) (xy 22.756622 -6.902704)
					(xy 22.756622 -6.851904) (xy 22.756622 -1.848104) (xy 21.943568 -1.848104) (xy 21.943568 -6.851904)
					(xy 21.943568 -6.902704) (xy 21.486622 -6.902704) (xy 21.486622 -6.851904) (xy 21.486622 -1.848104)
					(xy 20.673568 -1.848104) (xy 20.673568 -6.851904) (xy 20.673568 -6.902704) (xy 18.860008 -6.902704)
					(xy 18.860008 -1.849882) (xy 20.360132 -0.350012)
				)
			)
		)
	)
	(footprint ""
		(layer "B.Cu")
		(at 36.449 -64.837056 -90)
		(property "Reference" "PR45"
			(at 0 0 90)
			(layer "B.SilkS")
			(hide yes)
			(effects
				(font
					(size 1.27 1.27)
				)
				(justify mirror)
			)
		)
		(property "Value" ""
			(at 0 0 90)
			(layer "B.Fab")
			(effects
				(font
					(size 1.27 1.27)
				)
				(justify mirror)
			)
		)
		(duplicate_pad_numbers_are_jumpers no)
		(fp_line
			(start -0.7874 0.4064)
			(end 0.7874 0.4064)
			(stroke
				(width 0.1524)
				(type default)
			)
			(layer "B.SilkS")
		)
		(fp_line
			(start 0.7874 0.4064)
			(end 0.7874 -0.4064)
			(stroke
				(width 0.1524)
				(type default)
			)
			(layer "B.SilkS")
		)
		(fp_line
			(start -0.7874 -0.4064)
			(end -0.7874 0.4064)
			(stroke
				(width 0.1524)
				(type default)
			)
			(layer "B.SilkS")
		)
		(fp_line
			(start 0.7874 -0.4064)
			(end -0.7874 -0.4064)
			(stroke
				(width 0.1524)
				(type default)
			)
			(layer "B.SilkS")
		)
		(fp_line
			(start -0.67945 0.3048)
			(end -0.120396 0.3048)
			(stroke
				(width 0.1)
				(type default)
			)
			(layer "B.Fab")
		)
		(fp_line
			(start -0.120396 0.3048)
			(end -0.120396 0.2794)
			(stroke
				(width 0.1)
				(type default)
			)
			(layer "B.Fab")
		)
		(fp_line
			(start 0.12065 0.3048)
			(end 0.67945 0.3048)
			(stroke
				(width 0.1)
				(type default)
			)
			(layer "B.Fab")
		)
		(fp_line
			(start 0.67945 0.3048)
			(end 0.67945 -0.305054)
			(stroke
				(width 0.1)
				(type default)
			)
			(layer "B.Fab")
		)
		(fp_line
			(start -0.120396 0.2794)
			(end 0.12065 0.2794)
			(stroke
				(width 0.1)
				(type default)
			)
			(layer "B.Fab")
		)
		(fp_line
			(start 0.12065 0.2794)
			(end 0.12065 0.3048)
			(stroke
				(width 0.1)
				(type default)
			)
			(layer "B.Fab")
		)
		(fp_line
			(start -0.12065 -0.2794)
			(end -0.12065 -0.3048)
			(stroke
				(width 0.1)
				(type default)
			)
			(layer "B.Fab")
		)
		(fp_line
			(start 0.12065 -0.2794)
			(end -0.12065 -0.2794)
			(stroke
				(width 0.1)
				(type default)
			)
			(layer "B.Fab")
		)
		(fp_line
			(start -0.67945 -0.3048)
			(end -0.67945 0.3048)
			(stroke
				(width 0.1)
				(type default)
			)
			(layer "B.Fab")
		)
		(fp_line
			(start -0.12065 -0.3048)
			(end -0.67945 -0.3048)
			(stroke
				(width 0.1)
				(type default)
			)
			(layer "B.Fab")
		)
		(fp_line
			(start 0.12065 -0.305054)
			(end 0.12065 -0.2794)
			(stroke
				(width 0.1)
				(type default)
			)
			(layer "B.Fab")
		)
		(fp_line
			(start 0.67945 -0.305054)
			(end 0.12065 -0.305054)
			(stroke
				(width 0.1)
				(type default)
			)
			(layer "B.Fab")
		)
		(pad "1" smd circle
			(at 0.40005 0 90)
			(size 0 0)
			(layers "B.Cu" "B.Mask" "B.Paste")
			(net "FAN_3_CLREF")
		)
		(pad "2" smd circle
			(at -0.40005 0 90)
			(size 0 0)
			(layers "B.Cu" "B.Mask" "B.Paste")
			(net "GND")
		)
	)
	(footprint ""
		(layer "B.Cu")
		(at 39.365428 -67.494912 180)
		(property "Reference" "U74"
			(at -0.666242 1.693418 0)
			(unlocked yes)
			(layer "B.SilkS")
			(effects
				(font
					(size 0.7874 0.5842)
					(thickness 0.1524)
				)
				(justify mirror)
			)
		)
		(property "Value" ""
			(at 0 0 0)
			(layer "B.Fab")
			(effects
				(font
					(size 1.27 1.27)
				)
				(justify mirror)
			)
		)
		(duplicate_pad_numbers_are_jumpers no)
		(fp_line
			(start 1.7018 1.1176)
			(end 1.7018 -1.1176)
			(stroke
				(width 0.1524)
				(type default)
			)
			(layer "B.SilkS")
		)
		(fp_line
			(start 0.254 -1.1176)
			(end 1.7018 -1.1176)
			(stroke
				(width 0.1524)
				(type default)
			)
			(layer "B.SilkS")
		)
		(fp_line
			(start 0 -0.7112)
			(end 0.254 -1.1176)
			(stroke
				(width 0.1524)
				(type default)
			)
			(layer "B.SilkS")
		)
		(fp_line
			(start -0.254 -1.1176)
			(end 0 -0.7112)
			(stroke
				(width 0.1524)
				(type default)
			)
			(layer "B.SilkS")
		)
		(fp_line
			(start -1.7018 1.1176)
			(end 1.7018 1.1176)
			(stroke
				(width 0.1524)
				(type default)
			)
			(layer "B.SilkS")
		)
		(fp_line
			(start -1.7018 -1.1176)
			(end -0.254 -1.1176)
			(stroke
				(width 0.1524)
				(type default)
			)
			(layer "B.SilkS")
		)
		(fp_line
			(start -1.7018 -1.1176)
			(end -1.7018 1.1176)
			(stroke
				(width 0.1524)
				(type default)
			)
			(layer "B.SilkS")
		)
		(fp_poly
			(pts
				(xy 1.8161 -0.675386) (xy 2.4003 -0.446786) (xy 2.4003 -0.878586)
			)
			(stroke
				(width 0)
				(type default)
			)
			(fill yes)
			(layer "B.SilkS")
		)
		(fp_line
			(start 1.5494 1.1176)
			(end 1.5494 -1.1176)
			(stroke
				(width 0.1)
				(type default)
			)
			(layer "B.Fab")
		)
		(fp_line
			(start 0.254 -1.1176)
			(end 1.5494 -1.1176)
			(stroke
				(width 0.1)
				(type default)
			)
			(layer "B.Fab")
		)
		(fp_line
			(start -0.254 -1.1176)
			(end 0.254 -1.1176)
			(stroke
				(width 0.1)
				(type default)
			)
			(layer "B.Fab")
		)
		(fp_line
			(start -1.5494 1.1176)
			(end 1.5494 1.1176)
			(stroke
				(width 0.1)
				(type default)
			)
			(layer "B.Fab")
		)
		(fp_line
			(start -1.5494 -1.1176)
			(end -0.254 -1.1176)
			(stroke
				(width 0.1)
				(type default)
			)
			(layer "B.Fab")
		)
		(fp_line
			(start -1.5494 -1.1176)
			(end -1.5494 1.1176)
			(stroke
				(width 0.1)
				(type default)
			)
			(layer "B.Fab")
		)
		(fp_poly
			(pts
				(xy 1.8161 -0.675386) (xy 2.4003 -0.446786) (xy 2.4003 -0.878586)
			)
			(stroke
				(width 0)
				(type default)
			)
			(fill yes)
			(layer "B.Fab")
		)
		(pad "1" smd rect
			(at 0.962406 -0.649986 90)
			(size 0.3302 1.1684)
			(layers "B.Cu" "B.Mask" "B.Paste")
			(net "FAN_3_PRESENT_R")
		)
		(pad "2" smd rect
			(at 0.962406 0 90)
			(size 0.3302 1.1684)
			(layers "B.Cu" "B.Mask" "B.Paste")
			(net "P52V_FAN_3_BUFF_EN_R")
		)
		(pad "3" smd rect
			(at 0.962406 0.649986 90)
			(size 0.3302 1.1684)
			(layers "B.Cu" "B.Mask" "B.Paste")
			(net "GND")
		)
		(pad "4" smd rect
			(at -0.962406 0.649986 90)
			(size 0.3302 1.1684)
			(layers "B.Cu" "B.Mask" "B.Paste")
			(net "P52V_FAN_3_EN")
		)
		(pad "5" smd rect
			(at -0.962406 -0.649986 90)
			(size 0.3302 1.1684)
			(layers "B.Cu" "B.Mask" "B.Paste")
			(net "P3V3_AUX")
		)
	)
	(footprint ""
		(layer "B.Cu")
		(at 39.73068 -73.962768 90)
		(property "Reference" "PC32"
			(at 0 0 90)
			(layer "B.SilkS")
			(hide yes)
			(effects
				(font
					(size 1.27 1.27)
				)
				(justify mirror)
			)
		)
		(property "Value" ""
			(at 0 0 90)
			(layer "B.Fab")
			(effects
				(font
					(size 1.27 1.27)
				)
				(justify mirror)
			)
		)
		(duplicate_pad_numbers_are_jumpers no)
		(fp_line
			(start 0.7874 -0.4064)
			(end -0.7874 -0.4064)
			(stroke
				(width 0.1524)
				(type default)
			)
			(layer "B.SilkS")
		)
		(fp_line
			(start -0.7874 -0.4064)
			(end -0.7874 0.4064)
			(stroke
				(width 0.1524)
				(type default)
			)
			(layer "B.SilkS")
		)
		(fp_line
			(start 0.7874 0.4064)
			(end 0.7874 -0.4064)
			(stroke
				(width 0.1524)
				(type default)
			)
			(layer "B.SilkS")
		)
		(fp_line
			(start -0.7874 0.4064)
			(end 0.7874 0.4064)
			(stroke
				(width 0.1524)
				(type default)
			)
			(layer "B.SilkS")
		)
		(fp_line
			(start 0.67945 -0.305054)
			(end 0.12065 -0.305054)
			(stroke
				(width 0.1)
				(type default)
			)
			(layer "B.Fab")
		)
		(fp_line
			(start 0.12065 -0.305054)
			(end 0.12065 -0.2794)
			(stroke
				(width 0.1)
				(type default)
			)
			(layer "B.Fab")
		)
		(fp_line
			(start -0.12065 -0.3048)
			(end -0.67945 -0.3048)
			(stroke
				(width 0.1)
				(type default)
			)
			(layer "B.Fab")
		)
		(fp_line
			(start -0.67945 -0.3048)
			(end -0.67945 0.3048)
			(stroke
				(width 0.1)
				(type default)
			)
			(layer "B.Fab")
		)
		(fp_line
			(start 0.12065 -0.2794)
			(end -0.12065 -0.2794)
			(stroke
				(width 0.1)
				(type default)
			)
			(layer "B.Fab")
		)
		(fp_line
			(start -0.12065 -0.2794)
			(end -0.12065 -0.3048)
			(stroke
				(width 0.1)
				(type default)
			)
			(layer "B.Fab")
		)
		(fp_line
			(start 0.12065 0.2794)
			(end 0.12065 0.3048)
			(stroke
				(width 0.1)
				(type default)
			)
			(layer "B.Fab")
		)
		(fp_line
			(start -0.120396 0.2794)
			(end 0.12065 0.2794)
			(stroke
				(width 0.1)
				(type default)
			)
			(layer "B.Fab")
		)
		(fp_line
			(start 0.67945 0.3048)
			(end 0.67945 -0.305054)
			(stroke
				(width 0.1)
				(type default)
			)
			(layer "B.Fab")
		)
		(fp_line
			(start 0.12065 0.3048)
			(end 0.67945 0.3048)
			(stroke
				(width 0.1)
				(type default)
			)
			(layer "B.Fab")
		)
		(fp_line
			(start -0.120396 0.3048)
			(end -0.120396 0.2794)
			(stroke
				(width 0.1)
				(type default)
			)
			(layer "B.Fab")
		)
		(fp_line
			(start -0.67945 0.3048)
			(end -0.120396 0.3048)
			(stroke
				(width 0.1)
				(type default)
			)
			(layer "B.Fab")
		)
		(pad "1" smd circle
			(at 0.40005 0 270)
			(size 0 0)
			(layers "B.Cu" "B.Mask" "B.Paste")
			(net "FAN_2_P5V")
		)
		(pad "2" smd circle
			(at -0.40005 0 270)
			(size 0 0)
			(layers "B.Cu" "B.Mask" "B.Paste")
			(net "GND")
		)
	)
	(footprint ""
		(layer "B.Cu")
		(at 5.550154 -53.062124)
		(property "Reference" "PC37"
			(at 0 0 0)
			(layer "B.SilkS")
			(hide yes)
			(effects
				(font
					(size 1.27 1.27)
				)
				(justify mirror)
			)
		)
		(property "Value" ""
			(at 0 0 0)
			(layer "B.Fab")
			(effects
				(font
					(size 1.27 1.27)
				)
				(justify mirror)
			)
		)
		(duplicate_pad_numbers_are_jumpers no)
		(fp_line
			(start -1.524 -0.762)
			(end -1.524 0.762)
			(stroke
				(width 0.1524)
				(type default)
			)
			(layer "B.SilkS")
		)
		(fp_line
			(start -1.524 0.762)
			(end 1.524 0.762)
			(stroke
				(width 0.1524)
				(type default)
			)
			(layer "B.SilkS")
		)
		(fp_line
			(start 1.524 -0.762)
			(end -1.524 -0.762)
			(stroke
				(width 0.1524)
				(type default)
			)
			(layer "B.SilkS")
		)
		(fp_line
			(start 1.524 0.762)
			(end 1.524 -0.762)
			(stroke
				(width 0.1524)
				(type default)
			)
			(layer "B.SilkS")
		)
		(fp_line
			(start -1.1049 -0.724916)
			(end 1.1049 -0.724916)
			(stroke
				(width 0.1)
				(type default)
			)
			(layer "B.Fab")
		)
		(fp_line
			(start -1.1049 0.724916)
			(end -1.1049 -0.724916)
			(stroke
				(width 0.1)
				(type default)
			)
			(layer "B.Fab")
		)
		(fp_line
			(start 1.1049 -0.724916)
			(end 1.1049 0.724916)
			(stroke
				(width 0.1)
				(type default)
			)
			(layer "B.Fab")
		)
		(fp_line
			(start 1.1049 0.724916)
			(end -1.1049 0.724916)
			(stroke
				(width 0.1)
				(type default)
			)
			(layer "B.Fab")
		)
		(pad "1" smd rect
			(at 0.889 0)
			(size 1.016 1.27)
			(layers "B.Cu" "B.Mask" "B.Paste")
			(net "P52V_FAN_4")
		)
		(pad "2" smd rect
			(at -0.889 0)
			(size 1.016 1.27)
			(layers "B.Cu" "B.Mask" "B.Paste")
			(net "GND")
		)
	)
	(footprint ""
		(layer "B.Cu")
		(at 42.164 -250.23699 -90)
		(property "Reference" "PC2119"
			(at 0 0 90)
			(layer "B.SilkS")
			(hide yes)
			(effects
				(font
					(size 1.27 1.27)
				)
				(justify mirror)
			)
		)
		(property "Value" ""
			(at 0 0 90)
			(layer "B.Fab")
			(effects
				(font
					(size 1.27 1.27)
				)
				(justify mirror)
			)
		)
		(duplicate_pad_numbers_are_jumpers no)
		(fp_line
			(start -0.7874 0.4064)
			(end 0.7874 0.4064)
			(stroke
				(width 0.1524)
				(type default)
			)
			(layer "B.SilkS")
		)
		(fp_line
			(start 0.7874 0.4064)
			(end 0.7874 -0.4064)
			(stroke
				(width 0.1524)
				(type default)
			)
			(layer "B.SilkS")
		)
		(fp_line
			(start -0.7874 -0.4064)
			(end -0.7874 0.4064)
			(stroke
				(width 0.1524)
				(type default)
			)
			(layer "B.SilkS")
		)
		(fp_line
			(start 0.7874 -0.4064)
			(end -0.7874 -0.4064)
			(stroke
				(width 0.1524)
				(type default)
			)
			(layer "B.SilkS")
		)
		(fp_line
			(start -0.67945 0.3048)
			(end -0.120396 0.3048)
			(stroke
				(width 0.1)
				(type default)
			)
			(layer "B.Fab")
		)
		(fp_line
			(start -0.120396 0.3048)
			(end -0.120396 0.2794)
			(stroke
				(width 0.1)
				(type default)
			)
			(layer "B.Fab")
		)
		(fp_line
			(start 0.12065 0.3048)
			(end 0.67945 0.3048)
			(stroke
				(width 0.1)
				(type default)
			)
			(layer "B.Fab")
		)
		(fp_line
			(start 0.67945 0.3048)
			(end 0.67945 -0.305054)
			(stroke
				(width 0.1)
				(type default)
			)
			(layer "B.Fab")
		)
		(fp_line
			(start -0.120396 0.2794)
			(end 0.12065 0.2794)
			(stroke
				(width 0.1)
				(type default)
			)
			(layer "B.Fab")
		)
		(fp_line
			(start 0.12065 0.2794)
			(end 0.12065 0.3048)
			(stroke
				(width 0.1)
				(type default)
			)
			(layer "B.Fab")
		)
		(fp_line
			(start -0.12065 -0.2794)
			(end -0.12065 -0.3048)
			(stroke
				(width 0.1)
				(type default)
			)
			(layer "B.Fab")
		)
		(fp_line
			(start 0.12065 -0.2794)
			(end -0.12065 -0.2794)
			(stroke
				(width 0.1)
				(type default)
			)
			(layer "B.Fab")
		)
		(fp_line
			(start -0.67945 -0.3048)
			(end -0.67945 0.3048)
			(stroke
				(width 0.1)
				(type default)
			)
			(layer "B.Fab")
		)
		(fp_line
			(start -0.12065 -0.3048)
			(end -0.67945 -0.3048)
			(stroke
				(width 0.1)
				(type default)
			)
			(layer "B.Fab")
		)
		(fp_line
			(start 0.12065 -0.305054)
			(end 0.12065 -0.2794)
			(stroke
				(width 0.1)
				(type default)
			)
			(layer "B.Fab")
		)
		(fp_line
			(start 0.67945 -0.305054)
			(end 0.12065 -0.305054)
			(stroke
				(width 0.1)
				(type default)
			)
			(layer "B.Fab")
		)
		(pad "1" smd circle
			(at 0.40005 0 90)
			(size 0 0)
			(layers "B.Cu" "B.Mask" "B.Paste")
			(net "FAN_1_TEMP")
		)
		(pad "2" smd circle
			(at -0.40005 0 90)
			(size 0 0)
			(layers "B.Cu" "B.Mask" "B.Paste")
			(net "GND")
		)
	)
	(footprint ""
		(layer "B.Cu")
		(at 14.097 -73.971912 -90)
		(property "Reference" "PC3123"
			(at 0 0 90)
			(layer "B.SilkS")
			(hide yes)
			(effects
				(font
					(size 1.27 1.27)
				)
				(justify mirror)
			)
		)
		(property "Value" ""
			(at 0 0 90)
			(layer "B.Fab")
			(effects
				(font
					(size 1.27 1.27)
				)
				(justify mirror)
			)
		)
		(duplicate_pad_numbers_are_jumpers no)
		(fp_line
			(start -0.7874 0.4064)
			(end 0.7874 0.4064)
			(stroke
				(width 0.1524)
				(type default)
			)
			(layer "B.SilkS")
		)
		(fp_line
			(start 0.7874 0.4064)
			(end 0.7874 -0.4064)
			(stroke
				(width 0.1524)
				(type default)
			)
			(layer "B.SilkS")
		)
		(fp_line
			(start -0.7874 -0.4064)
			(end -0.7874 0.4064)
			(stroke
				(width 0.1524)
				(type default)
			)
			(layer "B.SilkS")
		)
		(fp_line
			(start 0.7874 -0.4064)
			(end -0.7874 -0.4064)
			(stroke
				(width 0.1524)
				(type default)
			)
			(layer "B.SilkS")
		)
		(fp_line
			(start -0.67945 0.3048)
			(end -0.120396 0.3048)
			(stroke
				(width 0.1)
				(type default)
			)
			(layer "B.Fab")
		)
		(fp_line
			(start -0.120396 0.3048)
			(end -0.120396 0.2794)
			(stroke
				(width 0.1)
				(type default)
			)
			(layer "B.Fab")
		)
		(fp_line
			(start 0.12065 0.3048)
			(end 0.67945 0.3048)
			(stroke
				(width 0.1)
				(type default)
			)
			(layer "B.Fab")
		)
		(fp_line
			(start 0.67945 0.3048)
			(end 0.67945 -0.305054)
			(stroke
				(width 0.1)
				(type default)
			)
			(layer "B.Fab")
		)
		(fp_line
			(start -0.120396 0.2794)
			(end 0.12065 0.2794)
			(stroke
				(width 0.1)
				(type default)
			)
			(layer "B.Fab")
		)
		(fp_line
			(start 0.12065 0.2794)
			(end 0.12065 0.3048)
			(stroke
				(width 0.1)
				(type default)
			)
			(layer "B.Fab")
		)
		(fp_line
			(start -0.12065 -0.2794)
			(end -0.12065 -0.3048)
			(stroke
				(width 0.1)
				(type default)
			)
			(layer "B.Fab")
		)
		(fp_line
			(start 0.12065 -0.2794)
			(end -0.12065 -0.2794)
			(stroke
				(width 0.1)
				(type default)
			)
			(layer "B.Fab")
		)
		(fp_line
			(start -0.67945 -0.3048)
			(end -0.67945 0.3048)
			(stroke
				(width 0.1)
				(type default)
			)
			(layer "B.Fab")
		)
		(fp_line
			(start -0.12065 -0.3048)
			(end -0.67945 -0.3048)
			(stroke
				(width 0.1)
				(type default)
			)
			(layer "B.Fab")
		)
		(fp_line
			(start 0.12065 -0.305054)
			(end 0.12065 -0.2794)
			(stroke
				(width 0.1)
				(type default)
			)
			(layer "B.Fab")
		)
		(fp_line
			(start 0.67945 -0.305054)
			(end 0.12065 -0.305054)
			(stroke
				(width 0.1)
				(type default)
			)
			(layer "B.Fab")
		)
		(pad "1" smd circle
			(at 0.40005 0 90)
			(size 0 0)
			(layers "B.Cu" "B.Mask" "B.Paste")
			(net "GND")
		)
		(pad "2" smd circle
			(at -0.40005 0 90)
			(size 0 0)
			(layers "B.Cu" "B.Mask" "B.Paste")
			(net "FAN_5_CLREF")
		)
	)
	(footprint ""
		(layer "B.Cu")
		(at 44.667932 -255.778 -90)
		(property "Reference" "U394"
			(at 1.651 -2.930398 270)
			(unlocked yes)
			(layer "B.SilkS")
			(effects
				(font
					(size 0.7874 0.5842)
					(thickness 0.1524)
				)
				(justify left mirror)
			)
		)
		(property "Value" ""
			(at 0 0 90)
			(layer "B.Fab")
			(effects
				(font
					(size 1.27 1.27)
				)
				(justify mirror)
			)
		)
		(duplicate_pad_numbers_are_jumpers no)
		(fp_line
			(start -1.3462 1.1938)
			(end -1.3462 -1.1938)
			(stroke
				(width 0.1524)
				(type default)
			)
			(layer "B.SilkS")
		)
		(fp_line
			(start 1.3462 1.1938)
			(end -1.3462 1.1938)
			(stroke
				(width 0.1524)
				(type default)
			)
			(layer "B.SilkS")
		)
		(fp_line
			(start -1.3462 -1.1938)
			(end 1.3462 -1.1938)
			(stroke
				(width 0.1524)
				(type default)
			)
			(layer "B.SilkS")
		)
		(fp_line
			(start 1.3462 -1.1938)
			(end 1.3462 1.1684)
			(stroke
				(width 0.1524)
				(type default)
			)
			(layer "B.SilkS")
		)
		(fp_poly
			(pts
				(xy 1.447038 -0.760476) (xy 2.052066 -0.457962) (xy 2.052066 -1.06299)
			)
			(stroke
				(width 0)
				(type default)
			)
			(fill yes)
			(layer "B.SilkS")
		)
		(fp_line
			(start -0.674878 1.124966)
			(end -0.674878 -1.124966)
			(stroke
				(width 0.1)
				(type default)
			)
			(layer "B.Fab")
		)
		(fp_line
			(start 0.674878 1.124966)
			(end -0.674878 1.124966)
			(stroke
				(width 0.1)
				(type default)
			)
			(layer "B.Fab")
		)
		(fp_line
			(start -0.674878 -1.124966)
			(end 0.674878 -1.124966)
			(stroke
				(width 0.1)
				(type default)
			)
			(layer "B.Fab")
		)
		(fp_line
			(start 0.674878 -1.124966)
			(end 0.674878 1.124966)
			(stroke
				(width 0.1)
				(type default)
			)
			(layer "B.Fab")
		)
		(fp_poly
			(pts
				(xy 1.447038 -0.760476) (xy 2.052066 -0.457962) (xy 2.052066 -1.06299)
			)
			(stroke
				(width 0)
				(type default)
			)
			(fill yes)
			(layer "B.Fab")
		)
		(pad "1" smd rect
			(at 0.899922 -0.750062 90)
			(size 0.6096 0.6096)
			(layers "B.Cu" "B.Mask" "B.Paste")
			(net "NC_U394_P1")
		)
		(pad "2" smd rect
			(at 0.899922 0)
			(size 0.4064 0.6096)
			(layers "B.Cu" "B.Mask" "B.Paste")
			(net "FAN_0_PRSNT_BUF_N")
		)
		(pad "3" smd rect
			(at 0.899922 0.750062 90)
			(size 0.6096 0.6096)
			(layers "B.Cu" "B.Mask" "B.Paste")
			(net "GND")
		)
		(pad "4" smd rect
			(at -0.899922 0.750062 90)
			(size 0.6096 0.6096)
			(layers "B.Cu" "B.Mask" "B.Paste")
			(net "FAN_0_PRESENT")
		)
		(pad "5" smd rect
			(at -0.899922 -0.750062 90)
			(size 0.6096 0.6096)
			(layers "B.Cu" "B.Mask" "B.Paste")
			(net "P3V3_AUX")
		)
	)
	(footprint ""
		(layer "B.Cu")
		(at 16.002 -314.198)
		(property "Reference" ""
			(at 0 0 0)
			(layer "B.SilkS")
			(hide yes)
			(effects
				(font
					(size 1.27 1.27)
				)
				(justify mirror)
			)
		)
		(property "Value" ""
			(at 0 0 0)
			(layer "B.Fab")
			(effects
				(font
					(size 1.27 1.27)
				)
				(justify mirror)
			)
		)
		(duplicate_pad_numbers_are_jumpers no)
		(pad "1" smd circle
			(at 0 0 180)
			(size 0.9906 0.9906)
			(layers "B.Cu" "B.Mask" "B.Paste")
			(net "Net_123")
		)
		(zone
			(layer "B.Cu")
			(hatch none 0.5)
			(connect_pads
				(clearance 0)
			)
			(min_thickness 0.25)
			(keepout
				(tracks not_allowed)
				(vias allowed)
				(pads allowed)
				(copperpour not_allowed)
				(footprints allowed)
			)
			(placement
				(enabled no)
				(sheetname "")
			)
			(fill
				(thermal_gap 0.5)
				(thermal_bridge_width 0.5)
				(island_removal_mode 0)
			)
			(polygon
				(pts
					(arc
						(start 17.6276 -314.198)
						(mid 14.3764 -314.198)
						(end 17.6276 -314.198)
					)
				)
			)
		)
	)
	(footprint ""
		(layer "B.Cu")
		(at 44.45 -73.971912 90)
		(property "Reference" "PC34"
			(at 0 0 90)
			(layer "B.SilkS")
			(hide yes)
			(effects
				(font
					(size 1.27 1.27)
				)
				(justify mirror)
			)
		)
		(property "Value" ""
			(at 0 0 90)
			(layer "B.Fab")
			(effects
				(font
					(size 1.27 1.27)
				)
				(justify mirror)
			)
		)
		(duplicate_pad_numbers_are_jumpers no)
		(fp_line
			(start 0.7874 -0.4064)
			(end -0.7874 -0.4064)
			(stroke
				(width 0.1524)
				(type default)
			)
			(layer "B.SilkS")
		)
		(fp_line
			(start -0.7874 -0.4064)
			(end -0.7874 0.4064)
			(stroke
				(width 0.1524)
				(type default)
			)
			(layer "B.SilkS")
		)
		(fp_line
			(start 0.7874 0.4064)
			(end 0.7874 -0.4064)
			(stroke
				(width 0.1524)
				(type default)
			)
			(layer "B.SilkS")
		)
		(fp_line
			(start -0.7874 0.4064)
			(end 0.7874 0.4064)
			(stroke
				(width 0.1524)
				(type default)
			)
			(layer "B.SilkS")
		)
		(fp_line
			(start 0.67945 -0.305054)
			(end 0.12065 -0.305054)
			(stroke
				(width 0.1)
				(type default)
			)
			(layer "B.Fab")
		)
		(fp_line
			(start 0.12065 -0.305054)
			(end 0.12065 -0.2794)
			(stroke
				(width 0.1)
				(type default)
			)
			(layer "B.Fab")
		)
		(fp_line
			(start -0.12065 -0.3048)
			(end -0.67945 -0.3048)
			(stroke
				(width 0.1)
				(type default)
			)
			(layer "B.Fab")
		)
		(fp_line
			(start -0.67945 -0.3048)
			(end -0.67945 0.3048)
			(stroke
				(width 0.1)
				(type default)
			)
			(layer "B.Fab")
		)
		(fp_line
			(start 0.12065 -0.2794)
			(end -0.12065 -0.2794)
			(stroke
				(width 0.1)
				(type default)
			)
			(layer "B.Fab")
		)
		(fp_line
			(start -0.12065 -0.2794)
			(end -0.12065 -0.3048)
			(stroke
				(width 0.1)
				(type default)
			)
			(layer "B.Fab")
		)
		(fp_line
			(start 0.12065 0.2794)
			(end 0.12065 0.3048)
			(stroke
				(width 0.1)
				(type default)
			)
			(layer "B.Fab")
		)
		(fp_line
			(start -0.120396 0.2794)
			(end 0.12065 0.2794)
			(stroke
				(width 0.1)
				(type default)
			)
			(layer "B.Fab")
		)
		(fp_line
			(start 0.67945 0.3048)
			(end 0.67945 -0.305054)
			(stroke
				(width 0.1)
				(type default)
			)
			(layer "B.Fab")
		)
		(fp_line
			(start 0.12065 0.3048)
			(end 0.67945 0.3048)
			(stroke
				(width 0.1)
				(type default)
			)
			(layer "B.Fab")
		)
		(fp_line
			(start -0.120396 0.3048)
			(end -0.120396 0.2794)
			(stroke
				(width 0.1)
				(type default)
			)
			(layer "B.Fab")
		)
		(fp_line
			(start -0.67945 0.3048)
			(end -0.120396 0.3048)
			(stroke
				(width 0.1)
				(type default)
			)
			(layer "B.Fab")
		)
		(pad "1" smd circle
			(at 0.40005 0 270)
			(size 0 0)
			(layers "B.Cu" "B.Mask" "B.Paste")
			(net "FAN_2_TIMER")
		)
		(pad "2" smd circle
			(at -0.40005 0 270)
			(size 0 0)
			(layers "B.Cu" "B.Mask" "B.Paste")
			(net "GND")
		)
	)
	(footprint ""
		(layer "B.Cu")
		(at 5.900166 -243.595144)
		(property "Reference" "PU8"
			(at 3.789934 4.315714 0)
			(unlocked yes)
			(layer "B.SilkS")
			(effects
				(font
					(size 0.7874 0.5842)
					(thickness 0.1524)
				)
				(justify left mirror)
			)
		)
		(property "Value" ""
			(at 0 0 0)
			(layer "B.Fab")
			(effects
				(font
					(size 1.27 1.27)
				)
				(justify mirror)
			)
		)
		(duplicate_pad_numbers_are_jumpers no)
		(fp_line
			(start -2.549906 -2.549906)
			(end -2.4384 -2.549906)
			(stroke
				(width 0.1524)
				(type default)
			)
			(layer "B.SilkS")
		)
		(fp_line
			(start -2.549906 -2.2352)
			(end -2.549906 -2.549906)
			(stroke
				(width 0.1524)
				(type default)
			)
			(layer "B.SilkS")
		)
		(fp_line
			(start -2.549906 -1.4986)
			(end -2.549906 -1.7526)
			(stroke
				(width 0.1524)
				(type default)
			)
			(layer "B.SilkS")
		)
		(fp_line
			(start -2.549906 -0.6858)
			(end -2.549906 -0.9144)
			(stroke
				(width 0.1524)
				(type default)
			)
			(layer "B.SilkS")
		)
		(fp_line
			(start -2.549906 0.9144)
			(end -2.549906 -0.1016)
			(stroke
				(width 0.1524)
				(type default)
			)
			(layer "B.SilkS")
		)
		(fp_line
			(start -2.549906 1.7526)
			(end -2.549906 1.4986)
			(stroke
				(width 0.1524)
				(type default)
			)
			(layer "B.SilkS")
		)
		(fp_line
			(start -2.549906 2.549906)
			(end -2.549906 2.2352)
			(stroke
				(width 0.1524)
				(type default)
			)
			(layer "B.SilkS")
		)
		(fp_line
			(start -2.4384 2.549906)
			(end -2.549906 2.549906)
			(stroke
				(width 0.1524)
				(type default)
			)
			(layer "B.SilkS")
		)
		(fp_line
			(start -2.199894 2.9464)
			(end -2.199894 3.4544)
			(stroke
				(width 0.1524)
				(type default)
			)
			(layer "B.SilkS")
		)
		(fp_line
			(start -1.800098 -3.9624)
			(end -1.800098 -2.9464)
			(stroke
				(width 0.1524)
				(type default)
			)
			(layer "B.SilkS")
		)
		(fp_line
			(start -0.199898 2.9464)
			(end -0.199898 3.9624)
			(stroke
				(width 0.1524)
				(type default)
			)
			(layer "B.SilkS")
		)
		(fp_line
			(start 0.199898 -3.4544)
			(end 0.199898 -2.9464)
			(stroke
				(width 0.1524)
				(type default)
			)
			(layer "B.SilkS")
		)
		(fp_line
			(start 1.800098 2.9464)
			(end 1.800098 3.4544)
			(stroke
				(width 0.1524)
				(type default)
			)
			(layer "B.SilkS")
		)
		(fp_line
			(start 2.199894 -3.9624)
			(end 2.199894 -2.9464)
			(stroke
				(width 0.1524)
				(type default)
			)
			(layer "B.SilkS")
		)
		(fp_line
			(start 2.4384 -2.549906)
			(end 2.549906 -2.549906)
			(stroke
				(width 0.1524)
				(type default)
			)
			(layer "B.SilkS")
		)
		(fp_line
			(start 2.549906 -2.549906)
			(end 2.549906 -2.2352)
			(stroke
				(width 0.1524)
				(type default)
			)
			(layer "B.SilkS")
		)
		(fp_line
			(start 2.549906 -1.7526)
			(end 2.549906 -1.4986)
			(stroke
				(width 0.1524)
				(type default)
			)
			(layer "B.SilkS")
		)
		(fp_line
			(start 2.549906 -0.9144)
			(end 2.549906 0.1016)
			(stroke
				(width 0.1524)
				(type default)
			)
			(layer "B.SilkS")
		)
		(fp_line
			(start 2.549906 0.6858)
			(end 2.549906 0.9144)
			(stroke
				(width 0.1524)
				(type default)
			)
			(layer "B.SilkS")
		)
		(fp_line
			(start 2.549906 1.4986)
			(end 2.549906 1.7526)
			(stroke
				(width 0.1524)
				(type default)
			)
			(layer "B.SilkS")
		)
		(fp_line
			(start 2.549906 2.2352)
			(end 2.549906 2.549906)
			(stroke
				(width 0.1524)
				(type default)
			)
			(layer "B.SilkS")
		)
		(fp_line
			(start 2.549906 2.549906)
			(end 2.4384 2.549906)
			(stroke
				(width 0.1524)
				(type default)
			)
			(layer "B.SilkS")
		)
		(fp_poly
			(pts
				(xy 3.523234 -1.491996) (xy 2.939034 -1.199896) (xy 3.523234 -0.907796)
			)
			(stroke
				(width 0)
				(type default)
			)
			(fill yes)
			(layer "B.SilkS")
		)
		(fp_line
			(start -2.549906 -2.549906)
			(end 2.549906 -2.549906)
			(stroke
				(width 0.1)
				(type default)
			)
			(layer "B.Fab")
		)
		(fp_line
			(start -2.549906 2.549906)
			(end -2.549906 -2.549906)
			(stroke
				(width 0.1)
				(type default)
			)
			(layer "B.Fab")
		)
		(fp_line
			(start -2.199894 2.9464)
			(end -2.199894 3.4544)
			(stroke
				(width 0.1)
				(type default)
			)
			(layer "B.Fab")
		)
		(fp_line
			(start -1.800098 -3.9624)
			(end -1.800098 -2.9464)
			(stroke
				(width 0.1)
				(type default)
			)
			(layer "B.Fab")
		)
		(fp_line
			(start -0.199898 2.9464)
			(end -0.199898 3.9624)
			(stroke
				(width 0.1)
				(type default)
			)
			(layer "B.Fab")
		)
		(fp_line
			(start 0.199898 -3.4544)
			(end 0.199898 -2.9464)
			(stroke
				(width 0.1)
				(type default)
			)
			(layer "B.Fab")
		)
		(fp_line
			(start 1.800098 2.9464)
			(end 1.800098 3.4544)
			(stroke
				(width 0.1)
				(type default)
			)
			(layer "B.Fab")
		)
		(fp_line
			(start 2.199894 -3.9624)
			(end 2.199894 -2.9464)
			(stroke
				(width 0.1)
				(type default)
			)
			(layer "B.Fab")
		)
		(fp_line
			(start 2.549906 -2.549906)
			(end 2.549906 2.549906)
			(stroke
				(width 0.1)
				(type default)
			)
			(layer "B.Fab")
		)
		(fp_line
			(start 2.549906 2.549906)
			(end -2.549906 2.549906)
			(stroke
				(width 0.1)
				(type default)
			)
			(layer "B.Fab")
		)
		(fp_poly
			(pts
				(xy 3.7084 -1.584706) (xy 2.939034 -1.199896) (xy 3.7084 -0.81534)
			)
			(stroke
				(width 0)
				(type default)
			)
			(fill yes)
			(layer "B.Fab")
		)
		(fp_text user "18"
			(at -3.617976 -1.080516 270)
			(unlocked yes)
			(layer "B.SilkS")
			(effects
				(font
					(size 0.635 0.4064)
					(thickness 0.1524)
				)
				(justify mirror)
			)
		)
		(fp_text user "16"
			(at -3.329432 1.2192 270)
			(unlocked yes)
			(layer "B.SilkS")
			(effects
				(font
					(size 0.635 0.4064)
					(thickness 0.1524)
				)
				(justify mirror)
			)
		)
		(fp_text user "15"
			(at -2.8956 3.126232 0)
			(unlocked yes)
			(layer "B.SilkS")
			(effects
				(font
					(size 0.635 0.4064)
					(thickness 0.1524)
				)
				(justify mirror)
			)
		)
		(fp_text user "19"
			(at -2.8448 -3.096768 0)
			(unlocked yes)
			(layer "B.SilkS")
			(effects
				(font
					(size 0.635 0.4064)
					(thickness 0.1524)
				)
				(justify mirror)
			)
		)
		(fp_text user "4"
			(at 2.6416 3.151632 0)
			(unlocked yes)
			(layer "B.SilkS")
			(effects
				(font
					(size 0.635 0.4064)
					(thickness 0.1524)
				)
				(justify mirror)
			)
		)
		(fp_text user "30"
			(at 2.9464 -3.045968 0)
			(unlocked yes)
			(layer "B.SilkS")
			(effects
				(font
					(size 0.635 0.4064)
					(thickness 0.1524)
				)
				(justify mirror)
			)
		)
		(fp_text user "3"
			(at 3.299968 1.1938 270)
			(unlocked yes)
			(layer "B.SilkS")
			(effects
				(font
					(size 0.635 0.4064)
					(thickness 0.1524)
				)
				(justify mirror)
			)
		)
		(fp_text user "16"
			(at -3.329432 1.2192 270)
			(unlocked yes)
			(layer "B.Fab")
			(effects
				(font
					(size 0.635 0.4064)
					(thickness 0.1524)
				)
				(justify mirror)
			)
		)
		(fp_text user "18"
			(at -3.304032 -1.2192 270)
			(unlocked yes)
			(layer "B.Fab")
			(effects
				(font
					(size 0.635 0.4064)
					(thickness 0.1524)
				)
				(justify mirror)
			)
		)
		(fp_text user "15"
			(at -2.8956 3.126232 0)
			(unlocked yes)
			(layer "B.Fab")
			(effects
				(font
					(size 0.635 0.4064)
					(thickness 0.1524)
				)
				(justify mirror)
			)
		)
		(fp_text user "19"
			(at -2.8448 -3.096768 0)
			(unlocked yes)
			(layer "B.Fab")
			(effects
				(font
					(size 0.635 0.4064)
					(thickness 0.1524)
				)
				(justify mirror)
			)
		)
		(fp_text user "4"
			(at 2.6416 3.151632 0)
			(unlocked yes)
			(layer "B.Fab")
			(effects
				(font
					(size 0.635 0.4064)
					(thickness 0.1524)
				)
				(justify mirror)
			)
		)
		(fp_text user "30"
			(at 2.9464 -3.045968 0)
			(unlocked yes)
			(layer "B.Fab")
			(effects
				(font
					(size 0.635 0.4064)
					(thickness 0.1524)
				)
				(justify mirror)
			)
		)
		(fp_text user "3"
			(at 3.299968 1.1938 270)
			(unlocked yes)
			(layer "B.Fab")
			(effects
				(font
					(size 0.635 0.4064)
					(thickness 0.1524)
				)
				(justify mirror)
			)
		)
		(pad "1" smd circle
			(at 1.599946 -1.199896 270)
			(size 0 0)
			(layers "B.Cu" "B.Mask" "B.Paste")
			(net "P52V_HSC")
		)
		(pad "2" smd rect
			(at 1.549908 0.40005 90)
			(size 0.3048 2.5146)
			(layers "B.Cu" "B.Mask" "B.Paste")
			(net "P52V_HSC")
		)
		(pad "3" smd rect
			(at 1.549908 1.199896 90)
			(size 0.3048 2.5146)
			(layers "B.Cu" "B.Mask" "B.Paste")
			(net "P52V_FAN_6")
		)
		(pad "4" smd circle
			(at 2.199894 2.350008)
			(size 0 0)
			(layers "B.Cu" "B.Mask" "B.Paste")
			(net "P52V_FAN_6")
		)
		(pad "5" smd rect
			(at 1.800098 2.350008 180)
			(size 0.1778 0.9144)
			(layers "B.Cu" "B.Mask" "B.Paste")
			(net "P52V_FAN_6")
		)
		(pad "6" smd rect
			(at 1.400048 2.350008 180)
			(size 0.1778 0.9144)
			(layers "B.Cu" "B.Mask" "B.Paste")
			(net "P52V_FAN_6")
		)
		(pad "7" smd rect
			(at 0.999998 2.350008 180)
			(size 0.1778 0.9144)
			(layers "B.Cu" "B.Mask" "B.Paste")
			(net "P52V_FAN_6")
		)
		(pad "8" smd rect
			(at 0.599948 2.350008 180)
			(size 0.1778 0.9144)
			(layers "B.Cu" "B.Mask" "B.Paste")
			(net "P52V_FAN_6")
		)
		(pad "9" smd rect
			(at 0.199898 2.350008 180)
			(size 0.1778 0.9144)
			(layers "B.Cu" "B.Mask" "B.Paste")
			(net "P52V_FAN_6")
		)
		(pad "10" smd rect
			(at -0.199898 2.350008 180)
			(size 0.1778 0.9144)
			(layers "B.Cu" "B.Mask" "B.Paste")
			(net "P52V_FAN_6")
		)
		(pad "11" smd rect
			(at -0.599948 2.350008 180)
			(size 0.1778 0.9144)
			(layers "B.Cu" "B.Mask" "B.Paste")
			(net "P52V_FAN_6")
		)
		(pad "12" smd rect
			(at -0.999998 2.350008 180)
			(size 0.1778 0.9144)
			(layers "B.Cu" "B.Mask" "B.Paste")
			(net "P52V_FAN_6")
		)
		(pad "13" smd rect
			(at -1.400048 2.350008 180)
			(size 0.1778 0.9144)
			(layers "B.Cu" "B.Mask" "B.Paste")
			(net "P52V_FAN_6")
		)
		(pad "14" smd rect
			(at -1.800098 2.350008 180)
			(size 0.1778 0.9144)
			(layers "B.Cu" "B.Mask" "B.Paste")
			(net "P52V_FAN_6")
		)
		(pad "15" smd circle
			(at -2.199894 2.350008)
			(size 0 0)
			(layers "B.Cu" "B.Mask" "B.Paste")
			(net "P52V_FAN_6")
		)
		(pad "16" smd rect
			(at -1.549908 1.199896 90)
			(size 0.3048 2.5146)
			(layers "B.Cu" "B.Mask" "B.Paste")
			(net "P52V_FAN_6")
		)
		(pad "17" smd rect
			(at -1.549908 -0.40005 90)
			(size 0.3048 2.5146)
			(layers "B.Cu" "B.Mask" "B.Paste")
			(net "P52V_FAN_6")
		)
		(pad "18" smd rect
			(at -1.549908 -1.199896 90)
			(size 0.3048 2.5146)
			(layers "B.Cu" "B.Mask" "B.Paste")
			(net "P52V_HSC")
		)
		(pad "19" smd circle
			(at -2.199894 -2.350008 180)
			(size 0 0)
			(layers "B.Cu" "B.Mask" "B.Paste")
			(net "FAN_6_CS")
		)
		(pad "20" smd rect
			(at -1.800098 -2.350008 180)
			(size 0.1778 0.9144)
			(layers "B.Cu" "B.Mask" "B.Paste")
			(net "FAN_6_IMON")
		)
		(pad "21" smd rect
			(at -1.400048 -2.350008 180)
			(size 0.1778 0.9144)
			(layers "B.Cu" "B.Mask" "B.Paste")
			(net "FAN_6_SS")
		)
		(pad "22" smd rect
			(at -0.999998 -2.350008 180)
			(size 0.1778 0.9144)
			(layers "B.Cu" "B.Mask" "B.Paste")
			(net "FAN_6_FAULT")
		)
		(pad "23" smd rect
			(at -0.599948 -2.350008 180)
			(size 0.1778 0.9144)
			(layers "B.Cu" "B.Mask" "B.Paste")
			(net "FAN_6_TIMER")
		)
		(pad "24" smd rect
			(at -0.199898 -2.350008 180)
			(size 0.1778 0.9144)
			(layers "B.Cu" "B.Mask" "B.Paste")
			(net "FAN_6_CLREF")
		)
		(pad "25" smd rect
			(at 0.199898 -2.350008 180)
			(size 0.1778 0.9144)
			(layers "B.Cu" "B.Mask" "B.Paste")
			(net "GND")
		)
		(pad "26" smd rect
			(at 0.599948 -2.350008 180)
			(size 0.1778 0.9144)
			(layers "B.Cu" "B.Mask" "B.Paste")
			(net "FAN_6_ON")
		)
		(pad "27" smd rect
			(at 0.999998 -2.350008 180)
			(size 0.1778 0.9144)
			(layers "B.Cu" "B.Mask" "B.Paste")
			(net "FAN_6_P3V_R")
		)
		(pad "28" smd rect
			(at 1.400048 -2.350008 180)
			(size 0.1778 0.9144)
			(layers "B.Cu" "B.Mask" "B.Paste")
			(net "FAN_6_P5V")
		)
		(pad "29" smd rect
			(at 1.800098 -2.350008 180)
			(size 0.1778 0.9144)
			(layers "B.Cu" "B.Mask" "B.Paste")
			(net "FAN_6_TEMP")
		)
		(pad "30" smd circle
			(at 2.199894 -2.350008 180)
			(size 0 0)
			(layers "B.Cu" "B.Mask" "B.Paste")
			(net "FAN_6_MODE")
		)
	)
	(footprint ""
		(layer "B.Cu")
		(at 2.794 -64.837056 90)
		(property "Reference" "PR54"
			(at 0 0 90)
			(layer "B.SilkS")
			(hide yes)
			(effects
				(font
					(size 1.27 1.27)
				)
				(justify mirror)
			)
		)
		(property "Value" ""
			(at 0 0 90)
			(layer "B.Fab")
			(effects
				(font
					(size 1.27 1.27)
				)
				(justify mirror)
			)
		)
		(duplicate_pad_numbers_are_jumpers no)
		(fp_line
			(start 0.7874 -0.4064)
			(end -0.7874 -0.4064)
			(stroke
				(width 0.1524)
				(type default)
			)
			(layer "B.SilkS")
		)
		(fp_line
			(start -0.7874 -0.4064)
			(end -0.7874 0.4064)
			(stroke
				(width 0.1524)
				(type default)
			)
			(layer "B.SilkS")
		)
		(fp_line
			(start 0.7874 0.4064)
			(end 0.7874 -0.4064)
			(stroke
				(width 0.1524)
				(type default)
			)
			(layer "B.SilkS")
		)
		(fp_line
			(start -0.7874 0.4064)
			(end 0.7874 0.4064)
			(stroke
				(width 0.1524)
				(type default)
			)
			(layer "B.SilkS")
		)
		(fp_line
			(start 0.67945 -0.305054)
			(end 0.12065 -0.305054)
			(stroke
				(width 0.1)
				(type default)
			)
			(layer "B.Fab")
		)
		(fp_line
			(start 0.12065 -0.305054)
			(end 0.12065 -0.2794)
			(stroke
				(width 0.1)
				(type default)
			)
			(layer "B.Fab")
		)
		(fp_line
			(start -0.12065 -0.3048)
			(end -0.67945 -0.3048)
			(stroke
				(width 0.1)
				(type default)
			)
			(layer "B.Fab")
		)
		(fp_line
			(start -0.67945 -0.3048)
			(end -0.67945 0.3048)
			(stroke
				(width 0.1)
				(type default)
			)
			(layer "B.Fab")
		)
		(fp_line
			(start 0.12065 -0.2794)
			(end -0.12065 -0.2794)
			(stroke
				(width 0.1)
				(type default)
			)
			(layer "B.Fab")
		)
		(fp_line
			(start -0.12065 -0.2794)
			(end -0.12065 -0.3048)
			(stroke
				(width 0.1)
				(type default)
			)
			(layer "B.Fab")
		)
		(fp_line
			(start 0.12065 0.2794)
			(end 0.12065 0.3048)
			(stroke
				(width 0.1)
				(type default)
			)
			(layer "B.Fab")
		)
		(fp_line
			(start -0.120396 0.2794)
			(end 0.12065 0.2794)
			(stroke
				(width 0.1)
				(type default)
			)
			(layer "B.Fab")
		)
		(fp_line
			(start 0.67945 0.3048)
			(end 0.67945 -0.305054)
			(stroke
				(width 0.1)
				(type default)
			)
			(layer "B.Fab")
		)
		(fp_line
			(start 0.12065 0.3048)
			(end 0.67945 0.3048)
			(stroke
				(width 0.1)
				(type default)
			)
			(layer "B.Fab")
		)
		(fp_line
			(start -0.120396 0.3048)
			(end -0.120396 0.2794)
			(stroke
				(width 0.1)
				(type default)
			)
			(layer "B.Fab")
		)
		(fp_line
			(start -0.67945 0.3048)
			(end -0.120396 0.3048)
			(stroke
				(width 0.1)
				(type default)
			)
			(layer "B.Fab")
		)
		(pad "1" smd circle
			(at 0.40005 0 270)
			(size 0 0)
			(layers "B.Cu" "B.Mask" "B.Paste")
			(net "GND")
		)
		(pad "2" smd circle
			(at -0.40005 0 270)
			(size 0 0)
			(layers "B.Cu" "B.Mask" "B.Paste")
			(net "FAN_4_IMON")
		)
	)
	(footprint ""
		(layer "B.Cu")
		(at 41.12768 -250.23699 -90)
		(property "Reference" "PR32"
			(at 0 0 90)
			(layer "B.SilkS")
			(hide yes)
			(effects
				(font
					(size 1.27 1.27)
				)
				(justify mirror)
			)
		)
		(property "Value" ""
			(at 0 0 90)
			(layer "B.Fab")
			(effects
				(font
					(size 1.27 1.27)
				)
				(justify mirror)
			)
		)
		(duplicate_pad_numbers_are_jumpers no)
		(fp_line
			(start -0.7874 0.4064)
			(end 0.7874 0.4064)
			(stroke
				(width 0.1524)
				(type default)
			)
			(layer "B.SilkS")
		)
		(fp_line
			(start 0.7874 0.4064)
			(end 0.7874 -0.4064)
			(stroke
				(width 0.1524)
				(type default)
			)
			(layer "B.SilkS")
		)
		(fp_line
			(start -0.7874 -0.4064)
			(end -0.7874 0.4064)
			(stroke
				(width 0.1524)
				(type default)
			)
			(layer "B.SilkS")
		)
		(fp_line
			(start 0.7874 -0.4064)
			(end -0.7874 -0.4064)
			(stroke
				(width 0.1524)
				(type default)
			)
			(layer "B.SilkS")
		)
		(fp_line
			(start -0.67945 0.3048)
			(end -0.120396 0.3048)
			(stroke
				(width 0.1)
				(type default)
			)
			(layer "B.Fab")
		)
		(fp_line
			(start -0.120396 0.3048)
			(end -0.120396 0.2794)
			(stroke
				(width 0.1)
				(type default)
			)
			(layer "B.Fab")
		)
		(fp_line
			(start 0.12065 0.3048)
			(end 0.67945 0.3048)
			(stroke
				(width 0.1)
				(type default)
			)
			(layer "B.Fab")
		)
		(fp_line
			(start 0.67945 0.3048)
			(end 0.67945 -0.305054)
			(stroke
				(width 0.1)
				(type default)
			)
			(layer "B.Fab")
		)
		(fp_line
			(start -0.120396 0.2794)
			(end 0.12065 0.2794)
			(stroke
				(width 0.1)
				(type default)
			)
			(layer "B.Fab")
		)
		(fp_line
			(start 0.12065 0.2794)
			(end 0.12065 0.3048)
			(stroke
				(width 0.1)
				(type default)
			)
			(layer "B.Fab")
		)
		(fp_line
			(start -0.12065 -0.2794)
			(end -0.12065 -0.3048)
			(stroke
				(width 0.1)
				(type default)
			)
			(layer "B.Fab")
		)
		(fp_line
			(start 0.12065 -0.2794)
			(end -0.12065 -0.2794)
			(stroke
				(width 0.1)
				(type default)
			)
			(layer "B.Fab")
		)
		(fp_line
			(start -0.67945 -0.3048)
			(end -0.67945 0.3048)
			(stroke
				(width 0.1)
				(type default)
			)
			(layer "B.Fab")
		)
		(fp_line
			(start -0.12065 -0.3048)
			(end -0.67945 -0.3048)
			(stroke
				(width 0.1)
				(type default)
			)
			(layer "B.Fab")
		)
		(fp_line
			(start 0.12065 -0.305054)
			(end 0.12065 -0.2794)
			(stroke
				(width 0.1)
				(type default)
			)
			(layer "B.Fab")
		)
		(fp_line
			(start 0.67945 -0.305054)
			(end 0.12065 -0.305054)
			(stroke
				(width 0.1)
				(type default)
			)
			(layer "B.Fab")
		)
		(pad "1" smd circle
			(at 0.40005 0 90)
			(size 0 0)
			(layers "B.Cu" "B.Mask" "B.Paste")
			(net "FAN_1_TEMP")
		)
		(pad "2" smd circle
			(at -0.40005 0 90)
			(size 0 0)
			(layers "B.Cu" "B.Mask" "B.Paste")
			(net "GND")
		)
	)
	(footprint ""
		(layer "B.Cu")
		(at 16.2052 -88.449912 180)
		(property "Reference" "C2111"
			(at 0 0 0)
			(layer "B.SilkS")
			(hide yes)
			(effects
				(font
					(size 1.27 1.27)
				)
				(justify mirror)
			)
		)
		(property "Value" ""
			(at 0 0 0)
			(layer "B.Fab")
			(effects
				(font
					(size 1.27 1.27)
				)
				(justify mirror)
			)
		)
		(duplicate_pad_numbers_are_jumpers no)
		(fp_line
			(start 2.2098 0.9398)
			(end 2.2098 -0.9398)
			(stroke
				(width 0.1524)
				(type default)
			)
			(layer "B.SilkS")
		)
		(fp_line
			(start 2.2098 -0.9398)
			(end -2.2098 -0.9398)
			(stroke
				(width 0.1524)
				(type default)
			)
			(layer "B.SilkS")
		)
		(fp_line
			(start -2.2098 0.9398)
			(end 2.2098 0.9398)
			(stroke
				(width 0.1524)
				(type default)
			)
			(layer "B.SilkS")
		)
		(fp_line
			(start -2.2098 -0.9398)
			(end -2.2098 0.9398)
			(stroke
				(width 0.1524)
				(type default)
			)
			(layer "B.SilkS")
		)
		(fp_line
			(start 1.700022 0.899922)
			(end 1.700022 -0.899922)
			(stroke
				(width 0.1)
				(type default)
			)
			(layer "B.Fab")
		)
		(fp_line
			(start 1.700022 -0.899922)
			(end -1.700022 -0.899922)
			(stroke
				(width 0.1)
				(type default)
			)
			(layer "B.Fab")
		)
		(fp_line
			(start -1.700022 0.899922)
			(end 1.700022 0.899922)
			(stroke
				(width 0.1)
				(type default)
			)
			(layer "B.Fab")
		)
		(fp_line
			(start -1.700022 -0.899922)
			(end -1.700022 0.899922)
			(stroke
				(width 0.1)
				(type default)
			)
			(layer "B.Fab")
		)
		(pad "1" smd rect
			(at 1.4732 0 180)
			(size 1.1684 1.5748)
			(layers "B.Cu" "B.Mask" "B.Paste")
			(net "P52V_FAN_5")
		)
		(pad "2" smd rect
			(at -1.4732 0 180)
			(size 1.1684 1.5748)
			(layers "B.Cu" "B.Mask" "B.Paste")
			(net "GND")
		)
	)
	(footprint ""
		(layer "B.Cu")
		(at 43.434 -73.971912 90)
		(property "Reference" "PR41"
			(at 0 0 90)
			(layer "B.SilkS")
			(hide yes)
			(effects
				(font
					(size 1.27 1.27)
				)
				(justify mirror)
			)
		)
		(property "Value" ""
			(at 0 0 90)
			(layer "B.Fab")
			(effects
				(font
					(size 1.27 1.27)
				)
				(justify mirror)
			)
		)
		(duplicate_pad_numbers_are_jumpers no)
		(fp_line
			(start 0.7874 -0.4064)
			(end -0.7874 -0.4064)
			(stroke
				(width 0.1524)
				(type default)
			)
			(layer "B.SilkS")
		)
		(fp_line
			(start -0.7874 -0.4064)
			(end -0.7874 0.4064)
			(stroke
				(width 0.1524)
				(type default)
			)
			(layer "B.SilkS")
		)
		(fp_line
			(start 0.7874 0.4064)
			(end 0.7874 -0.4064)
			(stroke
				(width 0.1524)
				(type default)
			)
			(layer "B.SilkS")
		)
		(fp_line
			(start -0.7874 0.4064)
			(end 0.7874 0.4064)
			(stroke
				(width 0.1524)
				(type default)
			)
			(layer "B.SilkS")
		)
		(fp_line
			(start 0.67945 -0.305054)
			(end 0.12065 -0.305054)
			(stroke
				(width 0.1)
				(type default)
			)
			(layer "B.Fab")
		)
		(fp_line
			(start 0.12065 -0.305054)
			(end 0.12065 -0.2794)
			(stroke
				(width 0.1)
				(type default)
			)
			(layer "B.Fab")
		)
		(fp_line
			(start -0.12065 -0.3048)
			(end -0.67945 -0.3048)
			(stroke
				(width 0.1)
				(type default)
			)
			(layer "B.Fab")
		)
		(fp_line
			(start -0.67945 -0.3048)
			(end -0.67945 0.3048)
			(stroke
				(width 0.1)
				(type default)
			)
			(layer "B.Fab")
		)
		(fp_line
			(start 0.12065 -0.2794)
			(end -0.12065 -0.2794)
			(stroke
				(width 0.1)
				(type default)
			)
			(layer "B.Fab")
		)
		(fp_line
			(start -0.12065 -0.2794)
			(end -0.12065 -0.3048)
			(stroke
				(width 0.1)
				(type default)
			)
			(layer "B.Fab")
		)
		(fp_line
			(start 0.12065 0.2794)
			(end 0.12065 0.3048)
			(stroke
				(width 0.1)
				(type default)
			)
			(layer "B.Fab")
		)
		(fp_line
			(start -0.120396 0.2794)
			(end 0.12065 0.2794)
			(stroke
				(width 0.1)
				(type default)
			)
			(layer "B.Fab")
		)
		(fp_line
			(start 0.67945 0.3048)
			(end 0.67945 -0.305054)
			(stroke
				(width 0.1)
				(type default)
			)
			(layer "B.Fab")
		)
		(fp_line
			(start 0.12065 0.3048)
			(end 0.67945 0.3048)
			(stroke
				(width 0.1)
				(type default)
			)
			(layer "B.Fab")
		)
		(fp_line
			(start -0.120396 0.3048)
			(end -0.120396 0.2794)
			(stroke
				(width 0.1)
				(type default)
			)
			(layer "B.Fab")
		)
		(fp_line
			(start -0.67945 0.3048)
			(end -0.120396 0.3048)
			(stroke
				(width 0.1)
				(type default)
			)
			(layer "B.Fab")
		)
		(pad "1" smd circle
			(at 0.40005 0 270)
			(size 0 0)
			(layers "B.Cu" "B.Mask" "B.Paste")
			(net "FAN_2_CLREF")
		)
		(pad "2" smd circle
			(at -0.40005 0 270)
			(size 0 0)
			(layers "B.Cu" "B.Mask" "B.Paste")
			(net "GND")
		)
	)
	(footprint ""
		(layer "B.Cu")
		(at 37.465 -258.572 90)
		(property "Reference" "PC2118"
			(at 0 0 90)
			(layer "B.SilkS")
			(hide yes)
			(effects
				(font
					(size 1.27 1.27)
				)
				(justify mirror)
			)
		)
		(property "Value" ""
			(at 0 0 90)
			(layer "B.Fab")
			(effects
				(font
					(size 1.27 1.27)
				)
				(justify mirror)
			)
		)
		(duplicate_pad_numbers_are_jumpers no)
		(fp_line
			(start 0.7874 -0.4064)
			(end -0.7874 -0.4064)
			(stroke
				(width 0.1524)
				(type default)
			)
			(layer "B.SilkS")
		)
		(fp_line
			(start -0.7874 -0.4064)
			(end -0.7874 0.4064)
			(stroke
				(width 0.1524)
				(type default)
			)
			(layer "B.SilkS")
		)
		(fp_line
			(start 0.7874 0.4064)
			(end 0.7874 -0.4064)
			(stroke
				(width 0.1524)
				(type default)
			)
			(layer "B.SilkS")
		)
		(fp_line
			(start -0.7874 0.4064)
			(end 0.7874 0.4064)
			(stroke
				(width 0.1524)
				(type default)
			)
			(layer "B.SilkS")
		)
		(fp_line
			(start 0.67945 -0.305054)
			(end 0.12065 -0.305054)
			(stroke
				(width 0.1)
				(type default)
			)
			(layer "B.Fab")
		)
		(fp_line
			(start 0.12065 -0.305054)
			(end 0.12065 -0.2794)
			(stroke
				(width 0.1)
				(type default)
			)
			(layer "B.Fab")
		)
		(fp_line
			(start -0.12065 -0.3048)
			(end -0.67945 -0.3048)
			(stroke
				(width 0.1)
				(type default)
			)
			(layer "B.Fab")
		)
		(fp_line
			(start -0.67945 -0.3048)
			(end -0.67945 0.3048)
			(stroke
				(width 0.1)
				(type default)
			)
			(layer "B.Fab")
		)
		(fp_line
			(start 0.12065 -0.2794)
			(end -0.12065 -0.2794)
			(stroke
				(width 0.1)
				(type default)
			)
			(layer "B.Fab")
		)
		(fp_line
			(start -0.12065 -0.2794)
			(end -0.12065 -0.3048)
			(stroke
				(width 0.1)
				(type default)
			)
			(layer "B.Fab")
		)
		(fp_line
			(start 0.12065 0.2794)
			(end 0.12065 0.3048)
			(stroke
				(width 0.1)
				(type default)
			)
			(layer "B.Fab")
		)
		(fp_line
			(start -0.120396 0.2794)
			(end 0.12065 0.2794)
			(stroke
				(width 0.1)
				(type default)
			)
			(layer "B.Fab")
		)
		(fp_line
			(start 0.67945 0.3048)
			(end 0.67945 -0.305054)
			(stroke
				(width 0.1)
				(type default)
			)
			(layer "B.Fab")
		)
		(fp_line
			(start 0.12065 0.3048)
			(end 0.67945 0.3048)
			(stroke
				(width 0.1)
				(type default)
			)
			(layer "B.Fab")
		)
		(fp_line
			(start -0.120396 0.3048)
			(end -0.120396 0.2794)
			(stroke
				(width 0.1)
				(type default)
			)
			(layer "B.Fab")
		)
		(fp_line
			(start -0.67945 0.3048)
			(end -0.120396 0.3048)
			(stroke
				(width 0.1)
				(type default)
			)
			(layer "B.Fab")
		)
		(pad "1" smd circle
			(at 0.40005 0 270)
			(size 0 0)
			(layers "B.Cu" "B.Mask" "B.Paste")
			(net "FAN_0_TEMP")
		)
		(pad "2" smd circle
			(at -0.40005 0 270)
			(size 0 0)
			(layers "B.Cu" "B.Mask" "B.Paste")
			(net "GND")
		)
	)
	(footprint ""
		(layer "B.Cu")
		(at 40.894 -130.048 180)
		(property "Reference" "R5430"
			(at 0 0 0)
			(layer "B.SilkS")
			(hide yes)
			(effects
				(font
					(size 1.27 1.27)
				)
				(justify mirror)
			)
		)
		(property "Value" ""
			(at 0 0 0)
			(layer "B.Fab")
			(effects
				(font
					(size 1.27 1.27)
				)
				(justify mirror)
			)
		)
		(duplicate_pad_numbers_are_jumpers no)
		(fp_line
			(start 0.7874 0.4064)
			(end 0.7874 -0.4064)
			(stroke
				(width 0.1524)
				(type default)
			)
			(layer "B.SilkS")
		)
		(fp_line
			(start 0.7874 -0.4064)
			(end -0.7874 -0.4064)
			(stroke
				(width 0.1524)
				(type default)
			)
			(layer "B.SilkS")
		)
		(fp_line
			(start -0.7874 0.4064)
			(end 0.7874 0.4064)
			(stroke
				(width 0.1524)
				(type default)
			)
			(layer "B.SilkS")
		)
		(fp_line
			(start -0.7874 -0.4064)
			(end -0.7874 0.4064)
			(stroke
				(width 0.1524)
				(type default)
			)
			(layer "B.SilkS")
		)
		(fp_line
			(start 0.67945 0.3048)
			(end 0.67945 -0.305054)
			(stroke
				(width 0.1)
				(type default)
			)
			(layer "B.Fab")
		)
		(fp_line
			(start 0.67945 -0.305054)
			(end 0.12065 -0.305054)
			(stroke
				(width 0.1)
				(type default)
			)
			(layer "B.Fab")
		)
		(fp_line
			(start 0.12065 0.3048)
			(end 0.67945 0.3048)
			(stroke
				(width 0.1)
				(type default)
			)
			(layer "B.Fab")
		)
		(fp_line
			(start 0.12065 0.2794)
			(end 0.12065 0.3048)
			(stroke
				(width 0.1)
				(type default)
			)
			(layer "B.Fab")
		)
		(fp_line
			(start 0.12065 -0.2794)
			(end -0.12065 -0.2794)
			(stroke
				(width 0.1)
				(type default)
			)
			(layer "B.Fab")
		)
		(fp_line
			(start 0.12065 -0.305054)
			(end 0.12065 -0.2794)
			(stroke
				(width 0.1)
				(type default)
			)
			(layer "B.Fab")
		)
		(fp_line
			(start -0.120396 0.3048)
			(end -0.120396 0.2794)
			(stroke
				(width 0.1)
				(type default)
			)
			(layer "B.Fab")
		)
		(fp_line
			(start -0.120396 0.2794)
			(end 0.12065 0.2794)
			(stroke
				(width 0.1)
				(type default)
			)
			(layer "B.Fab")
		)
		(fp_line
			(start -0.12065 -0.2794)
			(end -0.12065 -0.3048)
			(stroke
				(width 0.1)
				(type default)
			)
			(layer "B.Fab")
		)
		(fp_line
			(start -0.12065 -0.3048)
			(end -0.67945 -0.3048)
			(stroke
				(width 0.1)
				(type default)
			)
			(layer "B.Fab")
		)
		(fp_line
			(start -0.67945 0.3048)
			(end -0.120396 0.3048)
			(stroke
				(width 0.1)
				(type default)
			)
			(layer "B.Fab")
		)
		(fp_line
			(start -0.67945 -0.3048)
			(end -0.67945 0.3048)
			(stroke
				(width 0.1)
				(type default)
			)
			(layer "B.Fab")
		)
		(pad "1" smd rect
			(at 0.40005 0 180)
			(size 0.4572 0.508)
			(layers "B.Cu" "B.Mask" "B.Paste")
			(net "FAN_2_TACH_IL")
		)
		(pad "2" smd rect
			(at -0.40005 0 180)
			(size 0.4572 0.508)
			(layers "B.Cu" "B.Mask" "B.Paste")
			(net "GND")
		)
	)
	(footprint ""
		(layer "B.Cu")
		(at 1.651 -249.428 -90)
		(property "Reference" "PR66"
			(at 0 0 90)
			(layer "B.SilkS")
			(hide yes)
			(effects
				(font
					(size 1.27 1.27)
				)
				(justify mirror)
			)
		)
		(property "Value" ""
			(at 0 0 90)
			(layer "B.Fab")
			(effects
				(font
					(size 1.27 1.27)
				)
				(justify mirror)
			)
		)
		(duplicate_pad_numbers_are_jumpers no)
		(fp_line
			(start -0.7874 0.4064)
			(end 0.7874 0.4064)
			(stroke
				(width 0.1524)
				(type default)
			)
			(layer "B.SilkS")
		)
		(fp_line
			(start 0.7874 0.4064)
			(end 0.7874 -0.4064)
			(stroke
				(width 0.1524)
				(type default)
			)
			(layer "B.SilkS")
		)
		(fp_line
			(start -0.7874 -0.4064)
			(end -0.7874 0.4064)
			(stroke
				(width 0.1524)
				(type default)
			)
			(layer "B.SilkS")
		)
		(fp_line
			(start 0.7874 -0.4064)
			(end -0.7874 -0.4064)
			(stroke
				(width 0.1524)
				(type default)
			)
			(layer "B.SilkS")
		)
		(fp_line
			(start -0.67945 0.3048)
			(end -0.120396 0.3048)
			(stroke
				(width 0.1)
				(type default)
			)
			(layer "B.Fab")
		)
		(fp_line
			(start -0.120396 0.3048)
			(end -0.120396 0.2794)
			(stroke
				(width 0.1)
				(type default)
			)
			(layer "B.Fab")
		)
		(fp_line
			(start 0.12065 0.3048)
			(end 0.67945 0.3048)
			(stroke
				(width 0.1)
				(type default)
			)
			(layer "B.Fab")
		)
		(fp_line
			(start 0.67945 0.3048)
			(end 0.67945 -0.305054)
			(stroke
				(width 0.1)
				(type default)
			)
			(layer "B.Fab")
		)
		(fp_line
			(start -0.120396 0.2794)
			(end 0.12065 0.2794)
			(stroke
				(width 0.1)
				(type default)
			)
			(layer "B.Fab")
		)
		(fp_line
			(start 0.12065 0.2794)
			(end 0.12065 0.3048)
			(stroke
				(width 0.1)
				(type default)
			)
			(layer "B.Fab")
		)
		(fp_line
			(start -0.12065 -0.2794)
			(end -0.12065 -0.3048)
			(stroke
				(width 0.1)
				(type default)
			)
			(layer "B.Fab")
		)
		(fp_line
			(start 0.12065 -0.2794)
			(end -0.12065 -0.2794)
			(stroke
				(width 0.1)
				(type default)
			)
			(layer "B.Fab")
		)
		(fp_line
			(start -0.67945 -0.3048)
			(end -0.67945 0.3048)
			(stroke
				(width 0.1)
				(type default)
			)
			(layer "B.Fab")
		)
		(fp_line
			(start -0.12065 -0.3048)
			(end -0.67945 -0.3048)
			(stroke
				(width 0.1)
				(type default)
			)
			(layer "B.Fab")
		)
		(fp_line
			(start 0.12065 -0.305054)
			(end 0.12065 -0.2794)
			(stroke
				(width 0.1)
				(type default)
			)
			(layer "B.Fab")
		)
		(fp_line
			(start 0.67945 -0.305054)
			(end 0.12065 -0.305054)
			(stroke
				(width 0.1)
				(type default)
			)
			(layer "B.Fab")
		)
		(pad "1" smd circle
			(at 0.40005 0 90)
			(size 0 0)
			(layers "B.Cu" "B.Mask" "B.Paste")
			(net "FAN_6_CS")
		)
		(pad "2" smd circle
			(at -0.40005 0 90)
			(size 0 0)
			(layers "B.Cu" "B.Mask" "B.Paste")
			(net "GND")
		)
	)
	(footprint ""
		(layer "B.Cu")
		(at 6.700012 -197.01002 180)
		(property "Reference" "J7"
			(at 2.763012 19.24431 0)
			(unlocked yes)
			(layer "B.SilkS")
			(effects
				(font
					(size 0.7874 0.5842)
					(thickness 0.1524)
				)
				(justify left mirror)
			)
		)
		(property "Value" ""
			(at 0 0 0)
			(layer "B.Fab")
			(effects
				(font
					(size 1.27 1.27)
				)
				(justify mirror)
			)
		)
		(duplicate_pad_numbers_are_jumpers no)
		(fp_line
			(start 4.350004 18.524982)
			(end -6.35 18.524982)
			(stroke
				(width 0.1524)
				(type default)
			)
			(layer "B.SilkS")
		)
		(fp_line
			(start 4.350004 -4.52501)
			(end 4.350004 18.524982)
			(stroke
				(width 0.1524)
				(type default)
			)
			(layer "B.SilkS")
		)
		(fp_line
			(start 1.249934 15.424912)
			(end -3.24993 15.424912)
			(stroke
				(width 0.1524)
				(type default)
			)
			(layer "B.SilkS")
		)
		(fp_line
			(start 1.249934 8.200136)
			(end 4.350004 8.200136)
			(stroke
				(width 0.1524)
				(type default)
			)
			(layer "B.SilkS")
		)
		(fp_line
			(start 1.249934 8.200136)
			(end 1.249934 15.424912)
			(stroke
				(width 0.1524)
				(type default)
			)
			(layer "B.SilkS")
		)
		(fp_line
			(start 1.249934 5.799836)
			(end 4.350004 5.799836)
			(stroke
				(width 0.1524)
				(type default)
			)
			(layer "B.SilkS")
		)
		(fp_line
			(start 1.249934 -1.42494)
			(end 1.249934 5.799836)
			(stroke
				(width 0.1524)
				(type default)
			)
			(layer "B.SilkS")
		)
		(fp_line
			(start -0.029972 -1.42494)
			(end 1.249934 -1.42494)
			(stroke
				(width 0.1524)
				(type default)
			)
			(layer "B.SilkS")
		)
		(fp_line
			(start -3.24993 15.424912)
			(end -3.24993 -1.42494)
			(stroke
				(width 0.1524)
				(type default)
			)
			(layer "B.SilkS")
		)
		(fp_line
			(start -3.24993 -1.42494)
			(end -1.96977 -1.42494)
			(stroke
				(width 0.1524)
				(type default)
			)
			(layer "B.SilkS")
		)
		(fp_line
			(start -6.35 18.524982)
			(end -6.35 -4.52501)
			(stroke
				(width 0.1524)
				(type default)
			)
			(layer "B.SilkS")
		)
		(fp_line
			(start -6.35 -4.52501)
			(end 4.350004 -4.52501)
			(stroke
				(width 0.1524)
				(type default)
			)
			(layer "B.SilkS")
		)
		(fp_poly
			(pts
				(xy 5.527802 -0.508) (xy 5.527802 0.508) (xy 4.511802 0)
			)
			(stroke
				(width 0)
				(type default)
			)
			(fill yes)
			(layer "B.SilkS")
		)
		(fp_line
			(start 4.350004 18.524982)
			(end -6.35 18.524982)
			(stroke
				(width 0.1)
				(type default)
			)
			(layer "B.Fab")
		)
		(fp_line
			(start 4.350004 -4.52501)
			(end 4.350004 18.524982)
			(stroke
				(width 0.1)
				(type default)
			)
			(layer "B.Fab")
		)
		(fp_line
			(start -6.35 18.524982)
			(end -6.35 -4.52501)
			(stroke
				(width 0.1)
				(type default)
			)
			(layer "B.Fab")
		)
		(fp_line
			(start -6.35 -4.52501)
			(end 4.350004 -4.52501)
			(stroke
				(width 0.1)
				(type default)
			)
			(layer "B.Fab")
		)
		(fp_poly
			(pts
				(xy 5.527802 -0.508) (xy 5.527802 0.508) (xy 4.511802 0)
			)
			(stroke
				(width 0)
				(type default)
			)
			(fill yes)
			(layer "B.Fab")
		)
		(pad "" np_thru_hole circle
			(at -0.999998 -1.89992 90)
			(size 1.4986 1.4986)
			(drill 1.4986)
			(layers "*.Cu" "*.Mask")
			(clearance 0.381)
			(thermal_gap 0.381)
		)
		(pad "1" thru_hole rect
			(at 0 0 90)
			(size 1.3716 1.3716)
			(drill 0.9652)
			(layers "*.Cu" "*.Mask")
			(remove_unused_layers no)
			(net "FAN_6_TACH_IL_D")
			(clearance 0.0508)
			(padstack
				(mode front_inner_back)
				(layer "Inner"
					(shape circle)
					(size 1.3716 1.3716)
					(clearance 0.0508)
				)
				(layer "B.Cu"
					(shape rect)
					(size 1.3716 1.3716)
					(thermal_gap 0.0508)
					(clearance 0.0508)
				)
			)
		)
		(pad "2" thru_hole circle
			(at -1.999996 0 90)
			(size 1.3716 1.3716)
			(drill 0.9652)
			(layers "*.Cu" "*.Mask")
			(remove_unused_layers no)
			(net "FAN_6_PWM_OL_R")
			(clearance 0.0508)
			(thermal_gap 0.0508)
		)
		(pad "3" thru_hole circle
			(at 0 1.999996 90)
			(size 1.3716 1.3716)
			(drill 0.9652)
			(layers "*.Cu" "*.Mask")
			(remove_unused_layers no)
			(net "FAN_6_PWM_IL_R")
			(clearance 0.0508)
			(thermal_gap 0.0508)
		)
		(pad "4" thru_hole circle
			(at -1.999996 1.999996 90)
			(size 1.3716 1.3716)
			(drill 0.9652)
			(layers "*.Cu" "*.Mask")
			(remove_unused_layers no)
			(net "FAN_6_PRESENT_R_N")
			(clearance 0.0508)
			(thermal_gap 0.0508)
		)
		(pad "5" thru_hole circle
			(at 0 3.999992 90)
			(size 1.3716 1.3716)
			(drill 0.9652)
			(layers "*.Cu" "*.Mask")
			(remove_unused_layers no)
			(net "P12V_LED_R1_FAN6")
			(clearance 0.0508)
			(thermal_gap 0.0508)
		)
		(pad "6" thru_hole circle
			(at -1.999996 3.999992 90)
			(size 1.3716 1.3716)
			(drill 0.9652)
			(layers "*.Cu" "*.Mask")
			(remove_unused_layers no)
			(net "SMB_FAN6_SCL_R")
			(clearance 0.0508)
			(thermal_gap 0.0508)
		)
		(pad "7" thru_hole circle
			(at 0 5.999988 90)
			(size 1.3716 1.3716)
			(drill 0.9652)
			(layers "*.Cu" "*.Mask")
			(remove_unused_layers no)
			(net "SMB_FAN6_SDA_R")
			(clearance 0.0508)
			(thermal_gap 0.0508)
		)
		(pad "8" thru_hole circle
			(at -1.999996 5.999988 90)
			(size 1.3716 1.3716)
			(drill 0.9652)
			(layers "*.Cu" "*.Mask")
			(remove_unused_layers no)
			(net "GND")
			(clearance 0.0508)
			(thermal_gap 0.0508)
		)
		(pad "9" thru_hole circle
			(at 0 7.999984 90)
			(size 1.3716 1.3716)
			(drill 0.9652)
			(layers "*.Cu" "*.Mask")
			(remove_unused_layers no)
			(net "GND")
			(clearance 0.0508)
			(thermal_gap 0.0508)
		)
		(pad "10" thru_hole circle
			(at -1.999996 7.999984 90)
			(size 1.3716 1.3716)
			(drill 0.9652)
			(layers "*.Cu" "*.Mask")
			(remove_unused_layers no)
			(net "P52V_FAN_6")
			(clearance 0.0508)
			(thermal_gap 0.0508)
		)
		(pad "11" thru_hole circle
			(at 0 9.99998 90)
			(size 1.3716 1.3716)
			(drill 0.9652)
			(layers "*.Cu" "*.Mask")
			(remove_unused_layers no)
			(net "P52V_FAN_6")
			(clearance 0.0508)
			(thermal_gap 0.0508)
		)
		(pad "12" thru_hole circle
			(at -1.999996 9.99998 90)
			(size 1.3716 1.3716)
			(drill 0.9652)
			(layers "*.Cu" "*.Mask")
			(remove_unused_layers no)
			(net "FAN_6_FAIL_R_LED_N")
			(clearance 0.0508)
			(thermal_gap 0.0508)
		)
		(pad "13" thru_hole circle
			(at 0 11.999976 90)
			(size 1.3716 1.3716)
			(drill 0.9652)
			(layers "*.Cu" "*.Mask")
			(remove_unused_layers no)
			(net "FAN_6_TACH_OL_D")
			(clearance 0.0508)
			(thermal_gap 0.0508)
		)
		(pad "14" thru_hole circle
			(at -1.999996 11.999976 90)
			(size 1.3716 1.3716)
			(drill 0.9652)
			(layers "*.Cu" "*.Mask")
			(remove_unused_layers no)
			(net "FAN_6_OK_R_LED_N")
			(clearance 0.0508)
			(thermal_gap 0.0508)
		)
		(pad "15" thru_hole circle
			(at 0 13.999972 90)
			(size 1.3716 1.3716)
			(drill 0.9652)
			(layers "*.Cu" "*.Mask")
			(remove_unused_layers no)
			(net "Net_600")
			(clearance 0.0508)
			(thermal_gap 0.0508)
		)
		(pad "16" thru_hole circle
			(at -1.999996 13.999972 90)
			(size 1.3716 1.3716)
			(drill 0.9652)
			(layers "*.Cu" "*.Mask")
			(remove_unused_layers no)
			(net "Net_599")
			(clearance 0.0508)
			(thermal_gap 0.0508)
		)
		(zone
			(layers "F.Cu" "B.Cu" "In1.Cu" "In2.Cu" "In3.Cu" "In4.Cu")
			(hatch none 0.5)
			(connect_pads
				(clearance 0)
			)
			(min_thickness 0.25)
			(keepout
				(tracks not_allowed)
				(vias allowed)
				(pads allowed)
				(copperpour not_allowed)
				(footprints allowed)
			)
			(placement
				(enabled no)
				(sheetname "")
			)
			(fill
				(thermal_gap 0.5)
				(thermal_bridge_width 0.5)
				(island_removal_mode 0)
			)
			(polygon
				(pts
					(arc
						(start 8.95731 -195.1101)
						(mid 6.44271 -195.1101)
						(end 8.95731 -195.1101)
					)
				)
			)
		)
	)
	(footprint ""
		(layer "B.Cu")
		(at 17.653 -126.238 180)
		(property "Reference" "R5434"
			(at 0 0 0)
			(layer "B.SilkS")
			(hide yes)
			(effects
				(font
					(size 1.27 1.27)
				)
				(justify mirror)
			)
		)
		(property "Value" ""
			(at 0 0 0)
			(layer "B.Fab")
			(effects
				(font
					(size 1.27 1.27)
				)
				(justify mirror)
			)
		)
		(duplicate_pad_numbers_are_jumpers no)
		(fp_line
			(start 0.7874 0.4064)
			(end 0.7874 -0.4064)
			(stroke
				(width 0.1524)
				(type default)
			)
			(layer "B.SilkS")
		)
		(fp_line
			(start 0.7874 -0.4064)
			(end -0.7874 -0.4064)
			(stroke
				(width 0.1524)
				(type default)
			)
			(layer "B.SilkS")
		)
		(fp_line
			(start -0.7874 0.4064)
			(end 0.7874 0.4064)
			(stroke
				(width 0.1524)
				(type default)
			)
			(layer "B.SilkS")
		)
		(fp_line
			(start -0.7874 -0.4064)
			(end -0.7874 0.4064)
			(stroke
				(width 0.1524)
				(type default)
			)
			(layer "B.SilkS")
		)
		(fp_line
			(start 0.67945 0.3048)
			(end 0.67945 -0.305054)
			(stroke
				(width 0.1)
				(type default)
			)
			(layer "B.Fab")
		)
		(fp_line
			(start 0.67945 -0.305054)
			(end 0.12065 -0.305054)
			(stroke
				(width 0.1)
				(type default)
			)
			(layer "B.Fab")
		)
		(fp_line
			(start 0.12065 0.3048)
			(end 0.67945 0.3048)
			(stroke
				(width 0.1)
				(type default)
			)
			(layer "B.Fab")
		)
		(fp_line
			(start 0.12065 0.2794)
			(end 0.12065 0.3048)
			(stroke
				(width 0.1)
				(type default)
			)
			(layer "B.Fab")
		)
		(fp_line
			(start 0.12065 -0.2794)
			(end -0.12065 -0.2794)
			(stroke
				(width 0.1)
				(type default)
			)
			(layer "B.Fab")
		)
		(fp_line
			(start 0.12065 -0.305054)
			(end 0.12065 -0.2794)
			(stroke
				(width 0.1)
				(type default)
			)
			(layer "B.Fab")
		)
		(fp_line
			(start -0.120396 0.3048)
			(end -0.120396 0.2794)
			(stroke
				(width 0.1)
				(type default)
			)
			(layer "B.Fab")
		)
		(fp_line
			(start -0.120396 0.2794)
			(end 0.12065 0.2794)
			(stroke
				(width 0.1)
				(type default)
			)
			(layer "B.Fab")
		)
		(fp_line
			(start -0.12065 -0.2794)
			(end -0.12065 -0.3048)
			(stroke
				(width 0.1)
				(type default)
			)
			(layer "B.Fab")
		)
		(fp_line
			(start -0.12065 -0.3048)
			(end -0.67945 -0.3048)
			(stroke
				(width 0.1)
				(type default)
			)
			(layer "B.Fab")
		)
		(fp_line
			(start -0.67945 0.3048)
			(end -0.120396 0.3048)
			(stroke
				(width 0.1)
				(type default)
			)
			(layer "B.Fab")
		)
		(fp_line
			(start -0.67945 -0.3048)
			(end -0.67945 0.3048)
			(stroke
				(width 0.1)
				(type default)
			)
			(layer "B.Fab")
		)
		(pad "1" smd rect
			(at 0.40005 0 180)
			(size 0.4572 0.508)
			(layers "B.Cu" "B.Mask" "B.Paste")
			(net "FAN_4_TACH_IL")
		)
		(pad "2" smd rect
			(at -0.40005 0 180)
			(size 0.4572 0.508)
			(layers "B.Cu" "B.Mask" "B.Paste")
			(net "GND")
		)
	)
	(footprint ""
		(layer "B.Cu")
		(at 38.46068 -258.562856 90)
		(property "Reference" "PR8"
			(at 0 0 90)
			(layer "B.SilkS")
			(hide yes)
			(effects
				(font
					(size 1.27 1.27)
				)
				(justify mirror)
			)
		)
		(property "Value" ""
			(at 0 0 90)
			(layer "B.Fab")
			(effects
				(font
					(size 1.27 1.27)
				)
				(justify mirror)
			)
		)
		(duplicate_pad_numbers_are_jumpers no)
		(fp_line
			(start 0.7874 -0.4064)
			(end -0.7874 -0.4064)
			(stroke
				(width 0.1524)
				(type default)
			)
			(layer "B.SilkS")
		)
		(fp_line
			(start -0.7874 -0.4064)
			(end -0.7874 0.4064)
			(stroke
				(width 0.1524)
				(type default)
			)
			(layer "B.SilkS")
		)
		(fp_line
			(start 0.7874 0.4064)
			(end 0.7874 -0.4064)
			(stroke
				(width 0.1524)
				(type default)
			)
			(layer "B.SilkS")
		)
		(fp_line
			(start -0.7874 0.4064)
			(end 0.7874 0.4064)
			(stroke
				(width 0.1524)
				(type default)
			)
			(layer "B.SilkS")
		)
		(fp_line
			(start 0.67945 -0.305054)
			(end 0.12065 -0.305054)
			(stroke
				(width 0.1)
				(type default)
			)
			(layer "B.Fab")
		)
		(fp_line
			(start 0.12065 -0.305054)
			(end 0.12065 -0.2794)
			(stroke
				(width 0.1)
				(type default)
			)
			(layer "B.Fab")
		)
		(fp_line
			(start -0.12065 -0.3048)
			(end -0.67945 -0.3048)
			(stroke
				(width 0.1)
				(type default)
			)
			(layer "B.Fab")
		)
		(fp_line
			(start -0.67945 -0.3048)
			(end -0.67945 0.3048)
			(stroke
				(width 0.1)
				(type default)
			)
			(layer "B.Fab")
		)
		(fp_line
			(start 0.12065 -0.2794)
			(end -0.12065 -0.2794)
			(stroke
				(width 0.1)
				(type default)
			)
			(layer "B.Fab")
		)
		(fp_line
			(start -0.12065 -0.2794)
			(end -0.12065 -0.3048)
			(stroke
				(width 0.1)
				(type default)
			)
			(layer "B.Fab")
		)
		(fp_line
			(start 0.12065 0.2794)
			(end 0.12065 0.3048)
			(stroke
				(width 0.1)
				(type default)
			)
			(layer "B.Fab")
		)
		(fp_line
			(start -0.120396 0.2794)
			(end 0.12065 0.2794)
			(stroke
				(width 0.1)
				(type default)
			)
			(layer "B.Fab")
		)
		(fp_line
			(start 0.67945 0.3048)
			(end 0.67945 -0.305054)
			(stroke
				(width 0.1)
				(type default)
			)
			(layer "B.Fab")
		)
		(fp_line
			(start 0.12065 0.3048)
			(end 0.67945 0.3048)
			(stroke
				(width 0.1)
				(type default)
			)
			(layer "B.Fab")
		)
		(fp_line
			(start -0.120396 0.3048)
			(end -0.120396 0.2794)
			(stroke
				(width 0.1)
				(type default)
			)
			(layer "B.Fab")
		)
		(fp_line
			(start -0.67945 0.3048)
			(end -0.120396 0.3048)
			(stroke
				(width 0.1)
				(type default)
			)
			(layer "B.Fab")
		)
		(pad "1" smd circle
			(at 0.40005 0 270)
			(size 0 0)
			(layers "B.Cu" "B.Mask" "B.Paste")
			(net "FAN_0_TEMP")
		)
		(pad "2" smd circle
			(at -0.40005 0 270)
			(size 0 0)
			(layers "B.Cu" "B.Mask" "B.Paste")
			(net "GND")
		)
	)
	(footprint ""
		(layer "B.Cu")
		(at 8.763 -249.428 -90)
		(property "Reference" "PC51"
			(at 0 0 90)
			(layer "B.SilkS")
			(hide yes)
			(effects
				(font
					(size 1.27 1.27)
				)
				(justify mirror)
			)
		)
		(property "Value" ""
			(at 0 0 90)
			(layer "B.Fab")
			(effects
				(font
					(size 1.27 1.27)
				)
				(justify mirror)
			)
		)
		(duplicate_pad_numbers_are_jumpers no)
		(fp_line
			(start -0.7874 0.4064)
			(end 0.7874 0.4064)
			(stroke
				(width 0.1524)
				(type default)
			)
			(layer "B.SilkS")
		)
		(fp_line
			(start 0.7874 0.4064)
			(end 0.7874 -0.4064)
			(stroke
				(width 0.1524)
				(type default)
			)
			(layer "B.SilkS")
		)
		(fp_line
			(start -0.7874 -0.4064)
			(end -0.7874 0.4064)
			(stroke
				(width 0.1524)
				(type default)
			)
			(layer "B.SilkS")
		)
		(fp_line
			(start 0.7874 -0.4064)
			(end -0.7874 -0.4064)
			(stroke
				(width 0.1524)
				(type default)
			)
			(layer "B.SilkS")
		)
		(fp_line
			(start -0.67945 0.3048)
			(end -0.120396 0.3048)
			(stroke
				(width 0.1)
				(type default)
			)
			(layer "B.Fab")
		)
		(fp_line
			(start -0.120396 0.3048)
			(end -0.120396 0.2794)
			(stroke
				(width 0.1)
				(type default)
			)
			(layer "B.Fab")
		)
		(fp_line
			(start 0.12065 0.3048)
			(end 0.67945 0.3048)
			(stroke
				(width 0.1)
				(type default)
			)
			(layer "B.Fab")
		)
		(fp_line
			(start 0.67945 0.3048)
			(end 0.67945 -0.305054)
			(stroke
				(width 0.1)
				(type default)
			)
			(layer "B.Fab")
		)
		(fp_line
			(start -0.120396 0.2794)
			(end 0.12065 0.2794)
			(stroke
				(width 0.1)
				(type default)
			)
			(layer "B.Fab")
		)
		(fp_line
			(start 0.12065 0.2794)
			(end 0.12065 0.3048)
			(stroke
				(width 0.1)
				(type default)
			)
			(layer "B.Fab")
		)
		(fp_line
			(start -0.12065 -0.2794)
			(end -0.12065 -0.3048)
			(stroke
				(width 0.1)
				(type default)
			)
			(layer "B.Fab")
		)
		(fp_line
			(start 0.12065 -0.2794)
			(end -0.12065 -0.2794)
			(stroke
				(width 0.1)
				(type default)
			)
			(layer "B.Fab")
		)
		(fp_line
			(start -0.67945 -0.3048)
			(end -0.67945 0.3048)
			(stroke
				(width 0.1)
				(type default)
			)
			(layer "B.Fab")
		)
		(fp_line
			(start -0.12065 -0.3048)
			(end -0.67945 -0.3048)
			(stroke
				(width 0.1)
				(type default)
			)
			(layer "B.Fab")
		)
		(fp_line
			(start 0.12065 -0.305054)
			(end 0.12065 -0.2794)
			(stroke
				(width 0.1)
				(type default)
			)
			(layer "B.Fab")
		)
		(fp_line
			(start 0.67945 -0.305054)
			(end 0.12065 -0.305054)
			(stroke
				(width 0.1)
				(type default)
			)
			(layer "B.Fab")
		)
		(pad "1" smd circle
			(at 0.40005 0 90)
			(size 0 0)
			(layers "B.Cu" "B.Mask" "B.Paste")
			(net "FAN_6_P5V")
		)
		(pad "2" smd circle
			(at -0.40005 0 90)
			(size 0 0)
			(layers "B.Cu" "B.Mask" "B.Paste")
			(net "GND")
		)
	)
	(footprint ""
		(layer "B.Cu")
		(at 5.50799 -274.971256 -90)
		(property "Reference" "PD13"
			(at 4.7752 -3.749548 270)
			(unlocked yes)
			(layer "B.SilkS")
			(effects
				(font
					(size 0.7874 0.5842)
					(thickness 0.1524)
				)
				(justify left mirror)
			)
		)
		(property "Value" ""
			(at 0 0 90)
			(layer "B.Fab")
			(effects
				(font
					(size 1.27 1.27)
				)
				(justify mirror)
			)
		)
		(duplicate_pad_numbers_are_jumpers no)
		(fp_line
			(start -5.334 3.109976)
			(end -4.8133 3.109976)
			(stroke
				(width 0.1524)
				(type default)
			)
			(layer "B.SilkS")
		)
		(fp_line
			(start -5.334 3.109976)
			(end -5.334 0)
			(stroke
				(width 0.1524)
				(type default)
			)
			(layer "B.SilkS")
		)
		(fp_line
			(start -5.207 3.109976)
			(end -5.207 -3.109976)
			(stroke
				(width 0.1524)
				(type default)
			)
			(layer "B.SilkS")
		)
		(fp_line
			(start -5.1308 3.109976)
			(end -5.1308 -3.109976)
			(stroke
				(width 0.1524)
				(type default)
			)
			(layer "B.SilkS")
		)
		(fp_line
			(start -5.0292 3.109976)
			(end -5.0292 -3.109976)
			(stroke
				(width 0.1524)
				(type default)
			)
			(layer "B.SilkS")
		)
		(fp_line
			(start -4.9276 3.109976)
			(end -4.9276 -3.109976)
			(stroke
				(width 0.1524)
				(type default)
			)
			(layer "B.SilkS")
		)
		(fp_line
			(start -4.826 3.109976)
			(end 4.826 3.109976)
			(stroke
				(width 0.1524)
				(type default)
			)
			(layer "B.SilkS")
		)
		(fp_line
			(start 4.826 3.109976)
			(end 4.826 0)
			(stroke
				(width 0.1524)
				(type default)
			)
			(layer "B.SilkS")
		)
		(fp_line
			(start -1.143 1.397)
			(end -1.143 -1.397)
			(stroke
				(width 0.1524)
				(type default)
			)
			(layer "B.SilkS")
		)
		(fp_line
			(start 1.016 1.016)
			(end -1.016 0)
			(stroke
				(width 0.1524)
				(type default)
			)
			(layer "B.SilkS")
		)
		(fp_line
			(start -5.334 0)
			(end -5.334 -3.109976)
			(stroke
				(width 0.1524)
				(type default)
			)
			(layer "B.SilkS")
		)
		(fp_line
			(start -4.826 0)
			(end -4.826 3.109976)
			(stroke
				(width 0.1524)
				(type default)
			)
			(layer "B.SilkS")
		)
		(fp_line
			(start -1.143 0)
			(end -1.8034 0)
			(stroke
				(width 0.1524)
				(type default)
			)
			(layer "B.SilkS")
		)
		(fp_line
			(start -1.143 0)
			(end 1.016 -1.016)
			(stroke
				(width 0.1524)
				(type default)
			)
			(layer "B.SilkS")
		)
		(fp_line
			(start 1.0922 0)
			(end 1.7018 0)
			(stroke
				(width 0.1524)
				(type default)
			)
			(layer "B.SilkS")
		)
		(fp_line
			(start 4.826 0)
			(end 4.826 -3.109976)
			(stroke
				(width 0.1524)
				(type default)
			)
			(layer "B.SilkS")
		)
		(fp_line
			(start 1.016 -1.016)
			(end 1.016 1.016)
			(stroke
				(width 0.1524)
				(type default)
			)
			(layer "B.SilkS")
		)
		(fp_line
			(start -4.826 -3.109976)
			(end -4.826 0)
			(stroke
				(width 0.1524)
				(type default)
			)
			(layer "B.SilkS")
		)
		(fp_line
			(start -4.8133 -3.109976)
			(end -5.3467 -3.109976)
			(stroke
				(width 0.1524)
				(type default)
			)
			(layer "B.SilkS")
		)
		(fp_line
			(start 4.826 -3.109976)
			(end -4.826 -3.109976)
			(stroke
				(width 0.1524)
				(type default)
			)
			(layer "B.SilkS")
		)
		(fp_line
			(start -3.554984 3.109976)
			(end 3.554984 3.109976)
			(stroke
				(width 0.1)
				(type default)
			)
			(layer "B.Fab")
		)
		(fp_line
			(start 3.554984 3.109976)
			(end 3.554984 -3.109976)
			(stroke
				(width 0.1)
				(type default)
			)
			(layer "B.Fab")
		)
		(fp_line
			(start -1.143 1.397)
			(end -1.143 -1.397)
			(stroke
				(width 0.1)
				(type default)
			)
			(layer "B.Fab")
		)
		(fp_line
			(start 1.016 1.016)
			(end -1.016 0)
			(stroke
				(width 0.1)
				(type default)
			)
			(layer "B.Fab")
		)
		(fp_line
			(start -1.143 0)
			(end -1.8034 0)
			(stroke
				(width 0.1)
				(type default)
			)
			(layer "B.Fab")
		)
		(fp_line
			(start -1.143 0)
			(end 1.016 -1.016)
			(stroke
				(width 0.1)
				(type default)
			)
			(layer "B.Fab")
		)
		(fp_line
			(start 1.0922 0)
			(end 1.7018 0)
			(stroke
				(width 0.1)
				(type default)
			)
			(layer "B.Fab")
		)
		(fp_line
			(start 1.016 -1.016)
			(end 1.016 1.016)
			(stroke
				(width 0.1)
				(type default)
			)
			(layer "B.Fab")
		)
		(fp_line
			(start -3.554984 -3.109976)
			(end -3.554984 3.109976)
			(stroke
				(width 0.1)
				(type default)
			)
			(layer "B.Fab")
		)
		(fp_line
			(start 3.554984 -3.109976)
			(end -3.554984 -3.109976)
			(stroke
				(width 0.1)
				(type default)
			)
			(layer "B.Fab")
		)
		(fp_text user "+"
			(at 4.689856 2.93624 90)
			(unlocked yes)
			(layer "B.SilkS")
			(effects
				(font
					(size 1.905 1.4224)
					(thickness 0.1524)
				)
				(justify left mirror)
			)
		)
		(fp_text user "-"
			(at -6.613144 2.04724 90)
			(unlocked yes)
			(layer "B.SilkS")
			(effects
				(font
					(size 1.905 1.4224)
					(thickness 0.1524)
				)
				(justify left mirror)
			)
		)
		(fp_text user "-"
			(at -6.6802 0.22225 90)
			(unlocked yes)
			(layer "B.Fab")
			(effects
				(font
					(size 1.905 1.4224)
					(thickness 0.1524)
				)
				(justify left mirror)
			)
		)
		(fp_text user "+"
			(at 4.5466 0.19685 90)
			(unlocked yes)
			(layer "B.Fab")
			(effects
				(font
					(size 1.905 1.4224)
					(thickness 0.1524)
				)
				(justify left mirror)
			)
		)
		(pad "A" smd rect
			(at 3.400044 0 270)
			(size 2.5146 3.302)
			(layers "B.Cu" "B.Mask" "B.Paste")
			(net "GND")
		)
		(pad "C" smd rect
			(at -3.400044 0 270)
			(size 2.5146 3.302)
			(layers "B.Cu" "B.Mask" "B.Paste")
			(net "P52V_FAN_7")
		)
	)
	(footprint ""
		(layer "B.Cu")
		(at 5.596128 -230.088948)
		(property "Reference" "C2115"
			(at 0 0 0)
			(layer "B.SilkS")
			(hide yes)
			(effects
				(font
					(size 1.27 1.27)
				)
				(justify mirror)
			)
		)
		(property "Value" ""
			(at 0 0 0)
			(layer "B.Fab")
			(effects
				(font
					(size 1.27 1.27)
				)
				(justify mirror)
			)
		)
		(duplicate_pad_numbers_are_jumpers no)
		(fp_line
			(start -2.2098 -0.9398)
			(end -2.2098 0.9398)
			(stroke
				(width 0.1524)
				(type default)
			)
			(layer "B.SilkS")
		)
		(fp_line
			(start -2.2098 0.9398)
			(end 2.2098 0.9398)
			(stroke
				(width 0.1524)
				(type default)
			)
			(layer "B.SilkS")
		)
		(fp_line
			(start 2.2098 -0.9398)
			(end -2.2098 -0.9398)
			(stroke
				(width 0.1524)
				(type default)
			)
			(layer "B.SilkS")
		)
		(fp_line
			(start 2.2098 0.9398)
			(end 2.2098 -0.9398)
			(stroke
				(width 0.1524)
				(type default)
			)
			(layer "B.SilkS")
		)
		(fp_line
			(start -1.700022 -0.899922)
			(end -1.700022 0.899922)
			(stroke
				(width 0.1)
				(type default)
			)
			(layer "B.Fab")
		)
		(fp_line
			(start -1.700022 0.899922)
			(end 1.700022 0.899922)
			(stroke
				(width 0.1)
				(type default)
			)
			(layer "B.Fab")
		)
		(fp_line
			(start 1.700022 -0.899922)
			(end -1.700022 -0.899922)
			(stroke
				(width 0.1)
				(type default)
			)
			(layer "B.Fab")
		)
		(fp_line
			(start 1.700022 0.899922)
			(end 1.700022 -0.899922)
			(stroke
				(width 0.1)
				(type default)
			)
			(layer "B.Fab")
		)
		(pad "1" smd rect
			(at 1.4732 0)
			(size 1.1684 1.5748)
			(layers "B.Cu" "B.Mask" "B.Paste")
			(net "P52V_FAN_6")
		)
		(pad "2" smd rect
			(at -1.4732 0)
			(size 1.1684 1.5748)
			(layers "B.Cu" "B.Mask" "B.Paste")
			(net "GND")
		)
	)
	(footprint ""
		(layer "B.Cu")
		(at 12.334494 -255.905)
		(property "Reference" "U385"
			(at 0.111506 1.80467 0)
			(unlocked yes)
			(layer "B.SilkS")
			(effects
				(font
					(size 0.7874 0.5842)
					(thickness 0.1524)
				)
				(justify mirror)
			)
		)
		(property "Value" ""
			(at 0 0 0)
			(layer "B.Fab")
			(effects
				(font
					(size 1.27 1.27)
				)
				(justify mirror)
			)
		)
		(duplicate_pad_numbers_are_jumpers no)
		(fp_line
			(start -1.7018 -1.1176)
			(end -1.7018 1.1176)
			(stroke
				(width 0.1524)
				(type default)
			)
			(layer "B.SilkS")
		)
		(fp_line
			(start -1.7018 -1.1176)
			(end -0.254 -1.1176)
			(stroke
				(width 0.1524)
				(type default)
			)
			(layer "B.SilkS")
		)
		(fp_line
			(start -1.7018 1.1176)
			(end 1.7018 1.1176)
			(stroke
				(width 0.1524)
				(type default)
			)
			(layer "B.SilkS")
		)
		(fp_line
			(start -0.254 -1.1176)
			(end 0 -0.7112)
			(stroke
				(width 0.1524)
				(type default)
			)
			(layer "B.SilkS")
		)
		(fp_line
			(start 0 -0.7112)
			(end 0.254 -1.1176)
			(stroke
				(width 0.1524)
				(type default)
			)
			(layer "B.SilkS")
		)
		(fp_line
			(start 0.254 -1.1176)
			(end 1.7018 -1.1176)
			(stroke
				(width 0.1524)
				(type default)
			)
			(layer "B.SilkS")
		)
		(fp_line
			(start 1.7018 1.1176)
			(end 1.7018 -1.1176)
			(stroke
				(width 0.1524)
				(type default)
			)
			(layer "B.SilkS")
		)
		(fp_poly
			(pts
				(xy 1.8161 -0.675386) (xy 2.4003 -0.446786) (xy 2.4003 -0.878586)
			)
			(stroke
				(width 0)
				(type default)
			)
			(fill yes)
			(layer "B.SilkS")
		)
		(fp_line
			(start -1.5494 -1.1176)
			(end -1.5494 1.1176)
			(stroke
				(width 0.1)
				(type default)
			)
			(layer "B.Fab")
		)
		(fp_line
			(start -1.5494 -1.1176)
			(end -0.254 -1.1176)
			(stroke
				(width 0.1)
				(type default)
			)
			(layer "B.Fab")
		)
		(fp_line
			(start -1.5494 1.1176)
			(end 1.5494 1.1176)
			(stroke
				(width 0.1)
				(type default)
			)
			(layer "B.Fab")
		)
		(fp_line
			(start -0.254 -1.1176)
			(end 0.254 -1.1176)
			(stroke
				(width 0.1)
				(type default)
			)
			(layer "B.Fab")
		)
		(fp_line
			(start 0.254 -1.1176)
			(end 1.5494 -1.1176)
			(stroke
				(width 0.1)
				(type default)
			)
			(layer "B.Fab")
		)
		(fp_line
			(start 1.5494 1.1176)
			(end 1.5494 -1.1176)
			(stroke
				(width 0.1)
				(type default)
			)
			(layer "B.Fab")
		)
		(fp_poly
			(pts
				(xy 1.8161 -0.675386) (xy 2.4003 -0.446786) (xy 2.4003 -0.878586)
			)
			(stroke
				(width 0)
				(type default)
			)
			(fill yes)
			(layer "B.Fab")
		)
		(pad "1" smd rect
			(at 0.962406 -0.649986 270)
			(size 0.3302 1.1684)
			(layers "B.Cu" "B.Mask" "B.Paste")
			(net "FAN_7_PRESENT_R")
		)
		(pad "2" smd rect
			(at 0.962406 0 270)
			(size 0.3302 1.1684)
			(layers "B.Cu" "B.Mask" "B.Paste")
			(net "P52V_FAN_7_BUFF_EN_R")
		)
		(pad "3" smd rect
			(at 0.962406 0.649986 270)
			(size 0.3302 1.1684)
			(layers "B.Cu" "B.Mask" "B.Paste")
			(net "GND")
		)
		(pad "4" smd rect
			(at -0.962406 0.649986 270)
			(size 0.3302 1.1684)
			(layers "B.Cu" "B.Mask" "B.Paste")
			(net "P52V_FAN_7_EN")
		)
		(pad "5" smd rect
			(at -0.962406 -0.649986 270)
			(size 0.3302 1.1684)
			(layers "B.Cu" "B.Mask" "B.Paste")
			(net "P3V3_AUX")
		)
	)
	(footprint ""
		(layer "B.Cu")
		(at 44.069 -226.8728)
		(property "Reference" "PD8"
			(at -3.302 3.83667 0)
			(unlocked yes)
			(layer "B.SilkS")
			(effects
				(font
					(size 0.7874 0.5842)
					(thickness 0.1524)
				)
				(justify left mirror)
			)
		)
		(property "Value" ""
			(at 0 0 0)
			(layer "B.Fab")
			(effects
				(font
					(size 1.27 1.27)
				)
				(justify mirror)
			)
		)
		(duplicate_pad_numbers_are_jumpers no)
		(fp_line
			(start -5.334 0)
			(end -5.334 -3.109976)
			(stroke
				(width 0.1524)
				(type default)
			)
			(layer "B.SilkS")
		)
		(fp_line
			(start -5.334 3.109976)
			(end -5.334 0)
			(stroke
				(width 0.1524)
				(type default)
			)
			(layer "B.SilkS")
		)
		(fp_line
			(start -5.334 3.109976)
			(end -4.8133 3.109976)
			(stroke
				(width 0.1524)
				(type default)
			)
			(layer "B.SilkS")
		)
		(fp_line
			(start -5.207 3.109976)
			(end -5.207 -3.109976)
			(stroke
				(width 0.1524)
				(type default)
			)
			(layer "B.SilkS")
		)
		(fp_line
			(start -5.1308 3.109976)
			(end -5.1308 -3.109976)
			(stroke
				(width 0.1524)
				(type default)
			)
			(layer "B.SilkS")
		)
		(fp_line
			(start -5.0292 3.109976)
			(end -5.0292 -3.109976)
			(stroke
				(width 0.1524)
				(type default)
			)
			(layer "B.SilkS")
		)
		(fp_line
			(start -4.9276 3.109976)
			(end -4.9276 -3.109976)
			(stroke
				(width 0.1524)
				(type default)
			)
			(layer "B.SilkS")
		)
		(fp_line
			(start -4.826 -3.109976)
			(end -4.826 0)
			(stroke
				(width 0.1524)
				(type default)
			)
			(layer "B.SilkS")
		)
		(fp_line
			(start -4.826 0)
			(end -4.826 3.109976)
			(stroke
				(width 0.1524)
				(type default)
			)
			(layer "B.SilkS")
		)
		(fp_line
			(start -4.826 3.109976)
			(end 4.826 3.109976)
			(stroke
				(width 0.1524)
				(type default)
			)
			(layer "B.SilkS")
		)
		(fp_line
			(start -4.8133 -3.109976)
			(end -5.3467 -3.109976)
			(stroke
				(width 0.1524)
				(type default)
			)
			(layer "B.SilkS")
		)
		(fp_line
			(start -1.143 0)
			(end -1.8034 0)
			(stroke
				(width 0.1524)
				(type default)
			)
			(layer "B.SilkS")
		)
		(fp_line
			(start -1.143 0)
			(end 1.016 -1.016)
			(stroke
				(width 0.1524)
				(type default)
			)
			(layer "B.SilkS")
		)
		(fp_line
			(start -1.143 1.397)
			(end -1.143 -1.397)
			(stroke
				(width 0.1524)
				(type default)
			)
			(layer "B.SilkS")
		)
		(fp_line
			(start 1.016 -1.016)
			(end 1.016 1.016)
			(stroke
				(width 0.1524)
				(type default)
			)
			(layer "B.SilkS")
		)
		(fp_line
			(start 1.016 1.016)
			(end -1.016 0)
			(stroke
				(width 0.1524)
				(type default)
			)
			(layer "B.SilkS")
		)
		(fp_line
			(start 1.0922 0)
			(end 1.7018 0)
			(stroke
				(width 0.1524)
				(type default)
			)
			(layer "B.SilkS")
		)
		(fp_line
			(start 4.826 -3.109976)
			(end -4.826 -3.109976)
			(stroke
				(width 0.1524)
				(type default)
			)
			(layer "B.SilkS")
		)
		(fp_line
			(start 4.826 0)
			(end 4.826 -3.109976)
			(stroke
				(width 0.1524)
				(type default)
			)
			(layer "B.SilkS")
		)
		(fp_line
			(start 4.826 3.109976)
			(end 4.826 0)
			(stroke
				(width 0.1524)
				(type default)
			)
			(layer "B.SilkS")
		)
		(fp_line
			(start -3.554984 -3.109976)
			(end -3.554984 3.109976)
			(stroke
				(width 0.1)
				(type default)
			)
			(layer "B.Fab")
		)
		(fp_line
			(start -3.554984 3.109976)
			(end 3.554984 3.109976)
			(stroke
				(width 0.1)
				(type default)
			)
			(layer "B.Fab")
		)
		(fp_line
			(start -1.143 0)
			(end -1.8034 0)
			(stroke
				(width 0.1)
				(type default)
			)
			(layer "B.Fab")
		)
		(fp_line
			(start -1.143 0)
			(end 1.016 -1.016)
			(stroke
				(width 0.1)
				(type default)
			)
			(layer "B.Fab")
		)
		(fp_line
			(start -1.143 1.397)
			(end -1.143 -1.397)
			(stroke
				(width 0.1)
				(type default)
			)
			(layer "B.Fab")
		)
		(fp_line
			(start 1.016 -1.016)
			(end 1.016 1.016)
			(stroke
				(width 0.1)
				(type default)
			)
			(layer "B.Fab")
		)
		(fp_line
			(start 1.016 1.016)
			(end -1.016 0)
			(stroke
				(width 0.1)
				(type default)
			)
			(layer "B.Fab")
		)
		(fp_line
			(start 1.0922 0)
			(end 1.7018 0)
			(stroke
				(width 0.1)
				(type default)
			)
			(layer "B.Fab")
		)
		(fp_line
			(start 3.554984 -3.109976)
			(end -3.554984 -3.109976)
			(stroke
				(width 0.1)
				(type default)
			)
			(layer "B.Fab")
		)
		(fp_line
			(start 3.554984 3.109976)
			(end 3.554984 -3.109976)
			(stroke
				(width 0.1)
				(type default)
			)
			(layer "B.Fab")
		)
		(fp_text user "-"
			(at -6.731 1.79705 180)
			(unlocked yes)
			(layer "B.SilkS")
			(effects
				(font
					(size 1.905 1.4224)
					(thickness 0.1524)
				)
				(justify left mirror)
			)
		)
		(fp_text user "+"
			(at 5.207 0.65405 180)
			(unlocked yes)
			(layer "B.SilkS")
			(effects
				(font
					(size 1.905 1.4224)
					(thickness 0.1524)
				)
				(justify left mirror)
			)
		)
		(fp_text user "-"
			(at -6.6802 0.22225 180)
			(unlocked yes)
			(layer "B.Fab")
			(effects
				(font
					(size 1.905 1.4224)
					(thickness 0.1524)
				)
				(justify left mirror)
			)
		)
		(fp_text user "+"
			(at 4.5466 0.19685 180)
			(unlocked yes)
			(layer "B.Fab")
			(effects
				(font
					(size 1.905 1.4224)
					(thickness 0.1524)
				)
				(justify left mirror)
			)
		)
		(pad "A" smd rect
			(at 3.400044 0)
			(size 2.5146 3.302)
			(layers "B.Cu" "B.Mask" "B.Paste")
			(net "GND")
		)
		(pad "C" smd rect
			(at -3.400044 0)
			(size 2.5146 3.302)
			(layers "B.Cu" "B.Mask" "B.Paste")
			(net "P52V_FAN_1")
		)
	)
	(footprint ""
		(layer "B.Cu")
		(at 35.433 -64.837056 -90)
		(property "Reference" "PC21"
			(at 0 0 90)
			(layer "B.SilkS")
			(hide yes)
			(effects
				(font
					(size 1.27 1.27)
				)
				(justify mirror)
			)
		)
		(property "Value" ""
			(at 0 0 90)
			(layer "B.Fab")
			(effects
				(font
					(size 1.27 1.27)
				)
				(justify mirror)
			)
		)
		(duplicate_pad_numbers_are_jumpers no)
		(fp_line
			(start -0.7874 0.4064)
			(end 0.7874 0.4064)
			(stroke
				(width 0.1524)
				(type default)
			)
			(layer "B.SilkS")
		)
		(fp_line
			(start 0.7874 0.4064)
			(end 0.7874 -0.4064)
			(stroke
				(width 0.1524)
				(type default)
			)
			(layer "B.SilkS")
		)
		(fp_line
			(start -0.7874 -0.4064)
			(end -0.7874 0.4064)
			(stroke
				(width 0.1524)
				(type default)
			)
			(layer "B.SilkS")
		)
		(fp_line
			(start 0.7874 -0.4064)
			(end -0.7874 -0.4064)
			(stroke
				(width 0.1524)
				(type default)
			)
			(layer "B.SilkS")
		)
		(fp_line
			(start -0.67945 0.3048)
			(end -0.120396 0.3048)
			(stroke
				(width 0.1)
				(type default)
			)
			(layer "B.Fab")
		)
		(fp_line
			(start -0.120396 0.3048)
			(end -0.120396 0.2794)
			(stroke
				(width 0.1)
				(type default)
			)
			(layer "B.Fab")
		)
		(fp_line
			(start 0.12065 0.3048)
			(end 0.67945 0.3048)
			(stroke
				(width 0.1)
				(type default)
			)
			(layer "B.Fab")
		)
		(fp_line
			(start 0.67945 0.3048)
			(end 0.67945 -0.305054)
			(stroke
				(width 0.1)
				(type default)
			)
			(layer "B.Fab")
		)
		(fp_line
			(start -0.120396 0.2794)
			(end 0.12065 0.2794)
			(stroke
				(width 0.1)
				(type default)
			)
			(layer "B.Fab")
		)
		(fp_line
			(start 0.12065 0.2794)
			(end 0.12065 0.3048)
			(stroke
				(width 0.1)
				(type default)
			)
			(layer "B.Fab")
		)
		(fp_line
			(start -0.12065 -0.2794)
			(end -0.12065 -0.3048)
			(stroke
				(width 0.1)
				(type default)
			)
			(layer "B.Fab")
		)
		(fp_line
			(start 0.12065 -0.2794)
			(end -0.12065 -0.2794)
			(stroke
				(width 0.1)
				(type default)
			)
			(layer "B.Fab")
		)
		(fp_line
			(start -0.67945 -0.3048)
			(end -0.67945 0.3048)
			(stroke
				(width 0.1)
				(type default)
			)
			(layer "B.Fab")
		)
		(fp_line
			(start -0.12065 -0.3048)
			(end -0.67945 -0.3048)
			(stroke
				(width 0.1)
				(type default)
			)
			(layer "B.Fab")
		)
		(fp_line
			(start 0.12065 -0.305054)
			(end 0.12065 -0.2794)
			(stroke
				(width 0.1)
				(type default)
			)
			(layer "B.Fab")
		)
		(fp_line
			(start 0.67945 -0.305054)
			(end 0.12065 -0.305054)
			(stroke
				(width 0.1)
				(type default)
			)
			(layer "B.Fab")
		)
		(pad "1" smd circle
			(at 0.40005 0 90)
			(size 0 0)
			(layers "B.Cu" "B.Mask" "B.Paste")
			(net "FAN_3_TIMER")
		)
		(pad "2" smd circle
			(at -0.40005 0 90)
			(size 0 0)
			(layers "B.Cu" "B.Mask" "B.Paste")
			(net "GND")
		)
	)
	(footprint ""
		(layer "B.Cu")
		(at 44.069 -231.648 180)
		(property "Reference" "C2099"
			(at 0 0 0)
			(layer "B.SilkS")
			(hide yes)
			(effects
				(font
					(size 1.27 1.27)
				)
				(justify mirror)
			)
		)
		(property "Value" ""
			(at 0 0 0)
			(layer "B.Fab")
			(effects
				(font
					(size 1.27 1.27)
				)
				(justify mirror)
			)
		)
		(duplicate_pad_numbers_are_jumpers no)
		(fp_line
			(start 2.2098 0.9398)
			(end 2.2098 -0.9398)
			(stroke
				(width 0.1524)
				(type default)
			)
			(layer "B.SilkS")
		)
		(fp_line
			(start 2.2098 -0.9398)
			(end -2.2098 -0.9398)
			(stroke
				(width 0.1524)
				(type default)
			)
			(layer "B.SilkS")
		)
		(fp_line
			(start -2.2098 0.9398)
			(end 2.2098 0.9398)
			(stroke
				(width 0.1524)
				(type default)
			)
			(layer "B.SilkS")
		)
		(fp_line
			(start -2.2098 -0.9398)
			(end -2.2098 0.9398)
			(stroke
				(width 0.1524)
				(type default)
			)
			(layer "B.SilkS")
		)
		(fp_line
			(start 1.700022 0.899922)
			(end 1.700022 -0.899922)
			(stroke
				(width 0.1)
				(type default)
			)
			(layer "B.Fab")
		)
		(fp_line
			(start 1.700022 -0.899922)
			(end -1.700022 -0.899922)
			(stroke
				(width 0.1)
				(type default)
			)
			(layer "B.Fab")
		)
		(fp_line
			(start -1.700022 0.899922)
			(end 1.700022 0.899922)
			(stroke
				(width 0.1)
				(type default)
			)
			(layer "B.Fab")
		)
		(fp_line
			(start -1.700022 -0.899922)
			(end -1.700022 0.899922)
			(stroke
				(width 0.1)
				(type default)
			)
			(layer "B.Fab")
		)
		(pad "1" smd rect
			(at 1.4732 0 180)
			(size 1.1684 1.5748)
			(layers "B.Cu" "B.Mask" "B.Paste")
			(net "P52V_FAN_1")
		)
		(pad "2" smd rect
			(at -1.4732 0 180)
			(size 1.1684 1.5748)
			(layers "B.Cu" "B.Mask" "B.Paste")
			(net "GND")
		)
	)
	(footprint ""
		(layer "B.Cu")
		(at 9.906 -173.863 180)
		(property "Reference" "C1945"
			(at 0 0 0)
			(layer "B.SilkS")
			(hide yes)
			(effects
				(font
					(size 1.27 1.27)
				)
				(justify mirror)
			)
		)
		(property "Value" ""
			(at 0 0 0)
			(layer "B.Fab")
			(effects
				(font
					(size 1.27 1.27)
				)
				(justify mirror)
			)
		)
		(duplicate_pad_numbers_are_jumpers no)
		(fp_line
			(start 0.7874 0.4064)
			(end 0.7874 -0.4064)
			(stroke
				(width 0.1524)
				(type default)
			)
			(layer "B.SilkS")
		)
		(fp_line
			(start 0.7874 -0.4064)
			(end -0.7874 -0.4064)
			(stroke
				(width 0.1524)
				(type default)
			)
			(layer "B.SilkS")
		)
		(fp_line
			(start -0.7874 0.4064)
			(end 0.7874 0.4064)
			(stroke
				(width 0.1524)
				(type default)
			)
			(layer "B.SilkS")
		)
		(fp_line
			(start -0.7874 -0.4064)
			(end -0.7874 0.4064)
			(stroke
				(width 0.1524)
				(type default)
			)
			(layer "B.SilkS")
		)
		(fp_line
			(start 0.67945 0.3048)
			(end 0.67945 -0.305054)
			(stroke
				(width 0.1)
				(type default)
			)
			(layer "B.Fab")
		)
		(fp_line
			(start 0.67945 -0.305054)
			(end 0.12065 -0.305054)
			(stroke
				(width 0.1)
				(type default)
			)
			(layer "B.Fab")
		)
		(fp_line
			(start 0.12065 0.3048)
			(end 0.67945 0.3048)
			(stroke
				(width 0.1)
				(type default)
			)
			(layer "B.Fab")
		)
		(fp_line
			(start 0.12065 0.2794)
			(end 0.12065 0.3048)
			(stroke
				(width 0.1)
				(type default)
			)
			(layer "B.Fab")
		)
		(fp_line
			(start 0.12065 -0.2794)
			(end -0.12065 -0.2794)
			(stroke
				(width 0.1)
				(type default)
			)
			(layer "B.Fab")
		)
		(fp_line
			(start 0.12065 -0.305054)
			(end 0.12065 -0.2794)
			(stroke
				(width 0.1)
				(type default)
			)
			(layer "B.Fab")
		)
		(fp_line
			(start -0.120396 0.3048)
			(end -0.120396 0.2794)
			(stroke
				(width 0.1)
				(type default)
			)
			(layer "B.Fab")
		)
		(fp_line
			(start -0.120396 0.2794)
			(end 0.12065 0.2794)
			(stroke
				(width 0.1)
				(type default)
			)
			(layer "B.Fab")
		)
		(fp_line
			(start -0.12065 -0.2794)
			(end -0.12065 -0.3048)
			(stroke
				(width 0.1)
				(type default)
			)
			(layer "B.Fab")
		)
		(fp_line
			(start -0.12065 -0.3048)
			(end -0.67945 -0.3048)
			(stroke
				(width 0.1)
				(type default)
			)
			(layer "B.Fab")
		)
		(fp_line
			(start -0.67945 0.3048)
			(end -0.120396 0.3048)
			(stroke
				(width 0.1)
				(type default)
			)
			(layer "B.Fab")
		)
		(fp_line
			(start -0.67945 -0.3048)
			(end -0.67945 0.3048)
			(stroke
				(width 0.1)
				(type default)
			)
			(layer "B.Fab")
		)
		(pad "1" smd circle
			(at 0.40005 0)
			(size 0 0)
			(layers "B.Cu" "B.Mask" "B.Paste")
			(net "P3V3_AUX")
		)
		(pad "2" smd circle
			(at -0.40005 0)
			(size 0 0)
			(layers "B.Cu" "B.Mask" "B.Paste")
			(net "GND")
		)
	)
	(footprint ""
		(layer "B.Cu")
		(at 35.179 -250.23699 -90)
		(property "Reference" "PC28"
			(at 0 0 90)
			(layer "B.SilkS")
			(hide yes)
			(effects
				(font
					(size 1.27 1.27)
				)
				(justify mirror)
			)
		)
		(property "Value" ""
			(at 0 0 90)
			(layer "B.Fab")
			(effects
				(font
					(size 1.27 1.27)
				)
				(justify mirror)
			)
		)
		(duplicate_pad_numbers_are_jumpers no)
		(fp_line
			(start -0.7874 0.4064)
			(end 0.7874 0.4064)
			(stroke
				(width 0.1524)
				(type default)
			)
			(layer "B.SilkS")
		)
		(fp_line
			(start 0.7874 0.4064)
			(end 0.7874 -0.4064)
			(stroke
				(width 0.1524)
				(type default)
			)
			(layer "B.SilkS")
		)
		(fp_line
			(start -0.7874 -0.4064)
			(end -0.7874 0.4064)
			(stroke
				(width 0.1524)
				(type default)
			)
			(layer "B.SilkS")
		)
		(fp_line
			(start 0.7874 -0.4064)
			(end -0.7874 -0.4064)
			(stroke
				(width 0.1524)
				(type default)
			)
			(layer "B.SilkS")
		)
		(fp_line
			(start -0.67945 0.3048)
			(end -0.120396 0.3048)
			(stroke
				(width 0.1)
				(type default)
			)
			(layer "B.Fab")
		)
		(fp_line
			(start -0.120396 0.3048)
			(end -0.120396 0.2794)
			(stroke
				(width 0.1)
				(type default)
			)
			(layer "B.Fab")
		)
		(fp_line
			(start 0.12065 0.3048)
			(end 0.67945 0.3048)
			(stroke
				(width 0.1)
				(type default)
			)
			(layer "B.Fab")
		)
		(fp_line
			(start 0.67945 0.3048)
			(end 0.67945 -0.305054)
			(stroke
				(width 0.1)
				(type default)
			)
			(layer "B.Fab")
		)
		(fp_line
			(start -0.120396 0.2794)
			(end 0.12065 0.2794)
			(stroke
				(width 0.1)
				(type default)
			)
			(layer "B.Fab")
		)
		(fp_line
			(start 0.12065 0.2794)
			(end 0.12065 0.3048)
			(stroke
				(width 0.1)
				(type default)
			)
			(layer "B.Fab")
		)
		(fp_line
			(start -0.12065 -0.2794)
			(end -0.12065 -0.3048)
			(stroke
				(width 0.1)
				(type default)
			)
			(layer "B.Fab")
		)
		(fp_line
			(start 0.12065 -0.2794)
			(end -0.12065 -0.2794)
			(stroke
				(width 0.1)
				(type default)
			)
			(layer "B.Fab")
		)
		(fp_line
			(start -0.67945 -0.3048)
			(end -0.67945 0.3048)
			(stroke
				(width 0.1)
				(type default)
			)
			(layer "B.Fab")
		)
		(fp_line
			(start -0.12065 -0.3048)
			(end -0.67945 -0.3048)
			(stroke
				(width 0.1)
				(type default)
			)
			(layer "B.Fab")
		)
		(fp_line
			(start 0.12065 -0.305054)
			(end 0.12065 -0.2794)
			(stroke
				(width 0.1)
				(type default)
			)
			(layer "B.Fab")
		)
		(fp_line
			(start 0.67945 -0.305054)
			(end 0.12065 -0.305054)
			(stroke
				(width 0.1)
				(type default)
			)
			(layer "B.Fab")
		)
		(pad "1" smd circle
			(at 0.40005 0 90)
			(size 0 0)
			(layers "B.Cu" "B.Mask" "B.Paste")
			(net "FAN_1_TIMER")
		)
		(pad "2" smd circle
			(at -0.40005 0 90)
			(size 0 0)
			(layers "B.Cu" "B.Mask" "B.Paste")
			(net "GND")
		)
	)
	(footprint ""
		(layer "B.Cu")
		(at 9.710166 -64.837056 -90)
		(property "Reference" "PR52"
			(at 0 0 90)
			(layer "B.SilkS")
			(hide yes)
			(effects
				(font
					(size 1.27 1.27)
				)
				(justify mirror)
			)
		)
		(property "Value" ""
			(at 0 0 90)
			(layer "B.Fab")
			(effects
				(font
					(size 1.27 1.27)
				)
				(justify mirror)
			)
		)
		(duplicate_pad_numbers_are_jumpers no)
		(fp_line
			(start -0.7874 0.4064)
			(end 0.7874 0.4064)
			(stroke
				(width 0.1524)
				(type default)
			)
			(layer "B.SilkS")
		)
		(fp_line
			(start 0.7874 0.4064)
			(end 0.7874 -0.4064)
			(stroke
				(width 0.1524)
				(type default)
			)
			(layer "B.SilkS")
		)
		(fp_line
			(start -0.7874 -0.4064)
			(end -0.7874 0.4064)
			(stroke
				(width 0.1524)
				(type default)
			)
			(layer "B.SilkS")
		)
		(fp_line
			(start 0.7874 -0.4064)
			(end -0.7874 -0.4064)
			(stroke
				(width 0.1524)
				(type default)
			)
			(layer "B.SilkS")
		)
		(fp_line
			(start -0.67945 0.3048)
			(end -0.120396 0.3048)
			(stroke
				(width 0.1)
				(type default)
			)
			(layer "B.Fab")
		)
		(fp_line
			(start -0.120396 0.3048)
			(end -0.120396 0.2794)
			(stroke
				(width 0.1)
				(type default)
			)
			(layer "B.Fab")
		)
		(fp_line
			(start 0.12065 0.3048)
			(end 0.67945 0.3048)
			(stroke
				(width 0.1)
				(type default)
			)
			(layer "B.Fab")
		)
		(fp_line
			(start 0.67945 0.3048)
			(end 0.67945 -0.305054)
			(stroke
				(width 0.1)
				(type default)
			)
			(layer "B.Fab")
		)
		(fp_line
			(start -0.120396 0.2794)
			(end 0.12065 0.2794)
			(stroke
				(width 0.1)
				(type default)
			)
			(layer "B.Fab")
		)
		(fp_line
			(start 0.12065 0.2794)
			(end 0.12065 0.3048)
			(stroke
				(width 0.1)
				(type default)
			)
			(layer "B.Fab")
		)
		(fp_line
			(start -0.12065 -0.2794)
			(end -0.12065 -0.3048)
			(stroke
				(width 0.1)
				(type default)
			)
			(layer "B.Fab")
		)
		(fp_line
			(start 0.12065 -0.2794)
			(end -0.12065 -0.2794)
			(stroke
				(width 0.1)
				(type default)
			)
			(layer "B.Fab")
		)
		(fp_line
			(start -0.67945 -0.3048)
			(end -0.67945 0.3048)
			(stroke
				(width 0.1)
				(type default)
			)
			(layer "B.Fab")
		)
		(fp_line
			(start -0.12065 -0.3048)
			(end -0.67945 -0.3048)
			(stroke
				(width 0.1)
				(type default)
			)
			(layer "B.Fab")
		)
		(fp_line
			(start 0.12065 -0.305054)
			(end 0.12065 -0.2794)
			(stroke
				(width 0.1)
				(type default)
			)
			(layer "B.Fab")
		)
		(fp_line
			(start 0.67945 -0.305054)
			(end 0.12065 -0.305054)
			(stroke
				(width 0.1)
				(type default)
			)
			(layer "B.Fab")
		)
		(pad "1" smd circle
			(at 0.40005 0 90)
			(size 0 0)
			(layers "B.Cu" "B.Mask" "B.Paste")
			(net "FAN_4_TEMP")
		)
		(pad "2" smd circle
			(at -0.40005 0 90)
			(size 0 0)
			(layers "B.Cu" "B.Mask" "B.Paste")
			(net "GND")
		)
	)
	(footprint ""
		(layer "B.Cu")
		(at 6.223 -65.405)
		(property "Reference" "PC3122"
			(at 0 0 0)
			(layer "B.SilkS")
			(hide yes)
			(effects
				(font
					(size 1.27 1.27)
				)
				(justify mirror)
			)
		)
		(property "Value" ""
			(at 0 0 0)
			(layer "B.Fab")
			(effects
				(font
					(size 1.27 1.27)
				)
				(justify mirror)
			)
		)
		(duplicate_pad_numbers_are_jumpers no)
		(fp_line
			(start -0.7874 -0.4064)
			(end -0.7874 0.4064)
			(stroke
				(width 0.1524)
				(type default)
			)
			(layer "B.SilkS")
		)
		(fp_line
			(start -0.7874 0.4064)
			(end 0.7874 0.4064)
			(stroke
				(width 0.1524)
				(type default)
			)
			(layer "B.SilkS")
		)
		(fp_line
			(start 0.7874 -0.4064)
			(end -0.7874 -0.4064)
			(stroke
				(width 0.1524)
				(type default)
			)
			(layer "B.SilkS")
		)
		(fp_line
			(start 0.7874 0.4064)
			(end 0.7874 -0.4064)
			(stroke
				(width 0.1524)
				(type default)
			)
			(layer "B.SilkS")
		)
		(fp_line
			(start -0.67945 -0.3048)
			(end -0.67945 0.3048)
			(stroke
				(width 0.1)
				(type default)
			)
			(layer "B.Fab")
		)
		(fp_line
			(start -0.67945 0.3048)
			(end -0.120396 0.3048)
			(stroke
				(width 0.1)
				(type default)
			)
			(layer "B.Fab")
		)
		(fp_line
			(start -0.12065 -0.3048)
			(end -0.67945 -0.3048)
			(stroke
				(width 0.1)
				(type default)
			)
			(layer "B.Fab")
		)
		(fp_line
			(start -0.12065 -0.2794)
			(end -0.12065 -0.3048)
			(stroke
				(width 0.1)
				(type default)
			)
			(layer "B.Fab")
		)
		(fp_line
			(start -0.120396 0.2794)
			(end 0.12065 0.2794)
			(stroke
				(width 0.1)
				(type default)
			)
			(layer "B.Fab")
		)
		(fp_line
			(start -0.120396 0.3048)
			(end -0.120396 0.2794)
			(stroke
				(width 0.1)
				(type default)
			)
			(layer "B.Fab")
		)
		(fp_line
			(start 0.12065 -0.305054)
			(end 0.12065 -0.2794)
			(stroke
				(width 0.1)
				(type default)
			)
			(layer "B.Fab")
		)
		(fp_line
			(start 0.12065 -0.2794)
			(end -0.12065 -0.2794)
			(stroke
				(width 0.1)
				(type default)
			)
			(layer "B.Fab")
		)
		(fp_line
			(start 0.12065 0.2794)
			(end 0.12065 0.3048)
			(stroke
				(width 0.1)
				(type default)
			)
			(layer "B.Fab")
		)
		(fp_line
			(start 0.12065 0.3048)
			(end 0.67945 0.3048)
			(stroke
				(width 0.1)
				(type default)
			)
			(layer "B.Fab")
		)
		(fp_line
			(start 0.67945 -0.305054)
			(end 0.12065 -0.305054)
			(stroke
				(width 0.1)
				(type default)
			)
			(layer "B.Fab")
		)
		(fp_line
			(start 0.67945 0.3048)
			(end 0.67945 -0.305054)
			(stroke
				(width 0.1)
				(type default)
			)
			(layer "B.Fab")
		)
		(pad "1" smd circle
			(at 0.40005 0 180)
			(size 0 0)
			(layers "B.Cu" "B.Mask" "B.Paste")
			(net "GND")
		)
		(pad "2" smd circle
			(at -0.40005 0 180)
			(size 0 0)
			(layers "B.Cu" "B.Mask" "B.Paste")
			(net "FAN_4_CLREF")
		)
	)
	(footprint ""
		(layer "B.Cu")
		(at 40.894 -132.334 180)
		(property "Reference" "R5427"
			(at 0 0 0)
			(layer "B.SilkS")
			(hide yes)
			(effects
				(font
					(size 1.27 1.27)
				)
				(justify mirror)
			)
		)
		(property "Value" ""
			(at 0 0 0)
			(layer "B.Fab")
			(effects
				(font
					(size 1.27 1.27)
				)
				(justify mirror)
			)
		)
		(duplicate_pad_numbers_are_jumpers no)
		(fp_line
			(start 0.7874 0.4064)
			(end 0.7874 -0.4064)
			(stroke
				(width 0.1524)
				(type default)
			)
			(layer "B.SilkS")
		)
		(fp_line
			(start 0.7874 -0.4064)
			(end -0.7874 -0.4064)
			(stroke
				(width 0.1524)
				(type default)
			)
			(layer "B.SilkS")
		)
		(fp_line
			(start -0.7874 0.4064)
			(end 0.7874 0.4064)
			(stroke
				(width 0.1524)
				(type default)
			)
			(layer "B.SilkS")
		)
		(fp_line
			(start -0.7874 -0.4064)
			(end -0.7874 0.4064)
			(stroke
				(width 0.1524)
				(type default)
			)
			(layer "B.SilkS")
		)
		(fp_line
			(start 0.67945 0.3048)
			(end 0.67945 -0.305054)
			(stroke
				(width 0.1)
				(type default)
			)
			(layer "B.Fab")
		)
		(fp_line
			(start 0.67945 -0.305054)
			(end 0.12065 -0.305054)
			(stroke
				(width 0.1)
				(type default)
			)
			(layer "B.Fab")
		)
		(fp_line
			(start 0.12065 0.3048)
			(end 0.67945 0.3048)
			(stroke
				(width 0.1)
				(type default)
			)
			(layer "B.Fab")
		)
		(fp_line
			(start 0.12065 0.2794)
			(end 0.12065 0.3048)
			(stroke
				(width 0.1)
				(type default)
			)
			(layer "B.Fab")
		)
		(fp_line
			(start 0.12065 -0.2794)
			(end -0.12065 -0.2794)
			(stroke
				(width 0.1)
				(type default)
			)
			(layer "B.Fab")
		)
		(fp_line
			(start 0.12065 -0.305054)
			(end 0.12065 -0.2794)
			(stroke
				(width 0.1)
				(type default)
			)
			(layer "B.Fab")
		)
		(fp_line
			(start -0.120396 0.3048)
			(end -0.120396 0.2794)
			(stroke
				(width 0.1)
				(type default)
			)
			(layer "B.Fab")
		)
		(fp_line
			(start -0.120396 0.2794)
			(end 0.12065 0.2794)
			(stroke
				(width 0.1)
				(type default)
			)
			(layer "B.Fab")
		)
		(fp_line
			(start -0.12065 -0.2794)
			(end -0.12065 -0.3048)
			(stroke
				(width 0.1)
				(type default)
			)
			(layer "B.Fab")
		)
		(fp_line
			(start -0.12065 -0.3048)
			(end -0.67945 -0.3048)
			(stroke
				(width 0.1)
				(type default)
			)
			(layer "B.Fab")
		)
		(fp_line
			(start -0.67945 0.3048)
			(end -0.120396 0.3048)
			(stroke
				(width 0.1)
				(type default)
			)
			(layer "B.Fab")
		)
		(fp_line
			(start -0.67945 -0.3048)
			(end -0.67945 0.3048)
			(stroke
				(width 0.1)
				(type default)
			)
			(layer "B.Fab")
		)
		(pad "1" smd rect
			(at 0.40005 0 180)
			(size 0.4572 0.508)
			(layers "B.Cu" "B.Mask" "B.Paste")
			(net "FAN_0_TACH_OL")
		)
		(pad "2" smd rect
			(at -0.40005 0 180)
			(size 0.4572 0.508)
			(layers "B.Cu" "B.Mask" "B.Paste")
			(net "GND")
		)
	)
	(footprint ""
		(layer "B.Cu")
		(at 45.466 -73.971912 90)
		(property "Reference" "PC33"
			(at 0 0 90)
			(layer "B.SilkS")
			(hide yes)
			(effects
				(font
					(size 1.27 1.27)
				)
				(justify mirror)
			)
		)
		(property "Value" ""
			(at 0 0 90)
			(layer "B.Fab")
			(effects
				(font
					(size 1.27 1.27)
				)
				(justify mirror)
			)
		)
		(duplicate_pad_numbers_are_jumpers no)
		(fp_line
			(start 0.7874 -0.4064)
			(end -0.7874 -0.4064)
			(stroke
				(width 0.1524)
				(type default)
			)
			(layer "B.SilkS")
		)
		(fp_line
			(start -0.7874 -0.4064)
			(end -0.7874 0.4064)
			(stroke
				(width 0.1524)
				(type default)
			)
			(layer "B.SilkS")
		)
		(fp_line
			(start 0.7874 0.4064)
			(end 0.7874 -0.4064)
			(stroke
				(width 0.1524)
				(type default)
			)
			(layer "B.SilkS")
		)
		(fp_line
			(start -0.7874 0.4064)
			(end 0.7874 0.4064)
			(stroke
				(width 0.1524)
				(type default)
			)
			(layer "B.SilkS")
		)
		(fp_line
			(start 0.67945 -0.305054)
			(end 0.12065 -0.305054)
			(stroke
				(width 0.1)
				(type default)
			)
			(layer "B.Fab")
		)
		(fp_line
			(start 0.12065 -0.305054)
			(end 0.12065 -0.2794)
			(stroke
				(width 0.1)
				(type default)
			)
			(layer "B.Fab")
		)
		(fp_line
			(start -0.12065 -0.3048)
			(end -0.67945 -0.3048)
			(stroke
				(width 0.1)
				(type default)
			)
			(layer "B.Fab")
		)
		(fp_line
			(start -0.67945 -0.3048)
			(end -0.67945 0.3048)
			(stroke
				(width 0.1)
				(type default)
			)
			(layer "B.Fab")
		)
		(fp_line
			(start 0.12065 -0.2794)
			(end -0.12065 -0.2794)
			(stroke
				(width 0.1)
				(type default)
			)
			(layer "B.Fab")
		)
		(fp_line
			(start -0.12065 -0.2794)
			(end -0.12065 -0.3048)
			(stroke
				(width 0.1)
				(type default)
			)
			(layer "B.Fab")
		)
		(fp_line
			(start 0.12065 0.2794)
			(end 0.12065 0.3048)
			(stroke
				(width 0.1)
				(type default)
			)
			(layer "B.Fab")
		)
		(fp_line
			(start -0.120396 0.2794)
			(end 0.12065 0.2794)
			(stroke
				(width 0.1)
				(type default)
			)
			(layer "B.Fab")
		)
		(fp_line
			(start 0.67945 0.3048)
			(end 0.67945 -0.305054)
			(stroke
				(width 0.1)
				(type default)
			)
			(layer "B.Fab")
		)
		(fp_line
			(start 0.12065 0.3048)
			(end 0.67945 0.3048)
			(stroke
				(width 0.1)
				(type default)
			)
			(layer "B.Fab")
		)
		(fp_line
			(start -0.120396 0.3048)
			(end -0.120396 0.2794)
			(stroke
				(width 0.1)
				(type default)
			)
			(layer "B.Fab")
		)
		(fp_line
			(start -0.67945 0.3048)
			(end -0.120396 0.3048)
			(stroke
				(width 0.1)
				(type default)
			)
			(layer "B.Fab")
		)
		(pad "1" smd circle
			(at 0.40005 0 270)
			(size 0 0)
			(layers "B.Cu" "B.Mask" "B.Paste")
			(net "FAN_2_SS")
		)
		(pad "2" smd circle
			(at -0.40005 0 270)
			(size 0 0)
			(layers "B.Cu" "B.Mask" "B.Paste")
			(net "GND")
		)
	)
	(footprint ""
		(layer "B.Cu")
		(at 34.925 -86.106)
		(property "Reference" "PC30"
			(at 0 0 0)
			(layer "B.SilkS")
			(hide yes)
			(effects
				(font
					(size 1.27 1.27)
				)
				(justify mirror)
			)
		)
		(property "Value" ""
			(at 0 0 0)
			(layer "B.Fab")
			(effects
				(font
					(size 1.27 1.27)
				)
				(justify mirror)
			)
		)
		(duplicate_pad_numbers_are_jumpers no)
		(fp_line
			(start -1.524 -0.762)
			(end -1.524 0.762)
			(stroke
				(width 0.1524)
				(type default)
			)
			(layer "B.SilkS")
		)
		(fp_line
			(start -1.524 0.762)
			(end 1.524 0.762)
			(stroke
				(width 0.1524)
				(type default)
			)
			(layer "B.SilkS")
		)
		(fp_line
			(start 1.524 -0.762)
			(end -1.524 -0.762)
			(stroke
				(width 0.1524)
				(type default)
			)
			(layer "B.SilkS")
		)
		(fp_line
			(start 1.524 0.762)
			(end 1.524 -0.762)
			(stroke
				(width 0.1524)
				(type default)
			)
			(layer "B.SilkS")
		)
		(fp_line
			(start -1.1049 -0.724916)
			(end 1.1049 -0.724916)
			(stroke
				(width 0.1)
				(type default)
			)
			(layer "B.Fab")
		)
		(fp_line
			(start -1.1049 0.724916)
			(end -1.1049 -0.724916)
			(stroke
				(width 0.1)
				(type default)
			)
			(layer "B.Fab")
		)
		(fp_line
			(start 1.1049 -0.724916)
			(end 1.1049 0.724916)
			(stroke
				(width 0.1)
				(type default)
			)
			(layer "B.Fab")
		)
		(fp_line
			(start 1.1049 0.724916)
			(end -1.1049 0.724916)
			(stroke
				(width 0.1)
				(type default)
			)
			(layer "B.Fab")
		)
		(pad "1" smd rect
			(at 0.889 0)
			(size 1.016 1.27)
			(layers "B.Cu" "B.Mask" "B.Paste")
			(net "P52V_FAN_2")
		)
		(pad "2" smd rect
			(at -0.889 0)
			(size 1.016 1.27)
			(layers "B.Cu" "B.Mask" "B.Paste")
			(net "GND")
		)
	)
	(footprint ""
		(layer "B.Cu")
		(at 14.255242 -79.804768 180)
		(property "Reference" "PU7"
			(at -6.064758 -2.234438 0)
			(unlocked yes)
			(layer "B.SilkS")
			(effects
				(font
					(size 0.7874 0.5842)
					(thickness 0.1524)
				)
				(justify left mirror)
			)
		)
		(property "Value" ""
			(at 0 0 0)
			(layer "B.Fab")
			(effects
				(font
					(size 1.27 1.27)
				)
				(justify mirror)
			)
		)
		(duplicate_pad_numbers_are_jumpers no)
		(fp_line
			(start 2.549906 2.549906)
			(end 2.4384 2.549906)
			(stroke
				(width 0.1524)
				(type default)
			)
			(layer "B.SilkS")
		)
		(fp_line
			(start 2.549906 2.2352)
			(end 2.549906 2.549906)
			(stroke
				(width 0.1524)
				(type default)
			)
			(layer "B.SilkS")
		)
		(fp_line
			(start 2.549906 1.4986)
			(end 2.549906 1.7526)
			(stroke
				(width 0.1524)
				(type default)
			)
			(layer "B.SilkS")
		)
		(fp_line
			(start 2.549906 0.6858)
			(end 2.549906 0.9144)
			(stroke
				(width 0.1524)
				(type default)
			)
			(layer "B.SilkS")
		)
		(fp_line
			(start 2.549906 -0.9144)
			(end 2.549906 0.1016)
			(stroke
				(width 0.1524)
				(type default)
			)
			(layer "B.SilkS")
		)
		(fp_line
			(start 2.549906 -1.7526)
			(end 2.549906 -1.4986)
			(stroke
				(width 0.1524)
				(type default)
			)
			(layer "B.SilkS")
		)
		(fp_line
			(start 2.549906 -2.549906)
			(end 2.549906 -2.2352)
			(stroke
				(width 0.1524)
				(type default)
			)
			(layer "B.SilkS")
		)
		(fp_line
			(start 2.4384 -2.549906)
			(end 2.549906 -2.549906)
			(stroke
				(width 0.1524)
				(type default)
			)
			(layer "B.SilkS")
		)
		(fp_line
			(start 2.199894 -3.9624)
			(end 2.199894 -2.9464)
			(stroke
				(width 0.1524)
				(type default)
			)
			(layer "B.SilkS")
		)
		(fp_line
			(start 1.800098 2.9464)
			(end 1.800098 3.4544)
			(stroke
				(width 0.1524)
				(type default)
			)
			(layer "B.SilkS")
		)
		(fp_line
			(start 0.199898 -3.4544)
			(end 0.199898 -2.9464)
			(stroke
				(width 0.1524)
				(type default)
			)
			(layer "B.SilkS")
		)
		(fp_line
			(start -0.199898 2.9464)
			(end -0.199898 3.9624)
			(stroke
				(width 0.1524)
				(type default)
			)
			(layer "B.SilkS")
		)
		(fp_line
			(start -1.800098 -3.9624)
			(end -1.800098 -2.9464)
			(stroke
				(width 0.1524)
				(type default)
			)
			(layer "B.SilkS")
		)
		(fp_line
			(start -2.199894 2.9464)
			(end -2.199894 3.4544)
			(stroke
				(width 0.1524)
				(type default)
			)
			(layer "B.SilkS")
		)
		(fp_line
			(start -2.4384 2.549906)
			(end -2.549906 2.549906)
			(stroke
				(width 0.1524)
				(type default)
			)
			(layer "B.SilkS")
		)
		(fp_line
			(start -2.549906 2.549906)
			(end -2.549906 2.2352)
			(stroke
				(width 0.1524)
				(type default)
			)
			(layer "B.SilkS")
		)
		(fp_line
			(start -2.549906 1.7526)
			(end -2.549906 1.4986)
			(stroke
				(width 0.1524)
				(type default)
			)
			(layer "B.SilkS")
		)
		(fp_line
			(start -2.549906 0.9144)
			(end -2.549906 -0.1016)
			(stroke
				(width 0.1524)
				(type default)
			)
			(layer "B.SilkS")
		)
		(fp_line
			(start -2.549906 -0.6858)
			(end -2.549906 -0.9144)
			(stroke
				(width 0.1524)
				(type default)
			)
			(layer "B.SilkS")
		)
		(fp_line
			(start -2.549906 -1.4986)
			(end -2.549906 -1.7526)
			(stroke
				(width 0.1524)
				(type default)
			)
			(layer "B.SilkS")
		)
		(fp_line
			(start -2.549906 -2.2352)
			(end -2.549906 -2.549906)
			(stroke
				(width 0.1524)
				(type default)
			)
			(layer "B.SilkS")
		)
		(fp_line
			(start -2.549906 -2.549906)
			(end -2.4384 -2.549906)
			(stroke
				(width 0.1524)
				(type default)
			)
			(layer "B.SilkS")
		)
		(fp_poly
			(pts
				(xy 3.587242 -1.524) (xy 2.939034 -1.199896) (xy 3.587242 -0.875792)
			)
			(stroke
				(width 0)
				(type default)
			)
			(fill yes)
			(layer "B.SilkS")
		)
		(fp_line
			(start 2.549906 2.549906)
			(end -2.549906 2.549906)
			(stroke
				(width 0.1)
				(type default)
			)
			(layer "B.Fab")
		)
		(fp_line
			(start 2.549906 -2.549906)
			(end 2.549906 2.549906)
			(stroke
				(width 0.1)
				(type default)
			)
			(layer "B.Fab")
		)
		(fp_line
			(start 2.199894 -3.9624)
			(end 2.199894 -2.9464)
			(stroke
				(width 0.1)
				(type default)
			)
			(layer "B.Fab")
		)
		(fp_line
			(start 1.800098 2.9464)
			(end 1.800098 3.4544)
			(stroke
				(width 0.1)
				(type default)
			)
			(layer "B.Fab")
		)
		(fp_line
			(start 0.199898 -3.4544)
			(end 0.199898 -2.9464)
			(stroke
				(width 0.1)
				(type default)
			)
			(layer "B.Fab")
		)
		(fp_line
			(start -0.199898 2.9464)
			(end -0.199898 3.9624)
			(stroke
				(width 0.1)
				(type default)
			)
			(layer "B.Fab")
		)
		(fp_line
			(start -1.800098 -3.9624)
			(end -1.800098 -2.9464)
			(stroke
				(width 0.1)
				(type default)
			)
			(layer "B.Fab")
		)
		(fp_line
			(start -2.199894 2.9464)
			(end -2.199894 3.4544)
			(stroke
				(width 0.1)
				(type default)
			)
			(layer "B.Fab")
		)
		(fp_line
			(start -2.549906 2.549906)
			(end -2.549906 -2.549906)
			(stroke
				(width 0.1)
				(type default)
			)
			(layer "B.Fab")
		)
		(fp_line
			(start -2.549906 -2.549906)
			(end 2.549906 -2.549906)
			(stroke
				(width 0.1)
				(type default)
			)
			(layer "B.Fab")
		)
		(fp_poly
			(pts
				(xy 3.7084 -1.584706) (xy 2.939034 -1.199896) (xy 3.7084 -0.81534)
			)
			(stroke
				(width 0)
				(type default)
			)
			(fill yes)
			(layer "B.Fab")
		)
		(fp_text user "3"
			(at 3.299968 1.1938 90)
			(unlocked yes)
			(layer "B.SilkS")
			(effects
				(font
					(size 0.635 0.4064)
					(thickness 0.1524)
				)
				(justify mirror)
			)
		)
		(fp_text user "30"
			(at 2.9464 -3.045968 180)
			(unlocked yes)
			(layer "B.SilkS")
			(effects
				(font
					(size 0.635 0.4064)
					(thickness 0.1524)
				)
				(justify mirror)
			)
		)
		(fp_text user "4"
			(at 2.6416 3.151632 180)
			(unlocked yes)
			(layer "B.SilkS")
			(effects
				(font
					(size 0.635 0.4064)
					(thickness 0.1524)
				)
				(justify mirror)
			)
		)
		(fp_text user "19"
			(at -2.8448 -3.096768 180)
			(unlocked yes)
			(layer "B.SilkS")
			(effects
				(font
					(size 0.635 0.4064)
					(thickness 0.1524)
				)
				(justify mirror)
			)
		)
		(fp_text user "15"
			(at -2.8956 3.126232 180)
			(unlocked yes)
			(layer "B.SilkS")
			(effects
				(font
					(size 0.635 0.4064)
					(thickness 0.1524)
				)
				(justify mirror)
			)
		)
		(fp_text user "18"
			(at -3.304032 -1.2192 90)
			(unlocked yes)
			(layer "B.SilkS")
			(effects
				(font
					(size 0.635 0.4064)
					(thickness 0.1524)
				)
				(justify mirror)
			)
		)
		(fp_text user "16"
			(at -3.329432 1.2192 90)
			(unlocked yes)
			(layer "B.SilkS")
			(effects
				(font
					(size 0.635 0.4064)
					(thickness 0.1524)
				)
				(justify mirror)
			)
		)
		(fp_text user "3"
			(at 3.299968 1.1938 90)
			(unlocked yes)
			(layer "B.Fab")
			(effects
				(font
					(size 0.635 0.4064)
					(thickness 0.1524)
				)
				(justify mirror)
			)
		)
		(fp_text user "30"
			(at 2.9464 -3.045968 180)
			(unlocked yes)
			(layer "B.Fab")
			(effects
				(font
					(size 0.635 0.4064)
					(thickness 0.1524)
				)
				(justify mirror)
			)
		)
		(fp_text user "4"
			(at 2.6416 3.151632 180)
			(unlocked yes)
			(layer "B.Fab")
			(effects
				(font
					(size 0.635 0.4064)
					(thickness 0.1524)
				)
				(justify mirror)
			)
		)
		(fp_text user "19"
			(at -2.8448 -3.096768 180)
			(unlocked yes)
			(layer "B.Fab")
			(effects
				(font
					(size 0.635 0.4064)
					(thickness 0.1524)
				)
				(justify mirror)
			)
		)
		(fp_text user "15"
			(at -2.8956 3.126232 180)
			(unlocked yes)
			(layer "B.Fab")
			(effects
				(font
					(size 0.635 0.4064)
					(thickness 0.1524)
				)
				(justify mirror)
			)
		)
		(fp_text user "18"
			(at -3.304032 -1.2192 90)
			(unlocked yes)
			(layer "B.Fab")
			(effects
				(font
					(size 0.635 0.4064)
					(thickness 0.1524)
				)
				(justify mirror)
			)
		)
		(fp_text user "16"
			(at -3.329432 1.2192 90)
			(unlocked yes)
			(layer "B.Fab")
			(effects
				(font
					(size 0.635 0.4064)
					(thickness 0.1524)
				)
				(justify mirror)
			)
		)
		(pad "1" smd circle
			(at 1.599946 -1.199896 90)
			(size 0 0)
			(layers "B.Cu" "B.Mask" "B.Paste")
			(net "P52V_HSC")
		)
		(pad "2" smd rect
			(at 1.549908 0.40005 270)
			(size 0.3048 2.5146)
			(layers "B.Cu" "B.Mask" "B.Paste")
			(net "P52V_HSC")
		)
		(pad "3" smd rect
			(at 1.549908 1.199896 270)
			(size 0.3048 2.5146)
			(layers "B.Cu" "B.Mask" "B.Paste")
			(net "P52V_FAN_5")
		)
		(pad "4" smd circle
			(at 2.199894 2.350008 180)
			(size 0 0)
			(layers "B.Cu" "B.Mask" "B.Paste")
			(net "P52V_FAN_5")
		)
		(pad "5" smd rect
			(at 1.800098 2.350008)
			(size 0.1778 0.9144)
			(layers "B.Cu" "B.Mask" "B.Paste")
			(net "P52V_FAN_5")
		)
		(pad "6" smd rect
			(at 1.400048 2.350008)
			(size 0.1778 0.9144)
			(layers "B.Cu" "B.Mask" "B.Paste")
			(net "P52V_FAN_5")
		)
		(pad "7" smd rect
			(at 0.999998 2.350008)
			(size 0.1778 0.9144)
			(layers "B.Cu" "B.Mask" "B.Paste")
			(net "P52V_FAN_5")
		)
		(pad "8" smd rect
			(at 0.599948 2.350008)
			(size 0.1778 0.9144)
			(layers "B.Cu" "B.Mask" "B.Paste")
			(net "P52V_FAN_5")
		)
		(pad "9" smd rect
			(at 0.199898 2.350008)
			(size 0.1778 0.9144)
			(layers "B.Cu" "B.Mask" "B.Paste")
			(net "P52V_FAN_5")
		)
		(pad "10" smd rect
			(at -0.199898 2.350008)
			(size 0.1778 0.9144)
			(layers "B.Cu" "B.Mask" "B.Paste")
			(net "P52V_FAN_5")
		)
		(pad "11" smd rect
			(at -0.599948 2.350008)
			(size 0.1778 0.9144)
			(layers "B.Cu" "B.Mask" "B.Paste")
			(net "P52V_FAN_5")
		)
		(pad "12" smd rect
			(at -0.999998 2.350008)
			(size 0.1778 0.9144)
			(layers "B.Cu" "B.Mask" "B.Paste")
			(net "P52V_FAN_5")
		)
		(pad "13" smd rect
			(at -1.400048 2.350008)
			(size 0.1778 0.9144)
			(layers "B.Cu" "B.Mask" "B.Paste")
			(net "P52V_FAN_5")
		)
		(pad "14" smd rect
			(at -1.800098 2.350008)
			(size 0.1778 0.9144)
			(layers "B.Cu" "B.Mask" "B.Paste")
			(net "P52V_FAN_5")
		)
		(pad "15" smd circle
			(at -2.199894 2.350008 180)
			(size 0 0)
			(layers "B.Cu" "B.Mask" "B.Paste")
			(net "P52V_FAN_5")
		)
		(pad "16" smd rect
			(at -1.549908 1.199896 270)
			(size 0.3048 2.5146)
			(layers "B.Cu" "B.Mask" "B.Paste")
			(net "P52V_FAN_5")
		)
		(pad "17" smd rect
			(at -1.549908 -0.40005 270)
			(size 0.3048 2.5146)
			(layers "B.Cu" "B.Mask" "B.Paste")
			(net "P52V_FAN_5")
		)
		(pad "18" smd rect
			(at -1.549908 -1.199896 270)
			(size 0.3048 2.5146)
			(layers "B.Cu" "B.Mask" "B.Paste")
			(net "P52V_HSC")
		)
		(pad "19" smd circle
			(at -2.199894 -2.350008)
			(size 0 0)
			(layers "B.Cu" "B.Mask" "B.Paste")
			(net "FAN_5_CS")
		)
		(pad "20" smd rect
			(at -1.800098 -2.350008)
			(size 0.1778 0.9144)
			(layers "B.Cu" "B.Mask" "B.Paste")
			(net "FAN_5_IMON")
		)
		(pad "21" smd rect
			(at -1.400048 -2.350008)
			(size 0.1778 0.9144)
			(layers "B.Cu" "B.Mask" "B.Paste")
			(net "FAN_5_SS")
		)
		(pad "22" smd rect
			(at -0.999998 -2.350008)
			(size 0.1778 0.9144)
			(layers "B.Cu" "B.Mask" "B.Paste")
			(net "FAN_5_FAULT")
		)
		(pad "23" smd rect
			(at -0.599948 -2.350008)
			(size 0.1778 0.9144)
			(layers "B.Cu" "B.Mask" "B.Paste")
			(net "FAN_5_TIMER")
		)
		(pad "24" smd rect
			(at -0.199898 -2.350008)
			(size 0.1778 0.9144)
			(layers "B.Cu" "B.Mask" "B.Paste")
			(net "FAN_5_CLREF")
		)
		(pad "25" smd rect
			(at 0.199898 -2.350008)
			(size 0.1778 0.9144)
			(layers "B.Cu" "B.Mask" "B.Paste")
			(net "GND")
		)
		(pad "26" smd rect
			(at 0.599948 -2.350008)
			(size 0.1778 0.9144)
			(layers "B.Cu" "B.Mask" "B.Paste")
			(net "FAN_5_ON")
		)
		(pad "27" smd rect
			(at 0.999998 -2.350008)
			(size 0.1778 0.9144)
			(layers "B.Cu" "B.Mask" "B.Paste")
			(net "FAN_5_P3V_R")
		)
		(pad "28" smd rect
			(at 1.400048 -2.350008)
			(size 0.1778 0.9144)
			(layers "B.Cu" "B.Mask" "B.Paste")
			(net "FAN_5_P5V")
		)
		(pad "29" smd rect
			(at 1.800098 -2.350008)
			(size 0.1778 0.9144)
			(layers "B.Cu" "B.Mask" "B.Paste")
			(net "FAN_5_TEMP")
		)
		(pad "30" smd circle
			(at 2.199894 -2.350008)
			(size 0 0)
			(layers "B.Cu" "B.Mask" "B.Paste")
			(net "FAN_5_MODE")
		)
	)
	(footprint ""
		(layer "B.Cu")
		(at 39.968932 -255.905)
		(property "Reference" "U377"
			(at -3.824732 -0.81153 0)
			(unlocked yes)
			(layer "B.SilkS")
			(effects
				(font
					(size 0.7874 0.5842)
					(thickness 0.1524)
				)
				(justify mirror)
			)
		)
		(property "Value" ""
			(at 0 0 0)
			(layer "B.Fab")
			(effects
				(font
					(size 1.27 1.27)
				)
				(justify mirror)
			)
		)
		(duplicate_pad_numbers_are_jumpers no)
		(fp_line
			(start -1.7018 -1.1176)
			(end -1.7018 1.1176)
			(stroke
				(width 0.1524)
				(type default)
			)
			(layer "B.SilkS")
		)
		(fp_line
			(start -1.7018 -1.1176)
			(end -0.254 -1.1176)
			(stroke
				(width 0.1524)
				(type default)
			)
			(layer "B.SilkS")
		)
		(fp_line
			(start -1.7018 1.1176)
			(end 1.7018 1.1176)
			(stroke
				(width 0.1524)
				(type default)
			)
			(layer "B.SilkS")
		)
		(fp_line
			(start -0.254 -1.1176)
			(end 0 -0.7112)
			(stroke
				(width 0.1524)
				(type default)
			)
			(layer "B.SilkS")
		)
		(fp_line
			(start 0 -0.7112)
			(end 0.254 -1.1176)
			(stroke
				(width 0.1524)
				(type default)
			)
			(layer "B.SilkS")
		)
		(fp_line
			(start 0.254 -1.1176)
			(end 1.7018 -1.1176)
			(stroke
				(width 0.1524)
				(type default)
			)
			(layer "B.SilkS")
		)
		(fp_line
			(start 1.7018 1.1176)
			(end 1.7018 -1.1176)
			(stroke
				(width 0.1524)
				(type default)
			)
			(layer "B.SilkS")
		)
		(fp_poly
			(pts
				(xy 1.8161 -0.675386) (xy 2.4003 -0.446786) (xy 2.4003 -0.878586)
			)
			(stroke
				(width 0)
				(type default)
			)
			(fill yes)
			(layer "B.SilkS")
		)
		(fp_line
			(start -1.5494 -1.1176)
			(end -1.5494 1.1176)
			(stroke
				(width 0.1)
				(type default)
			)
			(layer "B.Fab")
		)
		(fp_line
			(start -1.5494 -1.1176)
			(end -0.254 -1.1176)
			(stroke
				(width 0.1)
				(type default)
			)
			(layer "B.Fab")
		)
		(fp_line
			(start -1.5494 1.1176)
			(end 1.5494 1.1176)
			(stroke
				(width 0.1)
				(type default)
			)
			(layer "B.Fab")
		)
		(fp_line
			(start -0.254 -1.1176)
			(end 0.254 -1.1176)
			(stroke
				(width 0.1)
				(type default)
			)
			(layer "B.Fab")
		)
		(fp_line
			(start 0.254 -1.1176)
			(end 1.5494 -1.1176)
			(stroke
				(width 0.1)
				(type default)
			)
			(layer "B.Fab")
		)
		(fp_line
			(start 1.5494 1.1176)
			(end 1.5494 -1.1176)
			(stroke
				(width 0.1)
				(type default)
			)
			(layer "B.Fab")
		)
		(fp_poly
			(pts
				(xy 1.8161 -0.675386) (xy 2.4003 -0.446786) (xy 2.4003 -0.878586)
			)
			(stroke
				(width 0)
				(type default)
			)
			(fill yes)
			(layer "B.Fab")
		)
		(pad "1" smd rect
			(at 0.962406 -0.649986 270)
			(size 0.3302 1.1684)
			(layers "B.Cu" "B.Mask" "B.Paste")
			(net "FAN_0_PRESENT_R")
		)
		(pad "2" smd rect
			(at 0.962406 0 270)
			(size 0.3302 1.1684)
			(layers "B.Cu" "B.Mask" "B.Paste")
			(net "P52V_FAN_0_BUFF_EN_R")
		)
		(pad "3" smd rect
			(at 0.962406 0.649986 270)
			(size 0.3302 1.1684)
			(layers "B.Cu" "B.Mask" "B.Paste")
			(net "GND")
		)
		(pad "4" smd rect
			(at -0.962406 0.649986 270)
			(size 0.3302 1.1684)
			(layers "B.Cu" "B.Mask" "B.Paste")
			(net "P52V_FAN_0_EN")
		)
		(pad "5" smd rect
			(at -0.962406 -0.649986 270)
			(size 0.3302 1.1684)
			(layers "B.Cu" "B.Mask" "B.Paste")
			(net "P3V3_AUX")
		)
	)
	(footprint ""
		(layer "B.Cu")
		(at 41.746932 -60.382912 -90)
		(property "Reference" "PC60"
			(at 0 0 90)
			(layer "B.SilkS")
			(hide yes)
			(effects
				(font
					(size 1.27 1.27)
				)
				(justify mirror)
			)
		)
		(property "Value" ""
			(at 0 0 90)
			(layer "B.Fab")
			(effects
				(font
					(size 1.27 1.27)
				)
				(justify mirror)
			)
		)
		(duplicate_pad_numbers_are_jumpers no)
		(fp_line
			(start -1.524 0.762)
			(end 1.524 0.762)
			(stroke
				(width 0.1524)
				(type default)
			)
			(layer "B.SilkS")
		)
		(fp_line
			(start 1.524 0.762)
			(end 1.524 -0.762)
			(stroke
				(width 0.1524)
				(type default)
			)
			(layer "B.SilkS")
		)
		(fp_line
			(start -1.524 -0.762)
			(end -1.524 0.762)
			(stroke
				(width 0.1524)
				(type default)
			)
			(layer "B.SilkS")
		)
		(fp_line
			(start 1.524 -0.762)
			(end -1.524 -0.762)
			(stroke
				(width 0.1524)
				(type default)
			)
			(layer "B.SilkS")
		)
		(fp_line
			(start -1.1049 0.724916)
			(end -1.1049 -0.724916)
			(stroke
				(width 0.1)
				(type default)
			)
			(layer "B.Fab")
		)
		(fp_line
			(start 1.1049 0.724916)
			(end -1.1049 0.724916)
			(stroke
				(width 0.1)
				(type default)
			)
			(layer "B.Fab")
		)
		(fp_line
			(start -1.1049 -0.724916)
			(end 1.1049 -0.724916)
			(stroke
				(width 0.1)
				(type default)
			)
			(layer "B.Fab")
		)
		(fp_line
			(start 1.1049 -0.724916)
			(end 1.1049 0.724916)
			(stroke
				(width 0.1)
				(type default)
			)
			(layer "B.Fab")
		)
		(pad "1" smd rect
			(at 0.889 0 270)
			(size 1.016 1.27)
			(layers "B.Cu" "B.Mask" "B.Paste")
			(net "P52V_HSC")
		)
		(pad "2" smd rect
			(at -0.889 0 270)
			(size 1.016 1.27)
			(layers "B.Cu" "B.Mask" "B.Paste")
			(net "GND")
		)
	)
	(footprint ""
		(layer "B.Cu")
		(at 16.129 -73.971912 90)
		(property "Reference" "PC47"
			(at 0 0 90)
			(layer "B.SilkS")
			(hide yes)
			(effects
				(font
					(size 1.27 1.27)
				)
				(justify mirror)
			)
		)
		(property "Value" ""
			(at 0 0 90)
			(layer "B.Fab")
			(effects
				(font
					(size 1.27 1.27)
				)
				(justify mirror)
			)
		)
		(duplicate_pad_numbers_are_jumpers no)
		(fp_line
			(start 0.7874 -0.4064)
			(end -0.7874 -0.4064)
			(stroke
				(width 0.1524)
				(type default)
			)
			(layer "B.SilkS")
		)
		(fp_line
			(start -0.7874 -0.4064)
			(end -0.7874 0.4064)
			(stroke
				(width 0.1524)
				(type default)
			)
			(layer "B.SilkS")
		)
		(fp_line
			(start 0.7874 0.4064)
			(end 0.7874 -0.4064)
			(stroke
				(width 0.1524)
				(type default)
			)
			(layer "B.SilkS")
		)
		(fp_line
			(start -0.7874 0.4064)
			(end 0.7874 0.4064)
			(stroke
				(width 0.1524)
				(type default)
			)
			(layer "B.SilkS")
		)
		(fp_line
			(start 0.67945 -0.305054)
			(end 0.12065 -0.305054)
			(stroke
				(width 0.1)
				(type default)
			)
			(layer "B.Fab")
		)
		(fp_line
			(start 0.12065 -0.305054)
			(end 0.12065 -0.2794)
			(stroke
				(width 0.1)
				(type default)
			)
			(layer "B.Fab")
		)
		(fp_line
			(start -0.12065 -0.3048)
			(end -0.67945 -0.3048)
			(stroke
				(width 0.1)
				(type default)
			)
			(layer "B.Fab")
		)
		(fp_line
			(start -0.67945 -0.3048)
			(end -0.67945 0.3048)
			(stroke
				(width 0.1)
				(type default)
			)
			(layer "B.Fab")
		)
		(fp_line
			(start 0.12065 -0.2794)
			(end -0.12065 -0.2794)
			(stroke
				(width 0.1)
				(type default)
			)
			(layer "B.Fab")
		)
		(fp_line
			(start -0.12065 -0.2794)
			(end -0.12065 -0.3048)
			(stroke
				(width 0.1)
				(type default)
			)
			(layer "B.Fab")
		)
		(fp_line
			(start 0.12065 0.2794)
			(end 0.12065 0.3048)
			(stroke
				(width 0.1)
				(type default)
			)
			(layer "B.Fab")
		)
		(fp_line
			(start -0.120396 0.2794)
			(end 0.12065 0.2794)
			(stroke
				(width 0.1)
				(type default)
			)
			(layer "B.Fab")
		)
		(fp_line
			(start 0.67945 0.3048)
			(end 0.67945 -0.305054)
			(stroke
				(width 0.1)
				(type default)
			)
			(layer "B.Fab")
		)
		(fp_line
			(start 0.12065 0.3048)
			(end 0.67945 0.3048)
			(stroke
				(width 0.1)
				(type default)
			)
			(layer "B.Fab")
		)
		(fp_line
			(start -0.120396 0.3048)
			(end -0.120396 0.2794)
			(stroke
				(width 0.1)
				(type default)
			)
			(layer "B.Fab")
		)
		(fp_line
			(start -0.67945 0.3048)
			(end -0.120396 0.3048)
			(stroke
				(width 0.1)
				(type default)
			)
			(layer "B.Fab")
		)
		(pad "1" smd circle
			(at 0.40005 0 270)
			(size 0 0)
			(layers "B.Cu" "B.Mask" "B.Paste")
			(net "FAN_5_TIMER")
		)
		(pad "2" smd circle
			(at -0.40005 0 270)
			(size 0 0)
			(layers "B.Cu" "B.Mask" "B.Paste")
			(net "GND")
		)
	)
	(footprint ""
		(layer "B.Cu")
		(at 39.47668 -258.562856 90)
		(property "Reference" "PC4"
			(at 0 0 90)
			(layer "B.SilkS")
			(hide yes)
			(effects
				(font
					(size 1.27 1.27)
				)
				(justify mirror)
			)
		)
		(property "Value" ""
			(at 0 0 90)
			(layer "B.Fab")
			(effects
				(font
					(size 1.27 1.27)
				)
				(justify mirror)
			)
		)
		(duplicate_pad_numbers_are_jumpers no)
		(fp_line
			(start 0.7874 -0.4064)
			(end -0.7874 -0.4064)
			(stroke
				(width 0.1524)
				(type default)
			)
			(layer "B.SilkS")
		)
		(fp_line
			(start -0.7874 -0.4064)
			(end -0.7874 0.4064)
			(stroke
				(width 0.1524)
				(type default)
			)
			(layer "B.SilkS")
		)
		(fp_line
			(start 0.7874 0.4064)
			(end 0.7874 -0.4064)
			(stroke
				(width 0.1524)
				(type default)
			)
			(layer "B.SilkS")
		)
		(fp_line
			(start -0.7874 0.4064)
			(end 0.7874 0.4064)
			(stroke
				(width 0.1524)
				(type default)
			)
			(layer "B.SilkS")
		)
		(fp_line
			(start 0.67945 -0.305054)
			(end 0.12065 -0.305054)
			(stroke
				(width 0.1)
				(type default)
			)
			(layer "B.Fab")
		)
		(fp_line
			(start 0.12065 -0.305054)
			(end 0.12065 -0.2794)
			(stroke
				(width 0.1)
				(type default)
			)
			(layer "B.Fab")
		)
		(fp_line
			(start -0.12065 -0.3048)
			(end -0.67945 -0.3048)
			(stroke
				(width 0.1)
				(type default)
			)
			(layer "B.Fab")
		)
		(fp_line
			(start -0.67945 -0.3048)
			(end -0.67945 0.3048)
			(stroke
				(width 0.1)
				(type default)
			)
			(layer "B.Fab")
		)
		(fp_line
			(start 0.12065 -0.2794)
			(end -0.12065 -0.2794)
			(stroke
				(width 0.1)
				(type default)
			)
			(layer "B.Fab")
		)
		(fp_line
			(start -0.12065 -0.2794)
			(end -0.12065 -0.3048)
			(stroke
				(width 0.1)
				(type default)
			)
			(layer "B.Fab")
		)
		(fp_line
			(start 0.12065 0.2794)
			(end 0.12065 0.3048)
			(stroke
				(width 0.1)
				(type default)
			)
			(layer "B.Fab")
		)
		(fp_line
			(start -0.120396 0.2794)
			(end 0.12065 0.2794)
			(stroke
				(width 0.1)
				(type default)
			)
			(layer "B.Fab")
		)
		(fp_line
			(start 0.67945 0.3048)
			(end 0.67945 -0.305054)
			(stroke
				(width 0.1)
				(type default)
			)
			(layer "B.Fab")
		)
		(fp_line
			(start 0.12065 0.3048)
			(end 0.67945 0.3048)
			(stroke
				(width 0.1)
				(type default)
			)
			(layer "B.Fab")
		)
		(fp_line
			(start -0.120396 0.3048)
			(end -0.120396 0.2794)
			(stroke
				(width 0.1)
				(type default)
			)
			(layer "B.Fab")
		)
		(fp_line
			(start -0.67945 0.3048)
			(end -0.120396 0.3048)
			(stroke
				(width 0.1)
				(type default)
			)
			(layer "B.Fab")
		)
		(pad "1" smd circle
			(at 0.40005 0 270)
			(size 0 0)
			(layers "B.Cu" "B.Mask" "B.Paste")
			(net "FAN_0_P5V")
		)
		(pad "2" smd circle
			(at -0.40005 0 270)
			(size 0 0)
			(layers "B.Cu" "B.Mask" "B.Paste")
			(net "GND")
		)
	)
	(footprint ""
		(layer "B.Cu")
		(at 10.380218 -245.3132 -90)
		(property "Reference" "PC63"
			(at 0 0 90)
			(layer "B.SilkS")
			(hide yes)
			(effects
				(font
					(size 1.27 1.27)
				)
				(justify mirror)
			)
		)
		(property "Value" ""
			(at 0 0 90)
			(layer "B.Fab")
			(effects
				(font
					(size 1.27 1.27)
				)
				(justify mirror)
			)
		)
		(duplicate_pad_numbers_are_jumpers no)
		(fp_line
			(start -1.524 0.762)
			(end 1.524 0.762)
			(stroke
				(width 0.1524)
				(type default)
			)
			(layer "B.SilkS")
		)
		(fp_line
			(start 1.524 0.762)
			(end 1.524 -0.762)
			(stroke
				(width 0.1524)
				(type default)
			)
			(layer "B.SilkS")
		)
		(fp_line
			(start -1.524 -0.762)
			(end -1.524 0.762)
			(stroke
				(width 0.1524)
				(type default)
			)
			(layer "B.SilkS")
		)
		(fp_line
			(start 1.524 -0.762)
			(end -1.524 -0.762)
			(stroke
				(width 0.1524)
				(type default)
			)
			(layer "B.SilkS")
		)
		(fp_line
			(start -1.1049 0.724916)
			(end -1.1049 -0.724916)
			(stroke
				(width 0.1)
				(type default)
			)
			(layer "B.Fab")
		)
		(fp_line
			(start 1.1049 0.724916)
			(end -1.1049 0.724916)
			(stroke
				(width 0.1)
				(type default)
			)
			(layer "B.Fab")
		)
		(fp_line
			(start -1.1049 -0.724916)
			(end 1.1049 -0.724916)
			(stroke
				(width 0.1)
				(type default)
			)
			(layer "B.Fab")
		)
		(fp_line
			(start 1.1049 -0.724916)
			(end 1.1049 0.724916)
			(stroke
				(width 0.1)
				(type default)
			)
			(layer "B.Fab")
		)
		(pad "1" smd rect
			(at 0.889 0 270)
			(size 1.016 1.27)
			(layers "B.Cu" "B.Mask" "B.Paste")
			(net "P52V_HSC")
		)
		(pad "2" smd rect
			(at -0.889 0 270)
			(size 1.016 1.27)
			(layers "B.Cu" "B.Mask" "B.Paste")
			(net "GND")
		)
	)
	(footprint ""
		(layer "B.Cu")
		(at 3.81 -64.837056 -90)
		(property "Reference" "PC40"
			(at 0 0 90)
			(layer "B.SilkS")
			(hide yes)
			(effects
				(font
					(size 1.27 1.27)
				)
				(justify mirror)
			)
		)
		(property "Value" ""
			(at 0 0 90)
			(layer "B.Fab")
			(effects
				(font
					(size 1.27 1.27)
				)
				(justify mirror)
			)
		)
		(duplicate_pad_numbers_are_jumpers no)
		(fp_line
			(start -0.7874 0.4064)
			(end 0.7874 0.4064)
			(stroke
				(width 0.1524)
				(type default)
			)
			(layer "B.SilkS")
		)
		(fp_line
			(start 0.7874 0.4064)
			(end 0.7874 -0.4064)
			(stroke
				(width 0.1524)
				(type default)
			)
			(layer "B.SilkS")
		)
		(fp_line
			(start -0.7874 -0.4064)
			(end -0.7874 0.4064)
			(stroke
				(width 0.1524)
				(type default)
			)
			(layer "B.SilkS")
		)
		(fp_line
			(start 0.7874 -0.4064)
			(end -0.7874 -0.4064)
			(stroke
				(width 0.1524)
				(type default)
			)
			(layer "B.SilkS")
		)
		(fp_line
			(start -0.67945 0.3048)
			(end -0.120396 0.3048)
			(stroke
				(width 0.1)
				(type default)
			)
			(layer "B.Fab")
		)
		(fp_line
			(start -0.120396 0.3048)
			(end -0.120396 0.2794)
			(stroke
				(width 0.1)
				(type default)
			)
			(layer "B.Fab")
		)
		(fp_line
			(start 0.12065 0.3048)
			(end 0.67945 0.3048)
			(stroke
				(width 0.1)
				(type default)
			)
			(layer "B.Fab")
		)
		(fp_line
			(start 0.67945 0.3048)
			(end 0.67945 -0.305054)
			(stroke
				(width 0.1)
				(type default)
			)
			(layer "B.Fab")
		)
		(fp_line
			(start -0.120396 0.2794)
			(end 0.12065 0.2794)
			(stroke
				(width 0.1)
				(type default)
			)
			(layer "B.Fab")
		)
		(fp_line
			(start 0.12065 0.2794)
			(end 0.12065 0.3048)
			(stroke
				(width 0.1)
				(type default)
			)
			(layer "B.Fab")
		)
		(fp_line
			(start -0.12065 -0.2794)
			(end -0.12065 -0.3048)
			(stroke
				(width 0.1)
				(type default)
			)
			(layer "B.Fab")
		)
		(fp_line
			(start 0.12065 -0.2794)
			(end -0.12065 -0.2794)
			(stroke
				(width 0.1)
				(type default)
			)
			(layer "B.Fab")
		)
		(fp_line
			(start -0.67945 -0.3048)
			(end -0.67945 0.3048)
			(stroke
				(width 0.1)
				(type default)
			)
			(layer "B.Fab")
		)
		(fp_line
			(start -0.12065 -0.3048)
			(end -0.67945 -0.3048)
			(stroke
				(width 0.1)
				(type default)
			)
			(layer "B.Fab")
		)
		(fp_line
			(start 0.12065 -0.305054)
			(end 0.12065 -0.2794)
			(stroke
				(width 0.1)
				(type default)
			)
			(layer "B.Fab")
		)
		(fp_line
			(start 0.67945 -0.305054)
			(end 0.12065 -0.305054)
			(stroke
				(width 0.1)
				(type default)
			)
			(layer "B.Fab")
		)
		(pad "1" smd circle
			(at 0.40005 0 90)
			(size 0 0)
			(layers "B.Cu" "B.Mask" "B.Paste")
			(net "FAN_4_SS")
		)
		(pad "2" smd circle
			(at -0.40005 0 90)
			(size 0 0)
			(layers "B.Cu" "B.Mask" "B.Paste")
			(net "GND")
		)
	)
	(footprint ""
		(layer "B.Cu")
		(at 16.2052 -93.529912 180)
		(property "Reference" "C2113"
			(at 0 0 0)
			(layer "B.SilkS")
			(hide yes)
			(effects
				(font
					(size 1.27 1.27)
				)
				(justify mirror)
			)
		)
		(property "Value" ""
			(at 0 0 0)
			(layer "B.Fab")
			(effects
				(font
					(size 1.27 1.27)
				)
				(justify mirror)
			)
		)
		(duplicate_pad_numbers_are_jumpers no)
		(fp_line
			(start 2.2098 0.9398)
			(end 2.2098 -0.9398)
			(stroke
				(width 0.1524)
				(type default)
			)
			(layer "B.SilkS")
		)
		(fp_line
			(start 2.2098 -0.9398)
			(end -2.2098 -0.9398)
			(stroke
				(width 0.1524)
				(type default)
			)
			(layer "B.SilkS")
		)
		(fp_line
			(start -2.2098 0.9398)
			(end 2.2098 0.9398)
			(stroke
				(width 0.1524)
				(type default)
			)
			(layer "B.SilkS")
		)
		(fp_line
			(start -2.2098 -0.9398)
			(end -2.2098 0.9398)
			(stroke
				(width 0.1524)
				(type default)
			)
			(layer "B.SilkS")
		)
		(fp_line
			(start 1.700022 0.899922)
			(end 1.700022 -0.899922)
			(stroke
				(width 0.1)
				(type default)
			)
			(layer "B.Fab")
		)
		(fp_line
			(start 1.700022 -0.899922)
			(end -1.700022 -0.899922)
			(stroke
				(width 0.1)
				(type default)
			)
			(layer "B.Fab")
		)
		(fp_line
			(start -1.700022 0.899922)
			(end 1.700022 0.899922)
			(stroke
				(width 0.1)
				(type default)
			)
			(layer "B.Fab")
		)
		(fp_line
			(start -1.700022 -0.899922)
			(end -1.700022 0.899922)
			(stroke
				(width 0.1)
				(type default)
			)
			(layer "B.Fab")
		)
		(pad "1" smd rect
			(at 1.4732 0 180)
			(size 1.1684 1.5748)
			(layers "B.Cu" "B.Mask" "B.Paste")
			(net "P52V_FAN_5")
		)
		(pad "2" smd rect
			(at -1.4732 0 180)
			(size 1.1684 1.5748)
			(layers "B.Cu" "B.Mask" "B.Paste")
			(net "GND")
		)
	)
	(footprint ""
		(layer "B.Cu")
		(at 9.922002 -166.755826 180)
		(property "Reference" "C51"
			(at 0 0 0)
			(layer "B.SilkS")
			(hide yes)
			(effects
				(font
					(size 1.27 1.27)
				)
				(justify mirror)
			)
		)
		(property "Value" ""
			(at 0 0 0)
			(layer "B.Fab")
			(effects
				(font
					(size 1.27 1.27)
				)
				(justify mirror)
			)
		)
		(duplicate_pad_numbers_are_jumpers no)
		(fp_line
			(start 0.7874 0.4064)
			(end 0.7874 -0.4064)
			(stroke
				(width 0.1524)
				(type default)
			)
			(layer "B.SilkS")
		)
		(fp_line
			(start 0.7874 -0.4064)
			(end -0.7874 -0.4064)
			(stroke
				(width 0.1524)
				(type default)
			)
			(layer "B.SilkS")
		)
		(fp_line
			(start -0.7874 0.4064)
			(end 0.7874 0.4064)
			(stroke
				(width 0.1524)
				(type default)
			)
			(layer "B.SilkS")
		)
		(fp_line
			(start -0.7874 -0.4064)
			(end -0.7874 0.4064)
			(stroke
				(width 0.1524)
				(type default)
			)
			(layer "B.SilkS")
		)
		(fp_line
			(start 0.67945 0.3048)
			(end 0.67945 -0.305054)
			(stroke
				(width 0.1)
				(type default)
			)
			(layer "B.Fab")
		)
		(fp_line
			(start 0.67945 -0.305054)
			(end 0.12065 -0.305054)
			(stroke
				(width 0.1)
				(type default)
			)
			(layer "B.Fab")
		)
		(fp_line
			(start 0.12065 0.3048)
			(end 0.67945 0.3048)
			(stroke
				(width 0.1)
				(type default)
			)
			(layer "B.Fab")
		)
		(fp_line
			(start 0.12065 0.2794)
			(end 0.12065 0.3048)
			(stroke
				(width 0.1)
				(type default)
			)
			(layer "B.Fab")
		)
		(fp_line
			(start 0.12065 -0.2794)
			(end -0.12065 -0.2794)
			(stroke
				(width 0.1)
				(type default)
			)
			(layer "B.Fab")
		)
		(fp_line
			(start 0.12065 -0.305054)
			(end 0.12065 -0.2794)
			(stroke
				(width 0.1)
				(type default)
			)
			(layer "B.Fab")
		)
		(fp_line
			(start -0.120396 0.3048)
			(end -0.120396 0.2794)
			(stroke
				(width 0.1)
				(type default)
			)
			(layer "B.Fab")
		)
		(fp_line
			(start -0.120396 0.2794)
			(end 0.12065 0.2794)
			(stroke
				(width 0.1)
				(type default)
			)
			(layer "B.Fab")
		)
		(fp_line
			(start -0.12065 -0.2794)
			(end -0.12065 -0.3048)
			(stroke
				(width 0.1)
				(type default)
			)
			(layer "B.Fab")
		)
		(fp_line
			(start -0.12065 -0.3048)
			(end -0.67945 -0.3048)
			(stroke
				(width 0.1)
				(type default)
			)
			(layer "B.Fab")
		)
		(fp_line
			(start -0.67945 0.3048)
			(end -0.120396 0.3048)
			(stroke
				(width 0.1)
				(type default)
			)
			(layer "B.Fab")
		)
		(fp_line
			(start -0.67945 -0.3048)
			(end -0.67945 0.3048)
			(stroke
				(width 0.1)
				(type default)
			)
			(layer "B.Fab")
		)
		(pad "1" smd circle
			(at 0.40005 0)
			(size 0 0)
			(layers "B.Cu" "B.Mask" "B.Paste")
			(net "P3V3_AUX")
		)
		(pad "2" smd circle
			(at -0.40005 0)
			(size 0 0)
			(layers "B.Cu" "B.Mask" "B.Paste")
			(net "GND")
		)
	)
	(footprint ""
		(layer "B.Cu")
		(at 40.894 -133.477 180)
		(property "Reference" "R5428"
			(at 0 0 0)
			(layer "B.SilkS")
			(hide yes)
			(effects
				(font
					(size 1.27 1.27)
				)
				(justify mirror)
			)
		)
		(property "Value" ""
			(at 0 0 0)
			(layer "B.Fab")
			(effects
				(font
					(size 1.27 1.27)
				)
				(justify mirror)
			)
		)
		(duplicate_pad_numbers_are_jumpers no)
		(fp_line
			(start 0.7874 0.4064)
			(end 0.7874 -0.4064)
			(stroke
				(width 0.1524)
				(type default)
			)
			(layer "B.SilkS")
		)
		(fp_line
			(start 0.7874 -0.4064)
			(end -0.7874 -0.4064)
			(stroke
				(width 0.1524)
				(type default)
			)
			(layer "B.SilkS")
		)
		(fp_line
			(start -0.7874 0.4064)
			(end 0.7874 0.4064)
			(stroke
				(width 0.1524)
				(type default)
			)
			(layer "B.SilkS")
		)
		(fp_line
			(start -0.7874 -0.4064)
			(end -0.7874 0.4064)
			(stroke
				(width 0.1524)
				(type default)
			)
			(layer "B.SilkS")
		)
		(fp_line
			(start 0.67945 0.3048)
			(end 0.67945 -0.305054)
			(stroke
				(width 0.1)
				(type default)
			)
			(layer "B.Fab")
		)
		(fp_line
			(start 0.67945 -0.305054)
			(end 0.12065 -0.305054)
			(stroke
				(width 0.1)
				(type default)
			)
			(layer "B.Fab")
		)
		(fp_line
			(start 0.12065 0.3048)
			(end 0.67945 0.3048)
			(stroke
				(width 0.1)
				(type default)
			)
			(layer "B.Fab")
		)
		(fp_line
			(start 0.12065 0.2794)
			(end 0.12065 0.3048)
			(stroke
				(width 0.1)
				(type default)
			)
			(layer "B.Fab")
		)
		(fp_line
			(start 0.12065 -0.2794)
			(end -0.12065 -0.2794)
			(stroke
				(width 0.1)
				(type default)
			)
			(layer "B.Fab")
		)
		(fp_line
			(start 0.12065 -0.305054)
			(end 0.12065 -0.2794)
			(stroke
				(width 0.1)
				(type default)
			)
			(layer "B.Fab")
		)
		(fp_line
			(start -0.120396 0.3048)
			(end -0.120396 0.2794)
			(stroke
				(width 0.1)
				(type default)
			)
			(layer "B.Fab")
		)
		(fp_line
			(start -0.120396 0.2794)
			(end 0.12065 0.2794)
			(stroke
				(width 0.1)
				(type default)
			)
			(layer "B.Fab")
		)
		(fp_line
			(start -0.12065 -0.2794)
			(end -0.12065 -0.3048)
			(stroke
				(width 0.1)
				(type default)
			)
			(layer "B.Fab")
		)
		(fp_line
			(start -0.12065 -0.3048)
			(end -0.67945 -0.3048)
			(stroke
				(width 0.1)
				(type default)
			)
			(layer "B.Fab")
		)
		(fp_line
			(start -0.67945 0.3048)
			(end -0.120396 0.3048)
			(stroke
				(width 0.1)
				(type default)
			)
			(layer "B.Fab")
		)
		(fp_line
			(start -0.67945 -0.3048)
			(end -0.67945 0.3048)
			(stroke
				(width 0.1)
				(type default)
			)
			(layer "B.Fab")
		)
		(pad "1" smd rect
			(at 0.40005 0 180)
			(size 0.4572 0.508)
			(layers "B.Cu" "B.Mask" "B.Paste")
			(net "FAN_1_TACH_IL")
		)
		(pad "2" smd rect
			(at -0.40005 0 180)
			(size 0.4572 0.508)
			(layers "B.Cu" "B.Mask" "B.Paste")
			(net "GND")
		)
	)
	(footprint ""
		(layer "B.Cu")
		(at 44.704 -50.165 180)
		(property "Reference" "C2105"
			(at 0 0 0)
			(layer "B.SilkS")
			(hide yes)
			(effects
				(font
					(size 1.27 1.27)
				)
				(justify mirror)
			)
		)
		(property "Value" ""
			(at 0 0 0)
			(layer "B.Fab")
			(effects
				(font
					(size 1.27 1.27)
				)
				(justify mirror)
			)
		)
		(duplicate_pad_numbers_are_jumpers no)
		(fp_line
			(start 2.2098 0.9398)
			(end 2.2098 -0.9398)
			(stroke
				(width 0.1524)
				(type default)
			)
			(layer "B.SilkS")
		)
		(fp_line
			(start 2.2098 -0.9398)
			(end -2.2098 -0.9398)
			(stroke
				(width 0.1524)
				(type default)
			)
			(layer "B.SilkS")
		)
		(fp_line
			(start -2.2098 0.9398)
			(end 2.2098 0.9398)
			(stroke
				(width 0.1524)
				(type default)
			)
			(layer "B.SilkS")
		)
		(fp_line
			(start -2.2098 -0.9398)
			(end -2.2098 0.9398)
			(stroke
				(width 0.1524)
				(type default)
			)
			(layer "B.SilkS")
		)
		(fp_line
			(start 1.700022 0.899922)
			(end 1.700022 -0.899922)
			(stroke
				(width 0.1)
				(type default)
			)
			(layer "B.Fab")
		)
		(fp_line
			(start 1.700022 -0.899922)
			(end -1.700022 -0.899922)
			(stroke
				(width 0.1)
				(type default)
			)
			(layer "B.Fab")
		)
		(fp_line
			(start -1.700022 0.899922)
			(end 1.700022 0.899922)
			(stroke
				(width 0.1)
				(type default)
			)
			(layer "B.Fab")
		)
		(fp_line
			(start -1.700022 -0.899922)
			(end -1.700022 0.899922)
			(stroke
				(width 0.1)
				(type default)
			)
			(layer "B.Fab")
		)
		(pad "1" smd rect
			(at 1.4732 0 180)
			(size 1.1684 1.5748)
			(layers "B.Cu" "B.Mask" "B.Paste")
			(net "P52V_FAN_3")
		)
		(pad "2" smd rect
			(at -1.4732 0 180)
			(size 1.1684 1.5748)
			(layers "B.Cu" "B.Mask" "B.Paste")
			(net "GND")
		)
	)
	(footprint ""
		(layer "B.Cu")
		(at 17.653 -131.953 180)
		(property "Reference" "R5440"
			(at 0 0 0)
			(layer "B.SilkS")
			(hide yes)
			(effects
				(font
					(size 1.27 1.27)
				)
				(justify mirror)
			)
		)
		(property "Value" ""
			(at 0 0 0)
			(layer "B.Fab")
			(effects
				(font
					(size 1.27 1.27)
				)
				(justify mirror)
			)
		)
		(duplicate_pad_numbers_are_jumpers no)
		(fp_line
			(start 0.7874 0.4064)
			(end 0.7874 -0.4064)
			(stroke
				(width 0.1524)
				(type default)
			)
			(layer "B.SilkS")
		)
		(fp_line
			(start 0.7874 -0.4064)
			(end -0.7874 -0.4064)
			(stroke
				(width 0.1524)
				(type default)
			)
			(layer "B.SilkS")
		)
		(fp_line
			(start -0.7874 0.4064)
			(end 0.7874 0.4064)
			(stroke
				(width 0.1524)
				(type default)
			)
			(layer "B.SilkS")
		)
		(fp_line
			(start -0.7874 -0.4064)
			(end -0.7874 0.4064)
			(stroke
				(width 0.1524)
				(type default)
			)
			(layer "B.SilkS")
		)
		(fp_line
			(start 0.67945 0.3048)
			(end 0.67945 -0.305054)
			(stroke
				(width 0.1)
				(type default)
			)
			(layer "B.Fab")
		)
		(fp_line
			(start 0.67945 -0.305054)
			(end 0.12065 -0.305054)
			(stroke
				(width 0.1)
				(type default)
			)
			(layer "B.Fab")
		)
		(fp_line
			(start 0.12065 0.3048)
			(end 0.67945 0.3048)
			(stroke
				(width 0.1)
				(type default)
			)
			(layer "B.Fab")
		)
		(fp_line
			(start 0.12065 0.2794)
			(end 0.12065 0.3048)
			(stroke
				(width 0.1)
				(type default)
			)
			(layer "B.Fab")
		)
		(fp_line
			(start 0.12065 -0.2794)
			(end -0.12065 -0.2794)
			(stroke
				(width 0.1)
				(type default)
			)
			(layer "B.Fab")
		)
		(fp_line
			(start 0.12065 -0.305054)
			(end 0.12065 -0.2794)
			(stroke
				(width 0.1)
				(type default)
			)
			(layer "B.Fab")
		)
		(fp_line
			(start -0.120396 0.3048)
			(end -0.120396 0.2794)
			(stroke
				(width 0.1)
				(type default)
			)
			(layer "B.Fab")
		)
		(fp_line
			(start -0.120396 0.2794)
			(end 0.12065 0.2794)
			(stroke
				(width 0.1)
				(type default)
			)
			(layer "B.Fab")
		)
		(fp_line
			(start -0.12065 -0.2794)
			(end -0.12065 -0.3048)
			(stroke
				(width 0.1)
				(type default)
			)
			(layer "B.Fab")
		)
		(fp_line
			(start -0.12065 -0.3048)
			(end -0.67945 -0.3048)
			(stroke
				(width 0.1)
				(type default)
			)
			(layer "B.Fab")
		)
		(fp_line
			(start -0.67945 0.3048)
			(end -0.120396 0.3048)
			(stroke
				(width 0.1)
				(type default)
			)
			(layer "B.Fab")
		)
		(fp_line
			(start -0.67945 -0.3048)
			(end -0.67945 0.3048)
			(stroke
				(width 0.1)
				(type default)
			)
			(layer "B.Fab")
		)
		(pad "1" smd rect
			(at 0.40005 0 180)
			(size 0.4572 0.508)
			(layers "B.Cu" "B.Mask" "B.Paste")
			(net "FAN_7_TACH_IL")
		)
		(pad "2" smd rect
			(at -0.40005 0 180)
			(size 0.4572 0.508)
			(layers "B.Cu" "B.Mask" "B.Paste")
			(net "GND")
		)
	)
	(footprint ""
		(layer "B.Cu")
		(at 5.596128 -232.755948)
		(property "Reference" "C2116"
			(at 0 0 0)
			(layer "B.SilkS")
			(hide yes)
			(effects
				(font
					(size 1.27 1.27)
				)
				(justify mirror)
			)
		)
		(property "Value" ""
			(at 0 0 0)
			(layer "B.Fab")
			(effects
				(font
					(size 1.27 1.27)
				)
				(justify mirror)
			)
		)
		(duplicate_pad_numbers_are_jumpers no)
		(fp_line
			(start -2.2098 -0.9398)
			(end -2.2098 0.9398)
			(stroke
				(width 0.1524)
				(type default)
			)
			(layer "B.SilkS")
		)
		(fp_line
			(start -2.2098 0.9398)
			(end 2.2098 0.9398)
			(stroke
				(width 0.1524)
				(type default)
			)
			(layer "B.SilkS")
		)
		(fp_line
			(start 2.2098 -0.9398)
			(end -2.2098 -0.9398)
			(stroke
				(width 0.1524)
				(type default)
			)
			(layer "B.SilkS")
		)
		(fp_line
			(start 2.2098 0.9398)
			(end 2.2098 -0.9398)
			(stroke
				(width 0.1524)
				(type default)
			)
			(layer "B.SilkS")
		)
		(fp_line
			(start -1.700022 -0.899922)
			(end -1.700022 0.899922)
			(stroke
				(width 0.1)
				(type default)
			)
			(layer "B.Fab")
		)
		(fp_line
			(start -1.700022 0.899922)
			(end 1.700022 0.899922)
			(stroke
				(width 0.1)
				(type default)
			)
			(layer "B.Fab")
		)
		(fp_line
			(start 1.700022 -0.899922)
			(end -1.700022 -0.899922)
			(stroke
				(width 0.1)
				(type default)
			)
			(layer "B.Fab")
		)
		(fp_line
			(start 1.700022 0.899922)
			(end 1.700022 -0.899922)
			(stroke
				(width 0.1)
				(type default)
			)
			(layer "B.Fab")
		)
		(pad "1" smd rect
			(at 1.4732 0)
			(size 1.1684 1.5748)
			(layers "B.Cu" "B.Mask" "B.Paste")
			(net "P52V_FAN_6")
		)
		(pad "2" smd rect
			(at -1.4732 0)
			(size 1.1684 1.5748)
			(layers "B.Cu" "B.Mask" "B.Paste")
			(net "GND")
		)
	)
	(footprint ""
		(layer "B.Cu")
		(at 9.906 -170.815 180)
		(property "Reference" "C1941"
			(at 0 0 0)
			(layer "B.SilkS")
			(hide yes)
			(effects
				(font
					(size 1.27 1.27)
				)
				(justify mirror)
			)
		)
		(property "Value" ""
			(at 0 0 0)
			(layer "B.Fab")
			(effects
				(font
					(size 1.27 1.27)
				)
				(justify mirror)
			)
		)
		(duplicate_pad_numbers_are_jumpers no)
		(fp_line
			(start 0.7874 0.4064)
			(end 0.7874 -0.4064)
			(stroke
				(width 0.1524)
				(type default)
			)
			(layer "B.SilkS")
		)
		(fp_line
			(start 0.7874 -0.4064)
			(end -0.7874 -0.4064)
			(stroke
				(width 0.1524)
				(type default)
			)
			(layer "B.SilkS")
		)
		(fp_line
			(start -0.7874 0.4064)
			(end 0.7874 0.4064)
			(stroke
				(width 0.1524)
				(type default)
			)
			(layer "B.SilkS")
		)
		(fp_line
			(start -0.7874 -0.4064)
			(end -0.7874 0.4064)
			(stroke
				(width 0.1524)
				(type default)
			)
			(layer "B.SilkS")
		)
		(fp_line
			(start 0.67945 0.3048)
			(end 0.67945 -0.305054)
			(stroke
				(width 0.1)
				(type default)
			)
			(layer "B.Fab")
		)
		(fp_line
			(start 0.67945 -0.305054)
			(end 0.12065 -0.305054)
			(stroke
				(width 0.1)
				(type default)
			)
			(layer "B.Fab")
		)
		(fp_line
			(start 0.12065 0.3048)
			(end 0.67945 0.3048)
			(stroke
				(width 0.1)
				(type default)
			)
			(layer "B.Fab")
		)
		(fp_line
			(start 0.12065 0.2794)
			(end 0.12065 0.3048)
			(stroke
				(width 0.1)
				(type default)
			)
			(layer "B.Fab")
		)
		(fp_line
			(start 0.12065 -0.2794)
			(end -0.12065 -0.2794)
			(stroke
				(width 0.1)
				(type default)
			)
			(layer "B.Fab")
		)
		(fp_line
			(start 0.12065 -0.305054)
			(end 0.12065 -0.2794)
			(stroke
				(width 0.1)
				(type default)
			)
			(layer "B.Fab")
		)
		(fp_line
			(start -0.120396 0.3048)
			(end -0.120396 0.2794)
			(stroke
				(width 0.1)
				(type default)
			)
			(layer "B.Fab")
		)
		(fp_line
			(start -0.120396 0.2794)
			(end 0.12065 0.2794)
			(stroke
				(width 0.1)
				(type default)
			)
			(layer "B.Fab")
		)
		(fp_line
			(start -0.12065 -0.2794)
			(end -0.12065 -0.3048)
			(stroke
				(width 0.1)
				(type default)
			)
			(layer "B.Fab")
		)
		(fp_line
			(start -0.12065 -0.3048)
			(end -0.67945 -0.3048)
			(stroke
				(width 0.1)
				(type default)
			)
			(layer "B.Fab")
		)
		(fp_line
			(start -0.67945 0.3048)
			(end -0.120396 0.3048)
			(stroke
				(width 0.1)
				(type default)
			)
			(layer "B.Fab")
		)
		(fp_line
			(start -0.67945 -0.3048)
			(end -0.67945 0.3048)
			(stroke
				(width 0.1)
				(type default)
			)
			(layer "B.Fab")
		)
		(pad "1" smd circle
			(at 0.40005 0)
			(size 0 0)
			(layers "B.Cu" "B.Mask" "B.Paste")
			(net "P3V3_AUX")
		)
		(pad "2" smd circle
			(at -0.40005 0)
			(size 0 0)
			(layers "B.Cu" "B.Mask" "B.Paste")
			(net "GND")
		)
	)
	(footprint ""
		(layer "B.Cu")
		(at 39.116 -64.837056 -90)
		(property "Reference" "PC18"
			(at 0 0 90)
			(layer "B.SilkS")
			(hide yes)
			(effects
				(font
					(size 1.27 1.27)
				)
				(justify mirror)
			)
		)
		(property "Value" ""
			(at 0 0 90)
			(layer "B.Fab")
			(effects
				(font
					(size 1.27 1.27)
				)
				(justify mirror)
			)
		)
		(duplicate_pad_numbers_are_jumpers no)
		(fp_line
			(start -0.7874 0.4064)
			(end 0.7874 0.4064)
			(stroke
				(width 0.1524)
				(type default)
			)
			(layer "B.SilkS")
		)
		(fp_line
			(start 0.7874 0.4064)
			(end 0.7874 -0.4064)
			(stroke
				(width 0.1524)
				(type default)
			)
			(layer "B.SilkS")
		)
		(fp_line
			(start -0.7874 -0.4064)
			(end -0.7874 0.4064)
			(stroke
				(width 0.1524)
				(type default)
			)
			(layer "B.SilkS")
		)
		(fp_line
			(start 0.7874 -0.4064)
			(end -0.7874 -0.4064)
			(stroke
				(width 0.1524)
				(type default)
			)
			(layer "B.SilkS")
		)
		(fp_line
			(start -0.67945 0.3048)
			(end -0.120396 0.3048)
			(stroke
				(width 0.1)
				(type default)
			)
			(layer "B.Fab")
		)
		(fp_line
			(start -0.120396 0.3048)
			(end -0.120396 0.2794)
			(stroke
				(width 0.1)
				(type default)
			)
			(layer "B.Fab")
		)
		(fp_line
			(start 0.12065 0.3048)
			(end 0.67945 0.3048)
			(stroke
				(width 0.1)
				(type default)
			)
			(layer "B.Fab")
		)
		(fp_line
			(start 0.67945 0.3048)
			(end 0.67945 -0.305054)
			(stroke
				(width 0.1)
				(type default)
			)
			(layer "B.Fab")
		)
		(fp_line
			(start -0.120396 0.2794)
			(end 0.12065 0.2794)
			(stroke
				(width 0.1)
				(type default)
			)
			(layer "B.Fab")
		)
		(fp_line
			(start 0.12065 0.2794)
			(end 0.12065 0.3048)
			(stroke
				(width 0.1)
				(type default)
			)
			(layer "B.Fab")
		)
		(fp_line
			(start -0.12065 -0.2794)
			(end -0.12065 -0.3048)
			(stroke
				(width 0.1)
				(type default)
			)
			(layer "B.Fab")
		)
		(fp_line
			(start 0.12065 -0.2794)
			(end -0.12065 -0.2794)
			(stroke
				(width 0.1)
				(type default)
			)
			(layer "B.Fab")
		)
		(fp_line
			(start -0.67945 -0.3048)
			(end -0.67945 0.3048)
			(stroke
				(width 0.1)
				(type default)
			)
			(layer "B.Fab")
		)
		(fp_line
			(start -0.12065 -0.3048)
			(end -0.67945 -0.3048)
			(stroke
				(width 0.1)
				(type default)
			)
			(layer "B.Fab")
		)
		(fp_line
			(start 0.12065 -0.305054)
			(end 0.12065 -0.2794)
			(stroke
				(width 0.1)
				(type default)
			)
			(layer "B.Fab")
		)
		(fp_line
			(start 0.67945 -0.305054)
			(end 0.12065 -0.305054)
			(stroke
				(width 0.1)
				(type default)
			)
			(layer "B.Fab")
		)
		(pad "1" smd circle
			(at 0.40005 0 90)
			(size 0 0)
			(layers "B.Cu" "B.Mask" "B.Paste")
			(net "FAN_3_P3V_R")
		)
		(pad "2" smd circle
			(at -0.40005 0 90)
			(size 0 0)
			(layers "B.Cu" "B.Mask" "B.Paste")
			(net "GND")
		)
	)
	(footprint ""
		(layer "B.Cu")
		(at 12.207494 -71.304912)
		(property "Reference" "U361"
			(at -0.142494 1.862582 0)
			(unlocked yes)
			(layer "B.SilkS")
			(effects
				(font
					(size 0.7874 0.5842)
					(thickness 0.1524)
				)
				(justify mirror)
			)
		)
		(property "Value" ""
			(at 0 0 0)
			(layer "B.Fab")
			(effects
				(font
					(size 1.27 1.27)
				)
				(justify mirror)
			)
		)
		(duplicate_pad_numbers_are_jumpers no)
		(fp_line
			(start -1.7018 -1.1176)
			(end -1.7018 1.1176)
			(stroke
				(width 0.1524)
				(type default)
			)
			(layer "B.SilkS")
		)
		(fp_line
			(start -1.7018 -1.1176)
			(end -0.254 -1.1176)
			(stroke
				(width 0.1524)
				(type default)
			)
			(layer "B.SilkS")
		)
		(fp_line
			(start -1.7018 1.1176)
			(end 1.7018 1.1176)
			(stroke
				(width 0.1524)
				(type default)
			)
			(layer "B.SilkS")
		)
		(fp_line
			(start -0.254 -1.1176)
			(end 0 -0.7112)
			(stroke
				(width 0.1524)
				(type default)
			)
			(layer "B.SilkS")
		)
		(fp_line
			(start 0 -0.7112)
			(end 0.254 -1.1176)
			(stroke
				(width 0.1524)
				(type default)
			)
			(layer "B.SilkS")
		)
		(fp_line
			(start 0.254 -1.1176)
			(end 1.7018 -1.1176)
			(stroke
				(width 0.1524)
				(type default)
			)
			(layer "B.SilkS")
		)
		(fp_line
			(start 1.7018 1.1176)
			(end 1.7018 -1.1176)
			(stroke
				(width 0.1524)
				(type default)
			)
			(layer "B.SilkS")
		)
		(fp_poly
			(pts
				(xy 1.8161 -0.675386) (xy 2.4003 -0.446786) (xy 2.4003 -0.878586)
			)
			(stroke
				(width 0)
				(type default)
			)
			(fill yes)
			(layer "B.SilkS")
		)
		(fp_line
			(start -1.5494 -1.1176)
			(end -1.5494 1.1176)
			(stroke
				(width 0.1)
				(type default)
			)
			(layer "B.Fab")
		)
		(fp_line
			(start -1.5494 -1.1176)
			(end -0.254 -1.1176)
			(stroke
				(width 0.1)
				(type default)
			)
			(layer "B.Fab")
		)
		(fp_line
			(start -1.5494 1.1176)
			(end 1.5494 1.1176)
			(stroke
				(width 0.1)
				(type default)
			)
			(layer "B.Fab")
		)
		(fp_line
			(start -0.254 -1.1176)
			(end 0.254 -1.1176)
			(stroke
				(width 0.1)
				(type default)
			)
			(layer "B.Fab")
		)
		(fp_line
			(start 0.254 -1.1176)
			(end 1.5494 -1.1176)
			(stroke
				(width 0.1)
				(type default)
			)
			(layer "B.Fab")
		)
		(fp_line
			(start 1.5494 1.1176)
			(end 1.5494 -1.1176)
			(stroke
				(width 0.1)
				(type default)
			)
			(layer "B.Fab")
		)
		(fp_poly
			(pts
				(xy 1.8161 -0.675386) (xy 2.4003 -0.446786) (xy 2.4003 -0.878586)
			)
			(stroke
				(width 0)
				(type default)
			)
			(fill yes)
			(layer "B.Fab")
		)
		(pad "1" smd rect
			(at 0.962406 -0.649986 270)
			(size 0.3302 1.1684)
			(layers "B.Cu" "B.Mask" "B.Paste")
			(net "FAN_5_PRESENT_R")
		)
		(pad "2" smd rect
			(at 0.962406 0 270)
			(size 0.3302 1.1684)
			(layers "B.Cu" "B.Mask" "B.Paste")
			(net "P52V_FAN_5_BUFF_EN_R")
		)
		(pad "3" smd rect
			(at 0.962406 0.649986 270)
			(size 0.3302 1.1684)
			(layers "B.Cu" "B.Mask" "B.Paste")
			(net "GND")
		)
		(pad "4" smd rect
			(at -0.962406 0.649986 270)
			(size 0.3302 1.1684)
			(layers "B.Cu" "B.Mask" "B.Paste")
			(net "P52V_FAN_5_EN")
		)
		(pad "5" smd rect
			(at -0.962406 -0.649986 270)
			(size 0.3302 1.1684)
			(layers "B.Cu" "B.Mask" "B.Paste")
			(net "P3V3_AUX")
		)
	)
	(footprint ""
		(layer "B.Cu")
		(at 7.326376 -41.383712 180)
		(property "Reference" "PD7"
			(at 2.678176 -3.767582 0)
			(unlocked yes)
			(layer "B.SilkS")
			(effects
				(font
					(size 0.7874 0.5842)
					(thickness 0.1524)
				)
				(justify left mirror)
			)
		)
		(property "Value" ""
			(at 0 0 0)
			(layer "B.Fab")
			(effects
				(font
					(size 1.27 1.27)
				)
				(justify mirror)
			)
		)
		(duplicate_pad_numbers_are_jumpers no)
		(fp_line
			(start 4.826 3.109976)
			(end 4.826 0)
			(stroke
				(width 0.1524)
				(type default)
			)
			(layer "B.SilkS")
		)
		(fp_line
			(start 4.826 0)
			(end 4.826 -3.109976)
			(stroke
				(width 0.1524)
				(type default)
			)
			(layer "B.SilkS")
		)
		(fp_line
			(start 4.826 -3.109976)
			(end -4.826 -3.109976)
			(stroke
				(width 0.1524)
				(type default)
			)
			(layer "B.SilkS")
		)
		(fp_line
			(start 1.0922 0)
			(end 1.7018 0)
			(stroke
				(width 0.1524)
				(type default)
			)
			(layer "B.SilkS")
		)
		(fp_line
			(start 1.016 1.016)
			(end -1.016 0)
			(stroke
				(width 0.1524)
				(type default)
			)
			(layer "B.SilkS")
		)
		(fp_line
			(start 1.016 -1.016)
			(end 1.016 1.016)
			(stroke
				(width 0.1524)
				(type default)
			)
			(layer "B.SilkS")
		)
		(fp_line
			(start -1.143 1.397)
			(end -1.143 -1.397)
			(stroke
				(width 0.1524)
				(type default)
			)
			(layer "B.SilkS")
		)
		(fp_line
			(start -1.143 0)
			(end 1.016 -1.016)
			(stroke
				(width 0.1524)
				(type default)
			)
			(layer "B.SilkS")
		)
		(fp_line
			(start -1.143 0)
			(end -1.8034 0)
			(stroke
				(width 0.1524)
				(type default)
			)
			(layer "B.SilkS")
		)
		(fp_line
			(start -4.8133 -3.109976)
			(end -5.3467 -3.109976)
			(stroke
				(width 0.1524)
				(type default)
			)
			(layer "B.SilkS")
		)
		(fp_line
			(start -4.826 3.109976)
			(end 4.826 3.109976)
			(stroke
				(width 0.1524)
				(type default)
			)
			(layer "B.SilkS")
		)
		(fp_line
			(start -4.826 0)
			(end -4.826 3.109976)
			(stroke
				(width 0.1524)
				(type default)
			)
			(layer "B.SilkS")
		)
		(fp_line
			(start -4.826 -3.109976)
			(end -4.826 0)
			(stroke
				(width 0.1524)
				(type default)
			)
			(layer "B.SilkS")
		)
		(fp_line
			(start -4.9276 3.109976)
			(end -4.9276 -3.109976)
			(stroke
				(width 0.1524)
				(type default)
			)
			(layer "B.SilkS")
		)
		(fp_line
			(start -5.0292 3.109976)
			(end -5.0292 -3.109976)
			(stroke
				(width 0.1524)
				(type default)
			)
			(layer "B.SilkS")
		)
		(fp_line
			(start -5.1308 3.109976)
			(end -5.1308 -3.109976)
			(stroke
				(width 0.1524)
				(type default)
			)
			(layer "B.SilkS")
		)
		(fp_line
			(start -5.207 3.109976)
			(end -5.207 -3.109976)
			(stroke
				(width 0.1524)
				(type default)
			)
			(layer "B.SilkS")
		)
		(fp_line
			(start -5.334 3.109976)
			(end -4.8133 3.109976)
			(stroke
				(width 0.1524)
				(type default)
			)
			(layer "B.SilkS")
		)
		(fp_line
			(start -5.334 3.109976)
			(end -5.334 0)
			(stroke
				(width 0.1524)
				(type default)
			)
			(layer "B.SilkS")
		)
		(fp_line
			(start -5.334 0)
			(end -5.334 -3.109976)
			(stroke
				(width 0.1524)
				(type default)
			)
			(layer "B.SilkS")
		)
		(fp_line
			(start 3.554984 3.109976)
			(end 3.554984 -3.109976)
			(stroke
				(width 0.1)
				(type default)
			)
			(layer "B.Fab")
		)
		(fp_line
			(start 3.554984 -3.109976)
			(end -3.554984 -3.109976)
			(stroke
				(width 0.1)
				(type default)
			)
			(layer "B.Fab")
		)
		(fp_line
			(start 1.0922 0)
			(end 1.7018 0)
			(stroke
				(width 0.1)
				(type default)
			)
			(layer "B.Fab")
		)
		(fp_line
			(start 1.016 1.016)
			(end -1.016 0)
			(stroke
				(width 0.1)
				(type default)
			)
			(layer "B.Fab")
		)
		(fp_line
			(start 1.016 -1.016)
			(end 1.016 1.016)
			(stroke
				(width 0.1)
				(type default)
			)
			(layer "B.Fab")
		)
		(fp_line
			(start -1.143 1.397)
			(end -1.143 -1.397)
			(stroke
				(width 0.1)
				(type default)
			)
			(layer "B.Fab")
		)
		(fp_line
			(start -1.143 0)
			(end 1.016 -1.016)
			(stroke
				(width 0.1)
				(type default)
			)
			(layer "B.Fab")
		)
		(fp_line
			(start -1.143 0)
			(end -1.8034 0)
			(stroke
				(width 0.1)
				(type default)
			)
			(layer "B.Fab")
		)
		(fp_line
			(start -3.554984 3.109976)
			(end 3.554984 3.109976)
			(stroke
				(width 0.1)
				(type default)
			)
			(layer "B.Fab")
		)
		(fp_line
			(start -3.554984 -3.109976)
			(end -3.554984 3.109976)
			(stroke
				(width 0.1)
				(type default)
			)
			(layer "B.Fab")
		)
		(fp_text user "+"
			(at 5.040376 -0.013462 0)
			(unlocked yes)
			(layer "B.SilkS")
			(effects
				(font
					(size 1.905 1.4224)
					(thickness 0.1524)
				)
				(justify left mirror)
			)
		)
		(fp_text user "-"
			(at -6.6802 0.22225 0)
			(unlocked yes)
			(layer "B.SilkS")
			(effects
				(font
					(size 1.905 1.4224)
					(thickness 0.1524)
				)
				(justify left mirror)
			)
		)
		(fp_text user "+"
			(at 4.5466 0.19685 0)
			(unlocked yes)
			(layer "B.Fab")
			(effects
				(font
					(size 1.905 1.4224)
					(thickness 0.1524)
				)
				(justify left mirror)
			)
		)
		(fp_text user "-"
			(at -6.6802 0.22225 0)
			(unlocked yes)
			(layer "B.Fab")
			(effects
				(font
					(size 1.905 1.4224)
					(thickness 0.1524)
				)
				(justify left mirror)
			)
		)
		(pad "A" smd rect
			(at 3.400044 0 180)
			(size 2.5146 3.302)
			(layers "B.Cu" "B.Mask" "B.Paste")
			(net "GND")
		)
		(pad "C" smd rect
			(at -3.400044 0 180)
			(size 2.5146 3.302)
			(layers "B.Cu" "B.Mask" "B.Paste")
			(net "P52V_FAN_4")
		)
	)
	(footprint ""
		(layer "B.Cu")
		(at 44.99991 -303.310036)
		(property "Reference" "J1"
			(at 3.64109 -5.273294 0)
			(unlocked yes)
			(layer "B.SilkS")
			(effects
				(font
					(size 0.7874 0.5842)
					(thickness 0.1524)
				)
				(justify left mirror)
			)
		)
		(property "Value" ""
			(at 0 0 0)
			(layer "B.Fab")
			(effects
				(font
					(size 1.27 1.27)
				)
				(justify mirror)
			)
		)
		(duplicate_pad_numbers_are_jumpers no)
		(fp_line
			(start -6.35 -4.52501)
			(end 4.350004 -4.52501)
			(stroke
				(width 0.1524)
				(type default)
			)
			(layer "B.SilkS")
		)
		(fp_line
			(start -6.35 18.524982)
			(end -6.35 -4.52501)
			(stroke
				(width 0.1524)
				(type default)
			)
			(layer "B.SilkS")
		)
		(fp_line
			(start -3.24993 -1.42494)
			(end -1.96977 -1.42494)
			(stroke
				(width 0.1524)
				(type default)
			)
			(layer "B.SilkS")
		)
		(fp_line
			(start -3.24993 15.424912)
			(end -3.24993 -1.42494)
			(stroke
				(width 0.1524)
				(type default)
			)
			(layer "B.SilkS")
		)
		(fp_line
			(start -0.029972 -1.42494)
			(end 1.249934 -1.42494)
			(stroke
				(width 0.1524)
				(type default)
			)
			(layer "B.SilkS")
		)
		(fp_line
			(start 1.249934 -1.42494)
			(end 1.249934 5.799836)
			(stroke
				(width 0.1524)
				(type default)
			)
			(layer "B.SilkS")
		)
		(fp_line
			(start 1.249934 5.799836)
			(end 4.350004 5.799836)
			(stroke
				(width 0.1524)
				(type default)
			)
			(layer "B.SilkS")
		)
		(fp_line
			(start 1.249934 8.200136)
			(end 1.249934 15.424912)
			(stroke
				(width 0.1524)
				(type default)
			)
			(layer "B.SilkS")
		)
		(fp_line
			(start 1.249934 8.200136)
			(end 4.350004 8.200136)
			(stroke
				(width 0.1524)
				(type default)
			)
			(layer "B.SilkS")
		)
		(fp_line
			(start 1.249934 15.424912)
			(end -3.24993 15.424912)
			(stroke
				(width 0.1524)
				(type default)
			)
			(layer "B.SilkS")
		)
		(fp_line
			(start 4.350004 -4.52501)
			(end 4.350004 18.524982)
			(stroke
				(width 0.1524)
				(type default)
			)
			(layer "B.SilkS")
		)
		(fp_line
			(start 4.350004 18.524982)
			(end -6.35 18.524982)
			(stroke
				(width 0.1524)
				(type default)
			)
			(layer "B.SilkS")
		)
		(fp_poly
			(pts
				(xy 5.527802 -0.508) (xy 5.527802 0.508) (xy 4.511802 0)
			)
			(stroke
				(width 0)
				(type default)
			)
			(fill yes)
			(layer "B.SilkS")
		)
		(fp_line
			(start -6.35 -4.52501)
			(end 4.350004 -4.52501)
			(stroke
				(width 0.1)
				(type default)
			)
			(layer "B.Fab")
		)
		(fp_line
			(start -6.35 18.524982)
			(end -6.35 -4.52501)
			(stroke
				(width 0.1)
				(type default)
			)
			(layer "B.Fab")
		)
		(fp_line
			(start 4.350004 -4.52501)
			(end 4.350004 18.524982)
			(stroke
				(width 0.1)
				(type default)
			)
			(layer "B.Fab")
		)
		(fp_line
			(start 4.350004 18.524982)
			(end -6.35 18.524982)
			(stroke
				(width 0.1)
				(type default)
			)
			(layer "B.Fab")
		)
		(fp_poly
			(pts
				(xy 5.527802 -0.508) (xy 5.527802 0.508) (xy 4.511802 0)
			)
			(stroke
				(width 0)
				(type default)
			)
			(fill yes)
			(layer "B.Fab")
		)
		(pad "" np_thru_hole circle
			(at -0.999998 -1.89992 270)
			(size 1.4986 1.4986)
			(drill 1.4986)
			(layers "*.Cu" "*.Mask")
			(clearance 0.381)
			(thermal_gap 0.381)
		)
		(pad "1" thru_hole rect
			(at 0 0 270)
			(size 1.3716 1.3716)
			(drill 0.9652)
			(layers "*.Cu" "*.Mask")
			(remove_unused_layers no)
			(net "FAN_0_TACH_IL_D")
			(clearance 0.0508)
			(padstack
				(mode front_inner_back)
				(layer "Inner"
					(shape circle)
					(size 1.3716 1.3716)
					(clearance 0.0508)
				)
				(layer "B.Cu"
					(shape rect)
					(size 1.3716 1.3716)
					(thermal_gap 0.0508)
					(clearance 0.0508)
				)
			)
		)
		(pad "2" thru_hole circle
			(at -1.999996 0 270)
			(size 1.3716 1.3716)
			(drill 0.9652)
			(layers "*.Cu" "*.Mask")
			(remove_unused_layers no)
			(net "FAN_0_PWM_OL_R")
			(clearance 0.0508)
			(thermal_gap 0.0508)
		)
		(pad "3" thru_hole circle
			(at 0 1.999996 270)
			(size 1.3716 1.3716)
			(drill 0.9652)
			(layers "*.Cu" "*.Mask")
			(remove_unused_layers no)
			(net "FAN_0_PWM_IL_R")
			(clearance 0.0508)
			(thermal_gap 0.0508)
		)
		(pad "4" thru_hole circle
			(at -1.999996 1.999996 270)
			(size 1.3716 1.3716)
			(drill 0.9652)
			(layers "*.Cu" "*.Mask")
			(remove_unused_layers no)
			(net "FAN_0_PRESENT_R_N")
			(clearance 0.0508)
			(thermal_gap 0.0508)
		)
		(pad "5" thru_hole circle
			(at 0 3.999992 270)
			(size 1.3716 1.3716)
			(drill 0.9652)
			(layers "*.Cu" "*.Mask")
			(remove_unused_layers no)
			(net "P12V_LED_R1_FAN0")
			(clearance 0.0508)
			(thermal_gap 0.0508)
		)
		(pad "6" thru_hole circle
			(at -1.999996 3.999992 270)
			(size 1.3716 1.3716)
			(drill 0.9652)
			(layers "*.Cu" "*.Mask")
			(remove_unused_layers no)
			(net "SMB_FAN0_SCL_R")
			(clearance 0.0508)
			(thermal_gap 0.0508)
		)
		(pad "7" thru_hole circle
			(at 0 5.999988 270)
			(size 1.3716 1.3716)
			(drill 0.9652)
			(layers "*.Cu" "*.Mask")
			(remove_unused_layers no)
			(net "SMB_FAN0_SDA_R")
			(clearance 0.0508)
			(thermal_gap 0.0508)
		)
		(pad "8" thru_hole circle
			(at -1.999996 5.999988 270)
			(size 1.3716 1.3716)
			(drill 0.9652)
			(layers "*.Cu" "*.Mask")
			(remove_unused_layers no)
			(net "GND")
			(clearance 0.0508)
			(thermal_gap 0.0508)
		)
		(pad "9" thru_hole circle
			(at 0 7.999984 270)
			(size 1.3716 1.3716)
			(drill 0.9652)
			(layers "*.Cu" "*.Mask")
			(remove_unused_layers no)
			(net "GND")
			(clearance 0.0508)
			(thermal_gap 0.0508)
		)
		(pad "10" thru_hole circle
			(at -1.999996 7.999984 270)
			(size 1.3716 1.3716)
			(drill 0.9652)
			(layers "*.Cu" "*.Mask")
			(remove_unused_layers no)
			(net "P52V_FAN_0")
			(clearance 0.0508)
			(thermal_gap 0.0508)
		)
		(pad "11" thru_hole circle
			(at 0 9.99998 270)
			(size 1.3716 1.3716)
			(drill 0.9652)
			(layers "*.Cu" "*.Mask")
			(remove_unused_layers no)
			(net "P52V_FAN_0")
			(clearance 0.0508)
			(thermal_gap 0.0508)
		)
		(pad "12" thru_hole circle
			(at -1.999996 9.99998 270)
			(size 1.3716 1.3716)
			(drill 0.9652)
			(layers "*.Cu" "*.Mask")
			(remove_unused_layers no)
			(net "FAN_0_FAIL_R_LED_N")
			(clearance 0.0508)
			(thermal_gap 0.0508)
		)
		(pad "13" thru_hole circle
			(at 0 11.999976 270)
			(size 1.3716 1.3716)
			(drill 0.9652)
			(layers "*.Cu" "*.Mask")
			(remove_unused_layers no)
			(net "FAN_0_TACH_OL_D")
			(clearance 0.0508)
			(thermal_gap 0.0508)
		)
		(pad "14" thru_hole circle
			(at -1.999996 11.999976 270)
			(size 1.3716 1.3716)
			(drill 0.9652)
			(layers "*.Cu" "*.Mask")
			(remove_unused_layers no)
			(net "FAN_0_OK_R_LED_N")
			(clearance 0.0508)
			(thermal_gap 0.0508)
		)
		(pad "15" thru_hole circle
			(at 0 13.999972 270)
			(size 1.3716 1.3716)
			(drill 0.9652)
			(layers "*.Cu" "*.Mask")
			(remove_unused_layers no)
			(net "Net_618")
			(clearance 0.0508)
			(thermal_gap 0.0508)
		)
		(pad "16" thru_hole circle
			(at -1.999996 13.999972 270)
			(size 1.3716 1.3716)
			(drill 0.9652)
			(layers "*.Cu" "*.Mask")
			(remove_unused_layers no)
			(net "Net_617")
			(clearance 0.0508)
			(thermal_gap 0.0508)
		)
		(zone
			(layers "F.Cu" "B.Cu" "In1.Cu" "In2.Cu" "In3.Cu" "In4.Cu")
			(hatch none 0.5)
			(connect_pads
				(clearance 0)
			)
			(min_thickness 0.25)
			(keepout
				(tracks not_allowed)
				(vias allowed)
				(pads allowed)
				(copperpour not_allowed)
				(footprints allowed)
			)
			(placement
				(enabled no)
				(sheetname "")
			)
			(fill
				(thermal_gap 0.5)
				(thermal_bridge_width 0.5)
				(island_removal_mode 0)
			)
			(polygon
				(pts
					(arc
						(start 45.257212 -305.209956)
						(mid 42.742612 -305.209956)
						(end 45.257212 -305.209956)
					)
				)
			)
		)
	)
	(footprint ""
		(layer "B.Cu")
		(at 40.11168 -250.23699 -90)
		(property "Reference" "PC26"
			(at 0 0 90)
			(layer "B.SilkS")
			(hide yes)
			(effects
				(font
					(size 1.27 1.27)
				)
				(justify mirror)
			)
		)
		(property "Value" ""
			(at 0 0 90)
			(layer "B.Fab")
			(effects
				(font
					(size 1.27 1.27)
				)
				(justify mirror)
			)
		)
		(duplicate_pad_numbers_are_jumpers no)
		(fp_line
			(start -0.7874 0.4064)
			(end 0.7874 0.4064)
			(stroke
				(width 0.1524)
				(type default)
			)
			(layer "B.SilkS")
		)
		(fp_line
			(start 0.7874 0.4064)
			(end 0.7874 -0.4064)
			(stroke
				(width 0.1524)
				(type default)
			)
			(layer "B.SilkS")
		)
		(fp_line
			(start -0.7874 -0.4064)
			(end -0.7874 0.4064)
			(stroke
				(width 0.1524)
				(type default)
			)
			(layer "B.SilkS")
		)
		(fp_line
			(start 0.7874 -0.4064)
			(end -0.7874 -0.4064)
			(stroke
				(width 0.1524)
				(type default)
			)
			(layer "B.SilkS")
		)
		(fp_line
			(start -0.67945 0.3048)
			(end -0.120396 0.3048)
			(stroke
				(width 0.1)
				(type default)
			)
			(layer "B.Fab")
		)
		(fp_line
			(start -0.120396 0.3048)
			(end -0.120396 0.2794)
			(stroke
				(width 0.1)
				(type default)
			)
			(layer "B.Fab")
		)
		(fp_line
			(start 0.12065 0.3048)
			(end 0.67945 0.3048)
			(stroke
				(width 0.1)
				(type default)
			)
			(layer "B.Fab")
		)
		(fp_line
			(start 0.67945 0.3048)
			(end 0.67945 -0.305054)
			(stroke
				(width 0.1)
				(type default)
			)
			(layer "B.Fab")
		)
		(fp_line
			(start -0.120396 0.2794)
			(end 0.12065 0.2794)
			(stroke
				(width 0.1)
				(type default)
			)
			(layer "B.Fab")
		)
		(fp_line
			(start 0.12065 0.2794)
			(end 0.12065 0.3048)
			(stroke
				(width 0.1)
				(type default)
			)
			(layer "B.Fab")
		)
		(fp_line
			(start -0.12065 -0.2794)
			(end -0.12065 -0.3048)
			(stroke
				(width 0.1)
				(type default)
			)
			(layer "B.Fab")
		)
		(fp_line
			(start 0.12065 -0.2794)
			(end -0.12065 -0.2794)
			(stroke
				(width 0.1)
				(type default)
			)
			(layer "B.Fab")
		)
		(fp_line
			(start -0.67945 -0.3048)
			(end -0.67945 0.3048)
			(stroke
				(width 0.1)
				(type default)
			)
			(layer "B.Fab")
		)
		(fp_line
			(start -0.12065 -0.3048)
			(end -0.67945 -0.3048)
			(stroke
				(width 0.1)
				(type default)
			)
			(layer "B.Fab")
		)
		(fp_line
			(start 0.12065 -0.305054)
			(end 0.12065 -0.2794)
			(stroke
				(width 0.1)
				(type default)
			)
			(layer "B.Fab")
		)
		(fp_line
			(start 0.67945 -0.305054)
			(end 0.12065 -0.305054)
			(stroke
				(width 0.1)
				(type default)
			)
			(layer "B.Fab")
		)
		(pad "1" smd circle
			(at 0.40005 0 90)
			(size 0 0)
			(layers "B.Cu" "B.Mask" "B.Paste")
			(net "FAN_1_P5V")
		)
		(pad "2" smd circle
			(at -0.40005 0 90)
			(size 0 0)
			(layers "B.Cu" "B.Mask" "B.Paste")
			(net "GND")
		)
	)
	(footprint ""
		(layer "B.Cu")
		(at 5.596128 -235.422948)
		(property "Reference" "C2114"
			(at 0 0 0)
			(layer "B.SilkS")
			(hide yes)
			(effects
				(font
					(size 1.27 1.27)
				)
				(justify mirror)
			)
		)
		(property "Value" ""
			(at 0 0 0)
			(layer "B.Fab")
			(effects
				(font
					(size 1.27 1.27)
				)
				(justify mirror)
			)
		)
		(duplicate_pad_numbers_are_jumpers no)
		(fp_line
			(start -2.2098 -0.9398)
			(end -2.2098 0.9398)
			(stroke
				(width 0.1524)
				(type default)
			)
			(layer "B.SilkS")
		)
		(fp_line
			(start -2.2098 0.9398)
			(end 2.2098 0.9398)
			(stroke
				(width 0.1524)
				(type default)
			)
			(layer "B.SilkS")
		)
		(fp_line
			(start 2.2098 -0.9398)
			(end -2.2098 -0.9398)
			(stroke
				(width 0.1524)
				(type default)
			)
			(layer "B.SilkS")
		)
		(fp_line
			(start 2.2098 0.9398)
			(end 2.2098 -0.9398)
			(stroke
				(width 0.1524)
				(type default)
			)
			(layer "B.SilkS")
		)
		(fp_line
			(start -1.700022 -0.899922)
			(end -1.700022 0.899922)
			(stroke
				(width 0.1)
				(type default)
			)
			(layer "B.Fab")
		)
		(fp_line
			(start -1.700022 0.899922)
			(end 1.700022 0.899922)
			(stroke
				(width 0.1)
				(type default)
			)
			(layer "B.Fab")
		)
		(fp_line
			(start 1.700022 -0.899922)
			(end -1.700022 -0.899922)
			(stroke
				(width 0.1)
				(type default)
			)
			(layer "B.Fab")
		)
		(fp_line
			(start 1.700022 0.899922)
			(end 1.700022 -0.899922)
			(stroke
				(width 0.1)
				(type default)
			)
			(layer "B.Fab")
		)
		(pad "1" smd rect
			(at 1.4732 0)
			(size 1.1684 1.5748)
			(layers "B.Cu" "B.Mask" "B.Paste")
			(net "P52V_FAN_6")
		)
		(pad "2" smd rect
			(at -1.4732 0)
			(size 1.1684 1.5748)
			(layers "B.Cu" "B.Mask" "B.Paste")
			(net "GND")
		)
	)
	(footprint ""
		(layer "B.Cu")
		(at 12.446 -73.9648 90)
		(property "Reference" "PC44"
			(at 0 0 90)
			(layer "B.SilkS")
			(hide yes)
			(effects
				(font
					(size 1.27 1.27)
				)
				(justify mirror)
			)
		)
		(property "Value" ""
			(at 0 0 90)
			(layer "B.Fab")
			(effects
				(font
					(size 1.27 1.27)
				)
				(justify mirror)
			)
		)
		(duplicate_pad_numbers_are_jumpers no)
		(fp_line
			(start 0.7874 -0.4064)
			(end -0.7874 -0.4064)
			(stroke
				(width 0.1524)
				(type default)
			)
			(layer "B.SilkS")
		)
		(fp_line
			(start -0.7874 -0.4064)
			(end -0.7874 0.4064)
			(stroke
				(width 0.1524)
				(type default)
			)
			(layer "B.SilkS")
		)
		(fp_line
			(start 0.7874 0.4064)
			(end 0.7874 -0.4064)
			(stroke
				(width 0.1524)
				(type default)
			)
			(layer "B.SilkS")
		)
		(fp_line
			(start -0.7874 0.4064)
			(end 0.7874 0.4064)
			(stroke
				(width 0.1524)
				(type default)
			)
			(layer "B.SilkS")
		)
		(fp_line
			(start 0.67945 -0.305054)
			(end 0.12065 -0.305054)
			(stroke
				(width 0.1)
				(type default)
			)
			(layer "B.Fab")
		)
		(fp_line
			(start 0.12065 -0.305054)
			(end 0.12065 -0.2794)
			(stroke
				(width 0.1)
				(type default)
			)
			(layer "B.Fab")
		)
		(fp_line
			(start -0.12065 -0.3048)
			(end -0.67945 -0.3048)
			(stroke
				(width 0.1)
				(type default)
			)
			(layer "B.Fab")
		)
		(fp_line
			(start -0.67945 -0.3048)
			(end -0.67945 0.3048)
			(stroke
				(width 0.1)
				(type default)
			)
			(layer "B.Fab")
		)
		(fp_line
			(start 0.12065 -0.2794)
			(end -0.12065 -0.2794)
			(stroke
				(width 0.1)
				(type default)
			)
			(layer "B.Fab")
		)
		(fp_line
			(start -0.12065 -0.2794)
			(end -0.12065 -0.3048)
			(stroke
				(width 0.1)
				(type default)
			)
			(layer "B.Fab")
		)
		(fp_line
			(start 0.12065 0.2794)
			(end 0.12065 0.3048)
			(stroke
				(width 0.1)
				(type default)
			)
			(layer "B.Fab")
		)
		(fp_line
			(start -0.120396 0.2794)
			(end 0.12065 0.2794)
			(stroke
				(width 0.1)
				(type default)
			)
			(layer "B.Fab")
		)
		(fp_line
			(start 0.67945 0.3048)
			(end 0.67945 -0.305054)
			(stroke
				(width 0.1)
				(type default)
			)
			(layer "B.Fab")
		)
		(fp_line
			(start 0.12065 0.3048)
			(end 0.67945 0.3048)
			(stroke
				(width 0.1)
				(type default)
			)
			(layer "B.Fab")
		)
		(fp_line
			(start -0.120396 0.3048)
			(end -0.120396 0.2794)
			(stroke
				(width 0.1)
				(type default)
			)
			(layer "B.Fab")
		)
		(fp_line
			(start -0.67945 0.3048)
			(end -0.120396 0.3048)
			(stroke
				(width 0.1)
				(type default)
			)
			(layer "B.Fab")
		)
		(pad "1" smd circle
			(at 0.40005 0 270)
			(size 0 0)
			(layers "B.Cu" "B.Mask" "B.Paste")
			(net "FAN_5_P3V_R")
		)
		(pad "2" smd circle
			(at -0.40005 0 270)
			(size 0 0)
			(layers "B.Cu" "B.Mask" "B.Paste")
			(net "GND")
		)
	)
	(footprint ""
		(layer "B.Cu")
		(at 14.382242 -264.404856 180)
		(property "Reference" "PU9"
			(at -6.191758 -2.430526 0)
			(unlocked yes)
			(layer "B.SilkS")
			(effects
				(font
					(size 0.7874 0.5842)
					(thickness 0.1524)
				)
				(justify left mirror)
			)
		)
		(property "Value" ""
			(at 0 0 0)
			(layer "B.Fab")
			(effects
				(font
					(size 1.27 1.27)
				)
				(justify mirror)
			)
		)
		(duplicate_pad_numbers_are_jumpers no)
		(fp_line
			(start 2.549906 2.549906)
			(end 2.4384 2.549906)
			(stroke
				(width 0.1524)
				(type default)
			)
			(layer "B.SilkS")
		)
		(fp_line
			(start 2.549906 2.2352)
			(end 2.549906 2.549906)
			(stroke
				(width 0.1524)
				(type default)
			)
			(layer "B.SilkS")
		)
		(fp_line
			(start 2.549906 1.4986)
			(end 2.549906 1.7526)
			(stroke
				(width 0.1524)
				(type default)
			)
			(layer "B.SilkS")
		)
		(fp_line
			(start 2.549906 0.6858)
			(end 2.549906 0.9144)
			(stroke
				(width 0.1524)
				(type default)
			)
			(layer "B.SilkS")
		)
		(fp_line
			(start 2.549906 -0.9144)
			(end 2.549906 0.1016)
			(stroke
				(width 0.1524)
				(type default)
			)
			(layer "B.SilkS")
		)
		(fp_line
			(start 2.549906 -1.7526)
			(end 2.549906 -1.4986)
			(stroke
				(width 0.1524)
				(type default)
			)
			(layer "B.SilkS")
		)
		(fp_line
			(start 2.549906 -2.549906)
			(end 2.549906 -2.2352)
			(stroke
				(width 0.1524)
				(type default)
			)
			(layer "B.SilkS")
		)
		(fp_line
			(start 2.4384 -2.549906)
			(end 2.549906 -2.549906)
			(stroke
				(width 0.1524)
				(type default)
			)
			(layer "B.SilkS")
		)
		(fp_line
			(start 2.199894 -3.9624)
			(end 2.199894 -2.9464)
			(stroke
				(width 0.1524)
				(type default)
			)
			(layer "B.SilkS")
		)
		(fp_line
			(start 1.800098 2.9464)
			(end 1.800098 3.4544)
			(stroke
				(width 0.1524)
				(type default)
			)
			(layer "B.SilkS")
		)
		(fp_line
			(start 0.199898 -3.4544)
			(end 0.199898 -2.9464)
			(stroke
				(width 0.1524)
				(type default)
			)
			(layer "B.SilkS")
		)
		(fp_line
			(start -0.199898 2.9464)
			(end -0.199898 3.9624)
			(stroke
				(width 0.1524)
				(type default)
			)
			(layer "B.SilkS")
		)
		(fp_line
			(start -1.800098 -3.9624)
			(end -1.800098 -2.9464)
			(stroke
				(width 0.1524)
				(type default)
			)
			(layer "B.SilkS")
		)
		(fp_line
			(start -2.199894 2.9464)
			(end -2.199894 3.4544)
			(stroke
				(width 0.1524)
				(type default)
			)
			(layer "B.SilkS")
		)
		(fp_line
			(start -2.4384 2.549906)
			(end -2.549906 2.549906)
			(stroke
				(width 0.1524)
				(type default)
			)
			(layer "B.SilkS")
		)
		(fp_line
			(start -2.549906 2.549906)
			(end -2.549906 2.2352)
			(stroke
				(width 0.1524)
				(type default)
			)
			(layer "B.SilkS")
		)
		(fp_line
			(start -2.549906 1.7526)
			(end -2.549906 1.4986)
			(stroke
				(width 0.1524)
				(type default)
			)
			(layer "B.SilkS")
		)
		(fp_line
			(start -2.549906 0.9144)
			(end -2.549906 -0.1016)
			(stroke
				(width 0.1524)
				(type default)
			)
			(layer "B.SilkS")
		)
		(fp_line
			(start -2.549906 -0.6858)
			(end -2.549906 -0.9144)
			(stroke
				(width 0.1524)
				(type default)
			)
			(layer "B.SilkS")
		)
		(fp_line
			(start -2.549906 -1.4986)
			(end -2.549906 -1.7526)
			(stroke
				(width 0.1524)
				(type default)
			)
			(layer "B.SilkS")
		)
		(fp_line
			(start -2.549906 -2.2352)
			(end -2.549906 -2.549906)
			(stroke
				(width 0.1524)
				(type default)
			)
			(layer "B.SilkS")
		)
		(fp_line
			(start -2.549906 -2.549906)
			(end -2.4384 -2.549906)
			(stroke
				(width 0.1524)
				(type default)
			)
			(layer "B.SilkS")
		)
		(fp_poly
			(pts
				(xy 3.565398 -1.513078) (xy 2.939034 -1.199896) (xy 3.565398 -0.886968)
			)
			(stroke
				(width 0)
				(type default)
			)
			(fill yes)
			(layer "B.SilkS")
		)
		(fp_line
			(start 2.549906 2.549906)
			(end -2.549906 2.549906)
			(stroke
				(width 0.1)
				(type default)
			)
			(layer "B.Fab")
		)
		(fp_line
			(start 2.549906 -2.549906)
			(end 2.549906 2.549906)
			(stroke
				(width 0.1)
				(type default)
			)
			(layer "B.Fab")
		)
		(fp_line
			(start 2.199894 -3.9624)
			(end 2.199894 -2.9464)
			(stroke
				(width 0.1)
				(type default)
			)
			(layer "B.Fab")
		)
		(fp_line
			(start 1.800098 2.9464)
			(end 1.800098 3.4544)
			(stroke
				(width 0.1)
				(type default)
			)
			(layer "B.Fab")
		)
		(fp_line
			(start 0.199898 -3.4544)
			(end 0.199898 -2.9464)
			(stroke
				(width 0.1)
				(type default)
			)
			(layer "B.Fab")
		)
		(fp_line
			(start -0.199898 2.9464)
			(end -0.199898 3.9624)
			(stroke
				(width 0.1)
				(type default)
			)
			(layer "B.Fab")
		)
		(fp_line
			(start -1.800098 -3.9624)
			(end -1.800098 -2.9464)
			(stroke
				(width 0.1)
				(type default)
			)
			(layer "B.Fab")
		)
		(fp_line
			(start -2.199894 2.9464)
			(end -2.199894 3.4544)
			(stroke
				(width 0.1)
				(type default)
			)
			(layer "B.Fab")
		)
		(fp_line
			(start -2.549906 2.549906)
			(end -2.549906 -2.549906)
			(stroke
				(width 0.1)
				(type default)
			)
			(layer "B.Fab")
		)
		(fp_line
			(start -2.549906 -2.549906)
			(end 2.549906 -2.549906)
			(stroke
				(width 0.1)
				(type default)
			)
			(layer "B.Fab")
		)
		(fp_poly
			(pts
				(xy 3.7084 -1.584706) (xy 2.939034 -1.199896) (xy 3.7084 -0.81534)
			)
			(stroke
				(width 0)
				(type default)
			)
			(fill yes)
			(layer "B.Fab")
		)
		(fp_text user "3"
			(at 3.333242 1.183894 0)
			(unlocked yes)
			(layer "B.SilkS")
			(effects
				(font
					(size 0.635 0.4064)
					(thickness 0.1524)
				)
				(justify mirror)
			)
		)
		(fp_text user "30"
			(at 2.952242 -3.134106 0)
			(unlocked yes)
			(layer "B.SilkS")
			(effects
				(font
					(size 0.635 0.4064)
					(thickness 0.1524)
				)
				(justify mirror)
			)
		)
		(fp_text user "4"
			(at 2.825242 3.215894 0)
			(unlocked yes)
			(layer "B.SilkS")
			(effects
				(font
					(size 0.635 0.4064)
					(thickness 0.1524)
				)
				(justify mirror)
			)
		)
		(fp_text user "15"
			(at -3.016758 3.088894 0)
			(unlocked yes)
			(layer "B.SilkS")
			(effects
				(font
					(size 0.635 0.4064)
					(thickness 0.1524)
				)
				(justify mirror)
			)
		)
		(fp_text user "19"
			(at -3.016758 -3.007106 0)
			(unlocked yes)
			(layer "B.SilkS")
			(effects
				(font
					(size 0.635 0.4064)
					(thickness 0.1524)
				)
				(justify mirror)
			)
		)
		(fp_text user "16"
			(at -3.429508 1.152144 270)
			(unlocked yes)
			(layer "B.SilkS")
			(effects
				(font
					(size 0.635 0.4064)
					(thickness 0.1524)
				)
				(justify mirror)
			)
		)
		(fp_text user "18"
			(at -3.429508 -1.387856 270)
			(unlocked yes)
			(layer "B.SilkS")
			(effects
				(font
					(size 0.635 0.4064)
					(thickness 0.1524)
				)
				(justify mirror)
			)
		)
		(fp_text user "3"
			(at 3.299968 1.1938 90)
			(unlocked yes)
			(layer "B.Fab")
			(effects
				(font
					(size 0.635 0.4064)
					(thickness 0.1524)
				)
				(justify mirror)
			)
		)
		(fp_text user "30"
			(at 2.9464 -3.045968 180)
			(unlocked yes)
			(layer "B.Fab")
			(effects
				(font
					(size 0.635 0.4064)
					(thickness 0.1524)
				)
				(justify mirror)
			)
		)
		(fp_text user "4"
			(at 2.6416 3.151632 180)
			(unlocked yes)
			(layer "B.Fab")
			(effects
				(font
					(size 0.635 0.4064)
					(thickness 0.1524)
				)
				(justify mirror)
			)
		)
		(fp_text user "19"
			(at -2.8448 -3.096768 180)
			(unlocked yes)
			(layer "B.Fab")
			(effects
				(font
					(size 0.635 0.4064)
					(thickness 0.1524)
				)
				(justify mirror)
			)
		)
		(fp_text user "15"
			(at -2.8956 3.126232 180)
			(unlocked yes)
			(layer "B.Fab")
			(effects
				(font
					(size 0.635 0.4064)
					(thickness 0.1524)
				)
				(justify mirror)
			)
		)
		(fp_text user "18"
			(at -3.304032 -1.2192 90)
			(unlocked yes)
			(layer "B.Fab")
			(effects
				(font
					(size 0.635 0.4064)
					(thickness 0.1524)
				)
				(justify mirror)
			)
		)
		(fp_text user "16"
			(at -3.329432 1.2192 90)
			(unlocked yes)
			(layer "B.Fab")
			(effects
				(font
					(size 0.635 0.4064)
					(thickness 0.1524)
				)
				(justify mirror)
			)
		)
		(pad "1" smd circle
			(at 1.599946 -1.199896 90)
			(size 0 0)
			(layers "B.Cu" "B.Mask" "B.Paste")
			(net "P52V_HSC")
		)
		(pad "2" smd rect
			(at 1.549908 0.40005 270)
			(size 0.3048 2.5146)
			(layers "B.Cu" "B.Mask" "B.Paste")
			(net "P52V_HSC")
		)
		(pad "3" smd rect
			(at 1.549908 1.199896 270)
			(size 0.3048 2.5146)
			(layers "B.Cu" "B.Mask" "B.Paste")
			(net "P52V_FAN_7")
		)
		(pad "4" smd circle
			(at 2.199894 2.350008 180)
			(size 0 0)
			(layers "B.Cu" "B.Mask" "B.Paste")
			(net "P52V_FAN_7")
		)
		(pad "5" smd rect
			(at 1.800098 2.350008)
			(size 0.1778 0.9144)
			(layers "B.Cu" "B.Mask" "B.Paste")
			(net "P52V_FAN_7")
		)
		(pad "6" smd rect
			(at 1.400048 2.350008)
			(size 0.1778 0.9144)
			(layers "B.Cu" "B.Mask" "B.Paste")
			(net "P52V_FAN_7")
		)
		(pad "7" smd rect
			(at 0.999998 2.350008)
			(size 0.1778 0.9144)
			(layers "B.Cu" "B.Mask" "B.Paste")
			(net "P52V_FAN_7")
		)
		(pad "8" smd rect
			(at 0.599948 2.350008)
			(size 0.1778 0.9144)
			(layers "B.Cu" "B.Mask" "B.Paste")
			(net "P52V_FAN_7")
		)
		(pad "9" smd rect
			(at 0.199898 2.350008)
			(size 0.1778 0.9144)
			(layers "B.Cu" "B.Mask" "B.Paste")
			(net "P52V_FAN_7")
		)
		(pad "10" smd rect
			(at -0.199898 2.350008)
			(size 0.1778 0.9144)
			(layers "B.Cu" "B.Mask" "B.Paste")
			(net "P52V_FAN_7")
		)
		(pad "11" smd rect
			(at -0.599948 2.350008)
			(size 0.1778 0.9144)
			(layers "B.Cu" "B.Mask" "B.Paste")
			(net "P52V_FAN_7")
		)
		(pad "12" smd rect
			(at -0.999998 2.350008)
			(size 0.1778 0.9144)
			(layers "B.Cu" "B.Mask" "B.Paste")
			(net "P52V_FAN_7")
		)
		(pad "13" smd rect
			(at -1.400048 2.350008)
			(size 0.1778 0.9144)
			(layers "B.Cu" "B.Mask" "B.Paste")
			(net "P52V_FAN_7")
		)
		(pad "14" smd rect
			(at -1.800098 2.350008)
			(size 0.1778 0.9144)
			(layers "B.Cu" "B.Mask" "B.Paste")
			(net "P52V_FAN_7")
		)
		(pad "15" smd circle
			(at -2.199894 2.350008 180)
			(size 0 0)
			(layers "B.Cu" "B.Mask" "B.Paste")
			(net "P52V_FAN_7")
		)
		(pad "16" smd rect
			(at -1.549908 1.199896 270)
			(size 0.3048 2.5146)
			(layers "B.Cu" "B.Mask" "B.Paste")
			(net "P52V_FAN_7")
		)
		(pad "17" smd rect
			(at -1.549908 -0.40005 270)
			(size 0.3048 2.5146)
			(layers "B.Cu" "B.Mask" "B.Paste")
			(net "P52V_FAN_7")
		)
		(pad "18" smd rect
			(at -1.549908 -1.199896 270)
			(size 0.3048 2.5146)
			(layers "B.Cu" "B.Mask" "B.Paste")
			(net "P52V_HSC")
		)
		(pad "19" smd circle
			(at -2.199894 -2.350008)
			(size 0 0)
			(layers "B.Cu" "B.Mask" "B.Paste")
			(net "FAN_7_CS")
		)
		(pad "20" smd rect
			(at -1.800098 -2.350008)
			(size 0.1778 0.9144)
			(layers "B.Cu" "B.Mask" "B.Paste")
			(net "FAN_7_IMON")
		)
		(pad "21" smd rect
			(at -1.400048 -2.350008)
			(size 0.1778 0.9144)
			(layers "B.Cu" "B.Mask" "B.Paste")
			(net "FAN_7_SS")
		)
		(pad "22" smd rect
			(at -0.999998 -2.350008)
			(size 0.1778 0.9144)
			(layers "B.Cu" "B.Mask" "B.Paste")
			(net "FAN_7_FAULT")
		)
		(pad "23" smd rect
			(at -0.599948 -2.350008)
			(size 0.1778 0.9144)
			(layers "B.Cu" "B.Mask" "B.Paste")
			(net "FAN_7_TIMER")
		)
		(pad "24" smd rect
			(at -0.199898 -2.350008)
			(size 0.1778 0.9144)
			(layers "B.Cu" "B.Mask" "B.Paste")
			(net "FAN_7_CLREF")
		)
		(pad "25" smd rect
			(at 0.199898 -2.350008)
			(size 0.1778 0.9144)
			(layers "B.Cu" "B.Mask" "B.Paste")
			(net "GND")
		)
		(pad "26" smd rect
			(at 0.599948 -2.350008)
			(size 0.1778 0.9144)
			(layers "B.Cu" "B.Mask" "B.Paste")
			(net "FAN_7_ON")
		)
		(pad "27" smd rect
			(at 0.999998 -2.350008)
			(size 0.1778 0.9144)
			(layers "B.Cu" "B.Mask" "B.Paste")
			(net "FAN_7_P3V_R")
		)
		(pad "28" smd rect
			(at 1.400048 -2.350008)
			(size 0.1778 0.9144)
			(layers "B.Cu" "B.Mask" "B.Paste")
			(net "FAN_7_P5V")
		)
		(pad "29" smd rect
			(at 1.800098 -2.350008)
			(size 0.1778 0.9144)
			(layers "B.Cu" "B.Mask" "B.Paste")
			(net "FAN_7_TEMP")
		)
		(pad "30" smd circle
			(at 2.199894 -2.350008)
			(size 0 0)
			(layers "B.Cu" "B.Mask" "B.Paste")
			(net "FAN_7_MODE")
		)
	)
	(footprint ""
		(layer "B.Cu")
		(at 16.782796 -277.431754 180)
		(property "Reference" "C2117"
			(at 0 0 0)
			(layer "B.SilkS")
			(hide yes)
			(effects
				(font
					(size 1.27 1.27)
				)
				(justify mirror)
			)
		)
		(property "Value" ""
			(at 0 0 0)
			(layer "B.Fab")
			(effects
				(font
					(size 1.27 1.27)
				)
				(justify mirror)
			)
		)
		(duplicate_pad_numbers_are_jumpers no)
		(fp_line
			(start 2.2098 0.9398)
			(end 2.2098 -0.9398)
			(stroke
				(width 0.1524)
				(type default)
			)
			(layer "B.SilkS")
		)
		(fp_line
			(start 2.2098 -0.9398)
			(end -2.2098 -0.9398)
			(stroke
				(width 0.1524)
				(type default)
			)
			(layer "B.SilkS")
		)
		(fp_line
			(start -2.2098 0.9398)
			(end 2.2098 0.9398)
			(stroke
				(width 0.1524)
				(type default)
			)
			(layer "B.SilkS")
		)
		(fp_line
			(start -2.2098 -0.9398)
			(end -2.2098 0.9398)
			(stroke
				(width 0.1524)
				(type default)
			)
			(layer "B.SilkS")
		)
		(fp_line
			(start 1.700022 0.899922)
			(end 1.700022 -0.899922)
			(stroke
				(width 0.1)
				(type default)
			)
			(layer "B.Fab")
		)
		(fp_line
			(start 1.700022 -0.899922)
			(end -1.700022 -0.899922)
			(stroke
				(width 0.1)
				(type default)
			)
			(layer "B.Fab")
		)
		(fp_line
			(start -1.700022 0.899922)
			(end 1.700022 0.899922)
			(stroke
				(width 0.1)
				(type default)
			)
			(layer "B.Fab")
		)
		(fp_line
			(start -1.700022 -0.899922)
			(end -1.700022 0.899922)
			(stroke
				(width 0.1)
				(type default)
			)
			(layer "B.Fab")
		)
		(pad "1" smd rect
			(at 1.4732 0 180)
			(size 1.1684 1.5748)
			(layers "B.Cu" "B.Mask" "B.Paste")
			(net "P52V_FAN_7")
		)
		(pad "2" smd rect
			(at -1.4732 0 180)
			(size 1.1684 1.5748)
			(layers "B.Cu" "B.Mask" "B.Paste")
			(net "GND")
		)
	)
	(footprint ""
		(layer "B.Cu")
		(at 38.71468 -73.962768 90)
		(property "Reference" "PR40"
			(at 0 0 90)
			(layer "B.SilkS")
			(hide yes)
			(effects
				(font
					(size 1.27 1.27)
				)
				(justify mirror)
			)
		)
		(property "Value" ""
			(at 0 0 90)
			(layer "B.Fab")
			(effects
				(font
					(size 1.27 1.27)
				)
				(justify mirror)
			)
		)
		(duplicate_pad_numbers_are_jumpers no)
		(fp_line
			(start 0.7874 -0.4064)
			(end -0.7874 -0.4064)
			(stroke
				(width 0.1524)
				(type default)
			)
			(layer "B.SilkS")
		)
		(fp_line
			(start -0.7874 -0.4064)
			(end -0.7874 0.4064)
			(stroke
				(width 0.1524)
				(type default)
			)
			(layer "B.SilkS")
		)
		(fp_line
			(start 0.7874 0.4064)
			(end 0.7874 -0.4064)
			(stroke
				(width 0.1524)
				(type default)
			)
			(layer "B.SilkS")
		)
		(fp_line
			(start -0.7874 0.4064)
			(end 0.7874 0.4064)
			(stroke
				(width 0.1524)
				(type default)
			)
			(layer "B.SilkS")
		)
		(fp_line
			(start 0.67945 -0.305054)
			(end 0.12065 -0.305054)
			(stroke
				(width 0.1)
				(type default)
			)
			(layer "B.Fab")
		)
		(fp_line
			(start 0.12065 -0.305054)
			(end 0.12065 -0.2794)
			(stroke
				(width 0.1)
				(type default)
			)
			(layer "B.Fab")
		)
		(fp_line
			(start -0.12065 -0.3048)
			(end -0.67945 -0.3048)
			(stroke
				(width 0.1)
				(type default)
			)
			(layer "B.Fab")
		)
		(fp_line
			(start -0.67945 -0.3048)
			(end -0.67945 0.3048)
			(stroke
				(width 0.1)
				(type default)
			)
			(layer "B.Fab")
		)
		(fp_line
			(start 0.12065 -0.2794)
			(end -0.12065 -0.2794)
			(stroke
				(width 0.1)
				(type default)
			)
			(layer "B.Fab")
		)
		(fp_line
			(start -0.12065 -0.2794)
			(end -0.12065 -0.3048)
			(stroke
				(width 0.1)
				(type default)
			)
			(layer "B.Fab")
		)
		(fp_line
			(start 0.12065 0.2794)
			(end 0.12065 0.3048)
			(stroke
				(width 0.1)
				(type default)
			)
			(layer "B.Fab")
		)
		(fp_line
			(start -0.120396 0.2794)
			(end 0.12065 0.2794)
			(stroke
				(width 0.1)
				(type default)
			)
			(layer "B.Fab")
		)
		(fp_line
			(start 0.67945 0.3048)
			(end 0.67945 -0.305054)
			(stroke
				(width 0.1)
				(type default)
			)
			(layer "B.Fab")
		)
		(fp_line
			(start 0.12065 0.3048)
			(end 0.67945 0.3048)
			(stroke
				(width 0.1)
				(type default)
			)
			(layer "B.Fab")
		)
		(fp_line
			(start -0.120396 0.3048)
			(end -0.120396 0.2794)
			(stroke
				(width 0.1)
				(type default)
			)
			(layer "B.Fab")
		)
		(fp_line
			(start -0.67945 0.3048)
			(end -0.120396 0.3048)
			(stroke
				(width 0.1)
				(type default)
			)
			(layer "B.Fab")
		)
		(pad "1" smd circle
			(at 0.40005 0 270)
			(size 0 0)
			(layers "B.Cu" "B.Mask" "B.Paste")
			(net "FAN_2_TEMP")
		)
		(pad "2" smd circle
			(at -0.40005 0 270)
			(size 0 0)
			(layers "B.Cu" "B.Mask" "B.Paste")
			(net "GND")
		)
	)
	(footprint ""
		(layer "B.Cu")
		(at 10.746486 -64.837056 -90)
		(property "Reference" "PC2122"
			(at 0 0 90)
			(layer "B.SilkS")
			(hide yes)
			(effects
				(font
					(size 1.27 1.27)
				)
				(justify mirror)
			)
		)
		(property "Value" ""
			(at 0 0 90)
			(layer "B.Fab")
			(effects
				(font
					(size 1.27 1.27)
				)
				(justify mirror)
			)
		)
		(duplicate_pad_numbers_are_jumpers no)
		(fp_line
			(start -0.7874 0.4064)
			(end 0.7874 0.4064)
			(stroke
				(width 0.1524)
				(type default)
			)
			(layer "B.SilkS")
		)
		(fp_line
			(start 0.7874 0.4064)
			(end 0.7874 -0.4064)
			(stroke
				(width 0.1524)
				(type default)
			)
			(layer "B.SilkS")
		)
		(fp_line
			(start -0.7874 -0.4064)
			(end -0.7874 0.4064)
			(stroke
				(width 0.1524)
				(type default)
			)
			(layer "B.SilkS")
		)
		(fp_line
			(start 0.7874 -0.4064)
			(end -0.7874 -0.4064)
			(stroke
				(width 0.1524)
				(type default)
			)
			(layer "B.SilkS")
		)
		(fp_line
			(start -0.67945 0.3048)
			(end -0.120396 0.3048)
			(stroke
				(width 0.1)
				(type default)
			)
			(layer "B.Fab")
		)
		(fp_line
			(start -0.120396 0.3048)
			(end -0.120396 0.2794)
			(stroke
				(width 0.1)
				(type default)
			)
			(layer "B.Fab")
		)
		(fp_line
			(start 0.12065 0.3048)
			(end 0.67945 0.3048)
			(stroke
				(width 0.1)
				(type default)
			)
			(layer "B.Fab")
		)
		(fp_line
			(start 0.67945 0.3048)
			(end 0.67945 -0.305054)
			(stroke
				(width 0.1)
				(type default)
			)
			(layer "B.Fab")
		)
		(fp_line
			(start -0.120396 0.2794)
			(end 0.12065 0.2794)
			(stroke
				(width 0.1)
				(type default)
			)
			(layer "B.Fab")
		)
		(fp_line
			(start 0.12065 0.2794)
			(end 0.12065 0.3048)
			(stroke
				(width 0.1)
				(type default)
			)
			(layer "B.Fab")
		)
		(fp_line
			(start -0.12065 -0.2794)
			(end -0.12065 -0.3048)
			(stroke
				(width 0.1)
				(type default)
			)
			(layer "B.Fab")
		)
		(fp_line
			(start 0.12065 -0.2794)
			(end -0.12065 -0.2794)
			(stroke
				(width 0.1)
				(type default)
			)
			(layer "B.Fab")
		)
		(fp_line
			(start -0.67945 -0.3048)
			(end -0.67945 0.3048)
			(stroke
				(width 0.1)
				(type default)
			)
			(layer "B.Fab")
		)
		(fp_line
			(start -0.12065 -0.3048)
			(end -0.67945 -0.3048)
			(stroke
				(width 0.1)
				(type default)
			)
			(layer "B.Fab")
		)
		(fp_line
			(start 0.12065 -0.305054)
			(end 0.12065 -0.2794)
			(stroke
				(width 0.1)
				(type default)
			)
			(layer "B.Fab")
		)
		(fp_line
			(start 0.67945 -0.305054)
			(end 0.12065 -0.305054)
			(stroke
				(width 0.1)
				(type default)
			)
			(layer "B.Fab")
		)
		(pad "1" smd circle
			(at 0.40005 0 90)
			(size 0 0)
			(layers "B.Cu" "B.Mask" "B.Paste")
			(net "FAN_4_TEMP")
		)
		(pad "2" smd circle
			(at -0.40005 0 90)
			(size 0 0)
			(layers "B.Cu" "B.Mask" "B.Paste")
			(net "GND")
		)
	)
	(footprint ""
		(layer "B.Cu")
		(at 8.694166 -64.837056 -90)
		(property "Reference" "PC39"
			(at 0 0 90)
			(layer "B.SilkS")
			(hide yes)
			(effects
				(font
					(size 1.27 1.27)
				)
				(justify mirror)
			)
		)
		(property "Value" ""
			(at 0 0 90)
			(layer "B.Fab")
			(effects
				(font
					(size 1.27 1.27)
				)
				(justify mirror)
			)
		)
		(duplicate_pad_numbers_are_jumpers no)
		(fp_line
			(start -0.7874 0.4064)
			(end 0.7874 0.4064)
			(stroke
				(width 0.1524)
				(type default)
			)
			(layer "B.SilkS")
		)
		(fp_line
			(start 0.7874 0.4064)
			(end 0.7874 -0.4064)
			(stroke
				(width 0.1524)
				(type default)
			)
			(layer "B.SilkS")
		)
		(fp_line
			(start -0.7874 -0.4064)
			(end -0.7874 0.4064)
			(stroke
				(width 0.1524)
				(type default)
			)
			(layer "B.SilkS")
		)
		(fp_line
			(start 0.7874 -0.4064)
			(end -0.7874 -0.4064)
			(stroke
				(width 0.1524)
				(type default)
			)
			(layer "B.SilkS")
		)
		(fp_line
			(start -0.67945 0.3048)
			(end -0.120396 0.3048)
			(stroke
				(width 0.1)
				(type default)
			)
			(layer "B.Fab")
		)
		(fp_line
			(start -0.120396 0.3048)
			(end -0.120396 0.2794)
			(stroke
				(width 0.1)
				(type default)
			)
			(layer "B.Fab")
		)
		(fp_line
			(start 0.12065 0.3048)
			(end 0.67945 0.3048)
			(stroke
				(width 0.1)
				(type default)
			)
			(layer "B.Fab")
		)
		(fp_line
			(start 0.67945 0.3048)
			(end 0.67945 -0.305054)
			(stroke
				(width 0.1)
				(type default)
			)
			(layer "B.Fab")
		)
		(fp_line
			(start -0.120396 0.2794)
			(end 0.12065 0.2794)
			(stroke
				(width 0.1)
				(type default)
			)
			(layer "B.Fab")
		)
		(fp_line
			(start 0.12065 0.2794)
			(end 0.12065 0.3048)
			(stroke
				(width 0.1)
				(type default)
			)
			(layer "B.Fab")
		)
		(fp_line
			(start -0.12065 -0.2794)
			(end -0.12065 -0.3048)
			(stroke
				(width 0.1)
				(type default)
			)
			(layer "B.Fab")
		)
		(fp_line
			(start 0.12065 -0.2794)
			(end -0.12065 -0.2794)
			(stroke
				(width 0.1)
				(type default)
			)
			(layer "B.Fab")
		)
		(fp_line
			(start -0.67945 -0.3048)
			(end -0.67945 0.3048)
			(stroke
				(width 0.1)
				(type default)
			)
			(layer "B.Fab")
		)
		(fp_line
			(start -0.12065 -0.3048)
			(end -0.67945 -0.3048)
			(stroke
				(width 0.1)
				(type default)
			)
			(layer "B.Fab")
		)
		(fp_line
			(start 0.12065 -0.305054)
			(end 0.12065 -0.2794)
			(stroke
				(width 0.1)
				(type default)
			)
			(layer "B.Fab")
		)
		(fp_line
			(start 0.67945 -0.305054)
			(end 0.12065 -0.305054)
			(stroke
				(width 0.1)
				(type default)
			)
			(layer "B.Fab")
		)
		(pad "1" smd circle
			(at 0.40005 0 90)
			(size 0 0)
			(layers "B.Cu" "B.Mask" "B.Paste")
			(net "FAN_4_P5V")
		)
		(pad "2" smd circle
			(at -0.40005 0 90)
			(size 0 0)
			(layers "B.Cu" "B.Mask" "B.Paste")
			(net "GND")
		)
	)
	(footprint ""
		(layer "B.Cu")
		(at 43.053 -258.572 -90)
		(property "Reference" "PC3118"
			(at 0 0 90)
			(layer "B.SilkS")
			(hide yes)
			(effects
				(font
					(size 1.27 1.27)
				)
				(justify mirror)
			)
		)
		(property "Value" ""
			(at 0 0 90)
			(layer "B.Fab")
			(effects
				(font
					(size 1.27 1.27)
				)
				(justify mirror)
			)
		)
		(duplicate_pad_numbers_are_jumpers no)
		(fp_line
			(start -0.7874 0.4064)
			(end 0.7874 0.4064)
			(stroke
				(width 0.1524)
				(type default)
			)
			(layer "B.SilkS")
		)
		(fp_line
			(start 0.7874 0.4064)
			(end 0.7874 -0.4064)
			(stroke
				(width 0.1524)
				(type default)
			)
			(layer "B.SilkS")
		)
		(fp_line
			(start -0.7874 -0.4064)
			(end -0.7874 0.4064)
			(stroke
				(width 0.1524)
				(type default)
			)
			(layer "B.SilkS")
		)
		(fp_line
			(start 0.7874 -0.4064)
			(end -0.7874 -0.4064)
			(stroke
				(width 0.1524)
				(type default)
			)
			(layer "B.SilkS")
		)
		(fp_line
			(start -0.67945 0.3048)
			(end -0.120396 0.3048)
			(stroke
				(width 0.1)
				(type default)
			)
			(layer "B.Fab")
		)
		(fp_line
			(start -0.120396 0.3048)
			(end -0.120396 0.2794)
			(stroke
				(width 0.1)
				(type default)
			)
			(layer "B.Fab")
		)
		(fp_line
			(start 0.12065 0.3048)
			(end 0.67945 0.3048)
			(stroke
				(width 0.1)
				(type default)
			)
			(layer "B.Fab")
		)
		(fp_line
			(start 0.67945 0.3048)
			(end 0.67945 -0.305054)
			(stroke
				(width 0.1)
				(type default)
			)
			(layer "B.Fab")
		)
		(fp_line
			(start -0.120396 0.2794)
			(end 0.12065 0.2794)
			(stroke
				(width 0.1)
				(type default)
			)
			(layer "B.Fab")
		)
		(fp_line
			(start 0.12065 0.2794)
			(end 0.12065 0.3048)
			(stroke
				(width 0.1)
				(type default)
			)
			(layer "B.Fab")
		)
		(fp_line
			(start -0.12065 -0.2794)
			(end -0.12065 -0.3048)
			(stroke
				(width 0.1)
				(type default)
			)
			(layer "B.Fab")
		)
		(fp_line
			(start 0.12065 -0.2794)
			(end -0.12065 -0.2794)
			(stroke
				(width 0.1)
				(type default)
			)
			(layer "B.Fab")
		)
		(fp_line
			(start -0.67945 -0.3048)
			(end -0.67945 0.3048)
			(stroke
				(width 0.1)
				(type default)
			)
			(layer "B.Fab")
		)
		(fp_line
			(start -0.12065 -0.3048)
			(end -0.67945 -0.3048)
			(stroke
				(width 0.1)
				(type default)
			)
			(layer "B.Fab")
		)
		(fp_line
			(start 0.12065 -0.305054)
			(end 0.12065 -0.2794)
			(stroke
				(width 0.1)
				(type default)
			)
			(layer "B.Fab")
		)
		(fp_line
			(start 0.67945 -0.305054)
			(end 0.12065 -0.305054)
			(stroke
				(width 0.1)
				(type default)
			)
			(layer "B.Fab")
		)
		(pad "1" smd circle
			(at 0.40005 0 90)
			(size 0 0)
			(layers "B.Cu" "B.Mask" "B.Paste")
			(net "GND")
		)
		(pad "2" smd circle
			(at -0.40005 0 90)
			(size 0 0)
			(layers "B.Cu" "B.Mask" "B.Paste")
			(net "FAN_0_CLREF")
		)
	)
	(footprint ""
		(layer "B.Cu")
		(at 40.23868 -64.837056 -90)
		(property "Reference" "PC19"
			(at 0 0 90)
			(layer "B.SilkS")
			(hide yes)
			(effects
				(font
					(size 1.27 1.27)
				)
				(justify mirror)
			)
		)
		(property "Value" ""
			(at 0 0 90)
			(layer "B.Fab")
			(effects
				(font
					(size 1.27 1.27)
				)
				(justify mirror)
			)
		)
		(duplicate_pad_numbers_are_jumpers no)
		(fp_line
			(start -0.7874 0.4064)
			(end 0.7874 0.4064)
			(stroke
				(width 0.1524)
				(type default)
			)
			(layer "B.SilkS")
		)
		(fp_line
			(start 0.7874 0.4064)
			(end 0.7874 -0.4064)
			(stroke
				(width 0.1524)
				(type default)
			)
			(layer "B.SilkS")
		)
		(fp_line
			(start -0.7874 -0.4064)
			(end -0.7874 0.4064)
			(stroke
				(width 0.1524)
				(type default)
			)
			(layer "B.SilkS")
		)
		(fp_line
			(start 0.7874 -0.4064)
			(end -0.7874 -0.4064)
			(stroke
				(width 0.1524)
				(type default)
			)
			(layer "B.SilkS")
		)
		(fp_line
			(start -0.67945 0.3048)
			(end -0.120396 0.3048)
			(stroke
				(width 0.1)
				(type default)
			)
			(layer "B.Fab")
		)
		(fp_line
			(start -0.120396 0.3048)
			(end -0.120396 0.2794)
			(stroke
				(width 0.1)
				(type default)
			)
			(layer "B.Fab")
		)
		(fp_line
			(start 0.12065 0.3048)
			(end 0.67945 0.3048)
			(stroke
				(width 0.1)
				(type default)
			)
			(layer "B.Fab")
		)
		(fp_line
			(start 0.67945 0.3048)
			(end 0.67945 -0.305054)
			(stroke
				(width 0.1)
				(type default)
			)
			(layer "B.Fab")
		)
		(fp_line
			(start -0.120396 0.2794)
			(end 0.12065 0.2794)
			(stroke
				(width 0.1)
				(type default)
			)
			(layer "B.Fab")
		)
		(fp_line
			(start 0.12065 0.2794)
			(end 0.12065 0.3048)
			(stroke
				(width 0.1)
				(type default)
			)
			(layer "B.Fab")
		)
		(fp_line
			(start -0.12065 -0.2794)
			(end -0.12065 -0.3048)
			(stroke
				(width 0.1)
				(type default)
			)
			(layer "B.Fab")
		)
		(fp_line
			(start 0.12065 -0.2794)
			(end -0.12065 -0.2794)
			(stroke
				(width 0.1)
				(type default)
			)
			(layer "B.Fab")
		)
		(fp_line
			(start -0.67945 -0.3048)
			(end -0.67945 0.3048)
			(stroke
				(width 0.1)
				(type default)
			)
			(layer "B.Fab")
		)
		(fp_line
			(start -0.12065 -0.3048)
			(end -0.67945 -0.3048)
			(stroke
				(width 0.1)
				(type default)
			)
			(layer "B.Fab")
		)
		(fp_line
			(start 0.12065 -0.305054)
			(end 0.12065 -0.2794)
			(stroke
				(width 0.1)
				(type default)
			)
			(layer "B.Fab")
		)
		(fp_line
			(start 0.67945 -0.305054)
			(end 0.12065 -0.305054)
			(stroke
				(width 0.1)
				(type default)
			)
			(layer "B.Fab")
		)
		(pad "1" smd circle
			(at 0.40005 0 90)
			(size 0 0)
			(layers "B.Cu" "B.Mask" "B.Paste")
			(net "FAN_3_P5V")
		)
		(pad "2" smd circle
			(at -0.40005 0 90)
			(size 0 0)
			(layers "B.Cu" "B.Mask" "B.Paste")
			(net "GND")
		)
	)
	(footprint ""
		(layer "B.Cu")
		(at 9.906 -172.847 180)
		(property "Reference" "C1943"
			(at 0 0 0)
			(layer "B.SilkS")
			(hide yes)
			(effects
				(font
					(size 1.27 1.27)
				)
				(justify mirror)
			)
		)
		(property "Value" ""
			(at 0 0 0)
			(layer "B.Fab")
			(effects
				(font
					(size 1.27 1.27)
				)
				(justify mirror)
			)
		)
		(duplicate_pad_numbers_are_jumpers no)
		(fp_line
			(start 0.7874 0.4064)
			(end 0.7874 -0.4064)
			(stroke
				(width 0.1524)
				(type default)
			)
			(layer "B.SilkS")
		)
		(fp_line
			(start 0.7874 -0.4064)
			(end -0.7874 -0.4064)
			(stroke
				(width 0.1524)
				(type default)
			)
			(layer "B.SilkS")
		)
		(fp_line
			(start -0.7874 0.4064)
			(end 0.7874 0.4064)
			(stroke
				(width 0.1524)
				(type default)
			)
			(layer "B.SilkS")
		)
		(fp_line
			(start -0.7874 -0.4064)
			(end -0.7874 0.4064)
			(stroke
				(width 0.1524)
				(type default)
			)
			(layer "B.SilkS")
		)
		(fp_line
			(start 0.67945 0.3048)
			(end 0.67945 -0.305054)
			(stroke
				(width 0.1)
				(type default)
			)
			(layer "B.Fab")
		)
		(fp_line
			(start 0.67945 -0.305054)
			(end 0.12065 -0.305054)
			(stroke
				(width 0.1)
				(type default)
			)
			(layer "B.Fab")
		)
		(fp_line
			(start 0.12065 0.3048)
			(end 0.67945 0.3048)
			(stroke
				(width 0.1)
				(type default)
			)
			(layer "B.Fab")
		)
		(fp_line
			(start 0.12065 0.2794)
			(end 0.12065 0.3048)
			(stroke
				(width 0.1)
				(type default)
			)
			(layer "B.Fab")
		)
		(fp_line
			(start 0.12065 -0.2794)
			(end -0.12065 -0.2794)
			(stroke
				(width 0.1)
				(type default)
			)
			(layer "B.Fab")
		)
		(fp_line
			(start 0.12065 -0.305054)
			(end 0.12065 -0.2794)
			(stroke
				(width 0.1)
				(type default)
			)
			(layer "B.Fab")
		)
		(fp_line
			(start -0.120396 0.3048)
			(end -0.120396 0.2794)
			(stroke
				(width 0.1)
				(type default)
			)
			(layer "B.Fab")
		)
		(fp_line
			(start -0.120396 0.2794)
			(end 0.12065 0.2794)
			(stroke
				(width 0.1)
				(type default)
			)
			(layer "B.Fab")
		)
		(fp_line
			(start -0.12065 -0.2794)
			(end -0.12065 -0.3048)
			(stroke
				(width 0.1)
				(type default)
			)
			(layer "B.Fab")
		)
		(fp_line
			(start -0.12065 -0.3048)
			(end -0.67945 -0.3048)
			(stroke
				(width 0.1)
				(type default)
			)
			(layer "B.Fab")
		)
		(fp_line
			(start -0.67945 0.3048)
			(end -0.120396 0.3048)
			(stroke
				(width 0.1)
				(type default)
			)
			(layer "B.Fab")
		)
		(fp_line
			(start -0.67945 -0.3048)
			(end -0.67945 0.3048)
			(stroke
				(width 0.1)
				(type default)
			)
			(layer "B.Fab")
		)
		(pad "1" smd circle
			(at 0.40005 0)
			(size 0 0)
			(layers "B.Cu" "B.Mask" "B.Paste")
			(net "P3V3_AUX")
		)
		(pad "2" smd circle
			(at -0.40005 0)
			(size 0 0)
			(layers "B.Cu" "B.Mask" "B.Paste")
			(net "GND")
		)
	)
	(footprint ""
		(layer "B.Cu")
		(at 44.99991 -211.009992)
		(property "Reference" "J2"
			(at 4.384802 -5.317744 0)
			(unlocked yes)
			(layer "B.SilkS")
			(effects
				(font
					(size 0.7874 0.5842)
					(thickness 0.1524)
				)
				(justify left mirror)
			)
		)
		(property "Value" ""
			(at 0 0 0)
			(layer "B.Fab")
			(effects
				(font
					(size 1.27 1.27)
				)
				(justify mirror)
			)
		)
		(duplicate_pad_numbers_are_jumpers no)
		(fp_line
			(start -6.35 -4.52501)
			(end 4.350004 -4.52501)
			(stroke
				(width 0.1524)
				(type default)
			)
			(layer "B.SilkS")
		)
		(fp_line
			(start -6.35 18.524982)
			(end -6.35 -4.52501)
			(stroke
				(width 0.1524)
				(type default)
			)
			(layer "B.SilkS")
		)
		(fp_line
			(start -3.24993 -1.42494)
			(end -1.96977 -1.42494)
			(stroke
				(width 0.1524)
				(type default)
			)
			(layer "B.SilkS")
		)
		(fp_line
			(start -3.24993 15.424912)
			(end -3.24993 -1.42494)
			(stroke
				(width 0.1524)
				(type default)
			)
			(layer "B.SilkS")
		)
		(fp_line
			(start -0.029972 -1.42494)
			(end 1.249934 -1.42494)
			(stroke
				(width 0.1524)
				(type default)
			)
			(layer "B.SilkS")
		)
		(fp_line
			(start 1.249934 -1.42494)
			(end 1.249934 5.799836)
			(stroke
				(width 0.1524)
				(type default)
			)
			(layer "B.SilkS")
		)
		(fp_line
			(start 1.249934 5.799836)
			(end 4.350004 5.799836)
			(stroke
				(width 0.1524)
				(type default)
			)
			(layer "B.SilkS")
		)
		(fp_line
			(start 1.249934 8.200136)
			(end 1.249934 15.424912)
			(stroke
				(width 0.1524)
				(type default)
			)
			(layer "B.SilkS")
		)
		(fp_line
			(start 1.249934 8.200136)
			(end 4.350004 8.200136)
			(stroke
				(width 0.1524)
				(type default)
			)
			(layer "B.SilkS")
		)
		(fp_line
			(start 1.249934 15.424912)
			(end -3.24993 15.424912)
			(stroke
				(width 0.1524)
				(type default)
			)
			(layer "B.SilkS")
		)
		(fp_line
			(start 4.350004 -4.52501)
			(end 4.350004 18.524982)
			(stroke
				(width 0.1524)
				(type default)
			)
			(layer "B.SilkS")
		)
		(fp_line
			(start 4.350004 18.524982)
			(end -6.35 18.524982)
			(stroke
				(width 0.1524)
				(type default)
			)
			(layer "B.SilkS")
		)
		(fp_poly
			(pts
				(xy 5.527802 -0.508) (xy 5.527802 0.508) (xy 4.511802 0)
			)
			(stroke
				(width 0)
				(type default)
			)
			(fill yes)
			(layer "B.SilkS")
		)
		(fp_line
			(start -6.35 -4.52501)
			(end 4.350004 -4.52501)
			(stroke
				(width 0.1)
				(type default)
			)
			(layer "B.Fab")
		)
		(fp_line
			(start -6.35 18.524982)
			(end -6.35 -4.52501)
			(stroke
				(width 0.1)
				(type default)
			)
			(layer "B.Fab")
		)
		(fp_line
			(start 4.350004 -4.52501)
			(end 4.350004 18.524982)
			(stroke
				(width 0.1)
				(type default)
			)
			(layer "B.Fab")
		)
		(fp_line
			(start 4.350004 18.524982)
			(end -6.35 18.524982)
			(stroke
				(width 0.1)
				(type default)
			)
			(layer "B.Fab")
		)
		(fp_poly
			(pts
				(xy 5.527802 -0.508) (xy 5.527802 0.508) (xy 4.511802 0)
			)
			(stroke
				(width 0)
				(type default)
			)
			(fill yes)
			(layer "B.Fab")
		)
		(pad "" np_thru_hole circle
			(at -0.999998 -1.89992 270)
			(size 1.4986 1.4986)
			(drill 1.4986)
			(layers "*.Cu" "*.Mask")
			(clearance 0.381)
			(thermal_gap 0.381)
		)
		(pad "1" thru_hole rect
			(at 0 0 270)
			(size 1.3716 1.3716)
			(drill 0.9652)
			(layers "*.Cu" "*.Mask")
			(remove_unused_layers no)
			(net "FAN_1_TACH_IL_D")
			(clearance 0.0508)
			(padstack
				(mode front_inner_back)
				(layer "Inner"
					(shape circle)
					(size 1.3716 1.3716)
					(clearance 0.0508)
				)
				(layer "B.Cu"
					(shape rect)
					(size 1.3716 1.3716)
					(thermal_gap 0.0508)
					(clearance 0.0508)
				)
			)
		)
		(pad "2" thru_hole circle
			(at -1.999996 0 270)
			(size 1.3716 1.3716)
			(drill 0.9652)
			(layers "*.Cu" "*.Mask")
			(remove_unused_layers no)
			(net "FAN_1_PWM_OL_R")
			(clearance 0.0508)
			(thermal_gap 0.0508)
		)
		(pad "3" thru_hole circle
			(at 0 1.999996 270)
			(size 1.3716 1.3716)
			(drill 0.9652)
			(layers "*.Cu" "*.Mask")
			(remove_unused_layers no)
			(net "FAN_1_PWM_IL_R")
			(clearance 0.0508)
			(thermal_gap 0.0508)
		)
		(pad "4" thru_hole circle
			(at -1.999996 1.999996 270)
			(size 1.3716 1.3716)
			(drill 0.9652)
			(layers "*.Cu" "*.Mask")
			(remove_unused_layers no)
			(net "FAN_1_PRESENT_R_N")
			(clearance 0.0508)
			(thermal_gap 0.0508)
		)
		(pad "5" thru_hole circle
			(at 0 3.999992 270)
			(size 1.3716 1.3716)
			(drill 0.9652)
			(layers "*.Cu" "*.Mask")
			(remove_unused_layers no)
			(net "P12V_LED_R1_FAN1")
			(clearance 0.0508)
			(thermal_gap 0.0508)
		)
		(pad "6" thru_hole circle
			(at -1.999996 3.999992 270)
			(size 1.3716 1.3716)
			(drill 0.9652)
			(layers "*.Cu" "*.Mask")
			(remove_unused_layers no)
			(net "SMB_FAN1_SCL_R")
			(clearance 0.0508)
			(thermal_gap 0.0508)
		)
		(pad "7" thru_hole circle
			(at 0 5.999988 270)
			(size 1.3716 1.3716)
			(drill 0.9652)
			(layers "*.Cu" "*.Mask")
			(remove_unused_layers no)
			(net "SMB_FAN1_SDA_R")
			(clearance 0.0508)
			(thermal_gap 0.0508)
		)
		(pad "8" thru_hole circle
			(at -1.999996 5.999988 270)
			(size 1.3716 1.3716)
			(drill 0.9652)
			(layers "*.Cu" "*.Mask")
			(remove_unused_layers no)
			(net "GND")
			(clearance 0.0508)
			(thermal_gap 0.0508)
		)
		(pad "9" thru_hole circle
			(at 0 7.999984 270)
			(size 1.3716 1.3716)
			(drill 0.9652)
			(layers "*.Cu" "*.Mask")
			(remove_unused_layers no)
			(net "GND")
			(clearance 0.0508)
			(thermal_gap 0.0508)
		)
		(pad "10" thru_hole circle
			(at -1.999996 7.999984 270)
			(size 1.3716 1.3716)
			(drill 0.9652)
			(layers "*.Cu" "*.Mask")
			(remove_unused_layers no)
			(net "P52V_FAN_1")
			(clearance 0.0508)
			(thermal_gap 0.0508)
		)
		(pad "11" thru_hole circle
			(at 0 9.99998 270)
			(size 1.3716 1.3716)
			(drill 0.9652)
			(layers "*.Cu" "*.Mask")
			(remove_unused_layers no)
			(net "P52V_FAN_1")
			(clearance 0.0508)
			(thermal_gap 0.0508)
		)
		(pad "12" thru_hole circle
			(at -1.999996 9.99998 270)
			(size 1.3716 1.3716)
			(drill 0.9652)
			(layers "*.Cu" "*.Mask")
			(remove_unused_layers no)
			(net "FAN_1_FAIL_R_LED_N")
			(clearance 0.0508)
			(thermal_gap 0.0508)
		)
		(pad "13" thru_hole circle
			(at 0 11.999976 270)
			(size 1.3716 1.3716)
			(drill 0.9652)
			(layers "*.Cu" "*.Mask")
			(remove_unused_layers no)
			(net "FAN_1_TACH_OL_D")
			(clearance 0.0508)
			(thermal_gap 0.0508)
		)
		(pad "14" thru_hole circle
			(at -1.999996 11.999976 270)
			(size 1.3716 1.3716)
			(drill 0.9652)
			(layers "*.Cu" "*.Mask")
			(remove_unused_layers no)
			(net "FAN_1_OK_R_LED_N")
			(clearance 0.0508)
			(thermal_gap 0.0508)
		)
		(pad "15" thru_hole circle
			(at 0 13.999972 270)
			(size 1.3716 1.3716)
			(drill 0.9652)
			(layers "*.Cu" "*.Mask")
			(remove_unused_layers no)
			(net "Net_615")
			(clearance 0.0508)
			(thermal_gap 0.0508)
		)
		(pad "16" thru_hole circle
			(at -1.999996 13.999972 270)
			(size 1.3716 1.3716)
			(drill 0.9652)
			(layers "*.Cu" "*.Mask")
			(remove_unused_layers no)
			(net "Net_614")
			(clearance 0.0508)
			(thermal_gap 0.0508)
		)
		(zone
			(layers "F.Cu" "B.Cu" "In1.Cu" "In2.Cu" "In3.Cu" "In4.Cu")
			(hatch none 0.5)
			(connect_pads
				(clearance 0)
			)
			(min_thickness 0.25)
			(keepout
				(tracks not_allowed)
				(vias allowed)
				(pads allowed)
				(copperpour not_allowed)
				(footprints allowed)
			)
			(placement
				(enabled no)
				(sheetname "")
			)
			(fill
				(thermal_gap 0.5)
				(thermal_bridge_width 0.5)
				(island_removal_mode 0)
			)
			(polygon
				(pts
					(arc
						(start 45.257212 -212.909912)
						(mid 42.742612 -212.909912)
						(end 45.257212 -212.909912)
					)
				)
			)
		)
	)
	(gr_poly
		(pts
			(xy 7.05358 -85.4837) (xy 7.05358 -84.56422) (xy 6.76402 -84.27466) (xy 3.2766 -84.27466) (xy 2.99212 -84.55914)
			(xy 2.99212 -85.47354) (xy 3.22326 -85.70468) (xy 6.8326 -85.70468)
		)
		(stroke
			(width 0)
			(type solid)
		)
		(fill yes)
		(layer "F.Cu")
		(net "GND")
	)
	(gr_poly
		(pts
			(xy 47.58436 -310.73344) (xy 47.58436 -308.3814) (xy 47.48276 -308.2798) (xy 43.38574 -308.2798)
			(xy 43.31462 -308.35092) (xy 43.31462 -310.74868) (xy 43.361864 -310.795924) (xy 47.521876 -310.795924)
		)
		(stroke
			(width 0)
			(type solid)
		)
		(fill yes)
		(layer "F.Cu")
		(net "P12V_LED_FAN0")
	)
	(gr_poly
		(pts
			(xy 50.01006 -310.7436) (xy 50.01006 -308.34838) (xy 49.9491 -308.28742) (xy 47.96028 -308.28742)
			(xy 47.92218 -308.32552) (xy 47.92218 -310.78424) (xy 47.98822 -310.85028) (xy 49.90338 -310.85028)
		)
		(stroke
			(width 0)
			(type solid)
		)
		(fill yes)
		(layer "F.Cu")
		(net "GND")
	)
	(gr_poly
		(pts
			(xy 33.73628 -279.69464) (xy 33.73628 -270.54556) (xy 33.52292 -270.3322) (xy 28.5242 -270.3322)
			(xy 28.194 -270.6624) (xy 28.194 -271.526) (xy 28.194 -279.654) (xy 28.575 -280.035) (xy 33.39592 -280.035)
		)
		(stroke
			(width 0)
			(type solid)
		)
		(fill yes)
		(layer "F.Cu")
		(net "GND")
	)
	(gr_poly
		(pts
			(xy 33.7566 -94.7166) (xy 33.7566 -85.725) (xy 33.4772 -85.4456) (xy 28.4226 -85.4456) (xy 28.194 -85.6742)
			(xy 28.194 -86.925912) (xy 28.194 -94.5134) (xy 28.575 -94.8944) (xy 33.5788 -94.8944)
		)
		(stroke
			(width 0)
			(type solid)
		)
		(fill yes)
		(layer "F.Cu")
		(net "GND")
	)
	(gr_poly
		(pts
			(xy 3.564128 -310.724296) (xy 3.564128 -309.132478) (xy 3.76428 -308.932326) (xy 3.76428 -308.23662)
			(xy 3.74396 -308.2163) (xy 1.89738 -308.2163) (xy 1.78308 -308.3306) (xy 1.78308 -310.68264) (xy 1.87452 -310.77408)
			(xy 3.514344 -310.77408)
		)
		(stroke
			(width 0)
			(type solid)
		)
		(fill yes)
		(layer "F.Cu")
		(net "GND")
	)
	(gr_poly
		(pts
			(xy 8.55218 -310.6166) (xy 8.55218 -308.53126) (xy 8.2931 -308.27218) (xy 4.1275 -308.27218) (xy 4.10718 -308.2925)
			(xy 4.10718 -308.923182) (xy 4.305808 -309.12181) (xy 4.305808 -310.739536) (xy 4.327652 -310.76138)
			(xy 8.4074 -310.76138)
		)
		(stroke
			(width 0)
			(type solid)
		)
		(fill yes)
		(layer "F.Cu")
		(net "P12V_LED_FAN7")
	)
	(gr_poly
		(pts
			(xy 22.870922 -95.090488) (xy 22.870922 -86.962488) (xy 22.869144 -86.960456) (xy 22.869144 -85.556344)
			(xy 22.5806 -85.2678) (xy 18.796 -85.2678) (xy 16.891 -87.1728) (xy 16.891 -95.180912) (xy 17.181576 -95.471488)
			(xy 17.409922 -95.471488) (xy 22.489922 -95.471488)
		)
		(stroke
			(width 0)
			(type solid)
		)
		(fill yes)
		(layer "F.Cu")
		(net "GND")
	)
	(gr_poly
		(pts
			(xy 24.369522 -278.268176) (xy 24.369522 -270.140176) (xy 24.369522 -269.123922) (xy 24.369522 -268.209522)
			(xy 23.8506 -267.6906) (xy 20.828 -267.6906) (xy 18.3896 -270.129) (xy 18.3896 -278.3586) (xy 18.680176 -278.649176)
			(xy 18.908522 -278.649176) (xy 23.988522 -278.649176)
		)
		(stroke
			(width 0)
			(type solid)
		)
		(fill yes)
		(layer "F.Cu")
		(net "GND")
	)
	(gr_poly
		(pts
			(xy 6.81736 -270.8021)
			(arc
				(start 6.82244 -270.8021)
				(mid 6.858361 -270.787221)
				(end 6.87324 -270.7513)
			)
			(xy 6.87324 -269.669006) (xy 6.671564 -269.46733) (xy 3.247136 -269.46733) (xy 3.02895 -269.685516)
			(xy 3.02895 -270.66113) (xy 3.258312 -270.890492) (xy 6.728968 -270.890492)
		)
		(stroke
			(width 0)
			(type solid)
		)
		(fill yes)
		(layer "F.Cu")
		(net "GND")
	)
	(gr_poly
		(pts
			(xy 48.9204 -88.734138)
			(arc
				(start 48.9204 -84.806282)
				(mid 48.916499 -84.786759)
				(end 48.905414 -84.770214)
			)
			(arc
				(start 48.325786 -84.190586)
				(mid 48.309252 -84.179475)
				(end 48.289718 -84.1756)
			)
			(xy 45.25645 -84.1756) (xy 44.71924 -84.71281) (xy 44.71924 -88.711532) (xy 44.967144 -88.959436)
			(xy 48.695102 -88.959436)
		)
		(stroke
			(width 0)
			(type solid)
		)
		(fill yes)
		(layer "F.Cu")
		(net "GND")
	)
	(gr_poly
		(pts
			(xy 35.047428 -260.924548)
			(arc
				(start 35.047428 -257.196082)
				(mid 35.043527 -257.176559)
				(end 35.032442 -257.160014)
			)
			(xy 34.808414 -256.935986) (xy 34.801302 -256.92862) (xy 34.782506 -256.921)
			(arc
				(start 31.51251 -256.921)
				(mid 31.492987 -256.924901)
				(end 31.476442 -256.935986)
			)
			(xy 31.252414 -257.160014) (xy 31.245048 -257.167126) (xy 31.237428 -257.185922) (xy 31.237428 -260.913372)
			(xy 31.496508 -261.172452) (xy 34.799524 -261.172452)
		)
		(stroke
			(width 0)
			(type solid)
		)
		(fill yes)
		(layer "F.Cu")
		(net "GND")
	)
	(gr_poly
		(pts
			(xy 50.419 -221.05112) (xy 50.419 -220.5736) (xy 50.0634 -220.218) (xy 50.0634 -216.854786) (xy 49.997614 -216.789)
			(arc
				(start 48.844708 -216.789)
				(mid 48.808787 -216.803879)
				(end 48.793908 -216.8398)
			)
			(xy 48.793908 -219.176092) (xy 48.133 -219.837) (xy 48.133 -220.8784) (xy 48.1838 -220.9292) (xy 49.784 -220.9292)
			(xy 49.91608 -221.06128) (xy 50.40884 -221.06128)
		)
		(stroke
			(width 0)
			(type solid)
		)
		(fill yes)
		(layer "F.Cu")
		(net "P12V_LED_FAN1")
	)
	(gr_poly
		(pts
			(arc
				(start 5.693918 -127)
				(mid 5.713441 -126.996099)
				(end 5.729986 -126.985014)
			)
			(arc
				(start 5.827014 -126.887986)
				(mid 5.838125 -126.871452)
				(end 5.842 -126.851918)
			)
			(arc
				(start 5.842 -124.481082)
				(mid 5.838099 -124.461559)
				(end 5.827014 -124.445014)
			)
			(arc
				(start 5.729986 -124.347986)
				(mid 5.713452 -124.336875)
				(end 5.693918 -124.333)
			)
			(xy 3.72618 -124.333) (xy 3.60172 -124.45746) (xy 3.60172 -126.55804) (xy 4.04368 -127)
		)
		(stroke
			(width 0)
			(type solid)
		)
		(fill yes)
		(layer "F.Cu")
		(net "GND")
	)
	(gr_poly
		(pts
			(xy 8.1788 -76.388976)
			(arc
				(start 8.1788 -72.639682)
				(mid 8.174899 -72.620159)
				(end 8.163814 -72.603614)
			)
			(arc
				(start 7.896098 -72.335898)
				(mid 7.879564 -72.324787)
				(end 7.86003 -72.320912)
			)
			(arc
				(start 3.751072 -72.320912)
				(mid 3.731549 -72.324813)
				(end 3.715004 -72.335898)
			)
			(arc
				(start 3.490976 -72.559926)
				(mid 3.479865 -72.57646)
				(end 3.47599 -72.595994)
			)
			(xy 3.47599 -76.400152) (xy 3.6449 -76.569062) (xy 7.998714 -76.569062)
		)
		(stroke
			(width 0)
			(type solid)
		)
		(fill yes)
		(layer "F.Cu")
		(net "GND")
	)
	(gr_poly
		(pts
			(xy 36.195 -76.355448)
			(arc
				(start 36.195 -72.588882)
				(mid 36.191099 -72.569359)
				(end 36.180014 -72.552814)
			)
			(arc
				(start 35.963098 -72.335898)
				(mid 35.946564 -72.324787)
				(end 35.92703 -72.320912)
			)
			(arc
				(start 30.39237 -72.320912)
				(mid 30.372847 -72.324813)
				(end 30.356302 -72.335898)
			)
			(arc
				(start 30.012386 -72.679814)
				(mid 30.001275 -72.696348)
				(end 29.9974 -72.715882)
			)
			(xy 29.9974 -76.29906) (xy 30.25648 -76.55814) (xy 35.992308 -76.55814)
		)
		(stroke
			(width 0)
			(type solid)
		)
		(fill yes)
		(layer "F.Cu")
		(net "GND")
	)
	(gr_poly
		(pts
			(arc
				(start 50.016918 -126.746)
				(mid 50.036441 -126.742099)
				(end 50.052986 -126.731014)
			)
			(arc
				(start 50.150014 -126.633986)
				(mid 50.161125 -126.617452)
				(end 50.165 -126.597918)
			)
			(arc
				(start 50.165 -124.227082)
				(mid 50.161099 -124.207559)
				(end 50.150014 -124.191014)
			)
			(arc
				(start 50.052986 -124.093986)
				(mid 50.036452 -124.082875)
				(end 50.016918 -124.079)
			)
			(xy 48.16094 -124.079) (xy 48.04156 -124.19838) (xy 48.04156 -126.55042) (xy 48.23714 -126.746)
		)
		(stroke
			(width 0)
			(type solid)
		)
		(fill yes)
		(layer "F.Cu")
		(net "GND")
	)
	(gr_poly
		(pts
			(xy 4.08432 -53.52796) (xy 4.08432 -52.811934) (xy 6.280404 -50.61585) (xy 6.280404 -44.172886) (xy 8.1026 -42.35069)
			(arc
				(start 8.1026 -36.320476)
				(mid 8.098699 -36.300953)
				(end 8.087614 -36.284408)
			)
			(arc
				(start 7.99592 -36.192714)
				(mid 7.979386 -36.181603)
				(end 7.959852 -36.177728)
			)
			(xy 5.362448 -36.177728) (xy 5.15366 -35.96894) (xy 1.99898 -35.96894) (xy 1.98374 -35.98418) (xy 1.98374 -36.5379)
			(xy 2.769108 -37.323268) (xy 2.769108 -53.607208) (xy 2.93878 -53.77688) (xy 3.8354 -53.77688)
		)
		(stroke
			(width 0)
			(type solid)
		)
		(fill yes)
		(layer "F.Cu")
		(net "GND")
	)
	(gr_poly
		(pts
			(xy 50.4444 -239.7506) (xy 50.4444 -221.43466) (xy 50.41646 -221.40672) (xy 49.91608 -221.40672)
			(xy 49.784 -221.5388) (xy 42.5958 -221.5388) (xy 42.291 -221.8436)
			(arc
				(start 42.291 -228.578918)
				(mid 42.294901 -228.598441)
				(end 42.305986 -228.614986)
			)
			(arc
				(start 45.578014 -231.887014)
				(mid 45.589125 -231.903548)
				(end 45.593 -231.923082)
			)
			(arc
				(start 45.593 -239.754918)
				(mid 45.596901 -239.774441)
				(end 45.607986 -239.790986)
			)
			(arc
				(start 45.674026 -239.857026)
				(mid 45.69056 -239.868137)
				(end 45.710094 -239.872012)
			)
			(xy 50.322988 -239.872012)
		)
		(stroke
			(width 0)
			(type solid)
		)
		(fill yes)
		(layer "F.Cu")
		(net "GND")
	)
	(gr_poly
		(pts
			(xy 32.258 -12.827) (xy 32.258 -8.636) (xy 31.857188 -8.235188) (xy 31.857188 -8.158988) (xy 31.857188 -1.935988)
			(xy 31.772352 -1.851152) (xy 31.6992 -1.851152)
			(arc
				(start 28.37053 -1.851152)
				(mid 28.351007 -1.855053)
				(end 28.334462 -1.866138)
			)
			(arc
				(start 28.081986 -2.118614)
				(mid 28.070875 -2.135148)
				(end 28.067 -2.154682)
			)
			(xy 28.067 -6.616192) (xy 28.067 -7.912862) (xy 28.231338 -8.0772) (xy 29.464 -8.0772) (xy 30.48 -9.0932)
			(xy 30.48 -12.75334) (xy 30.64256 -12.9159) (xy 31.5849 -12.9159) (xy 31.7373 -12.9159) (xy 32.1691 -12.9159)
		)
		(stroke
			(width 0)
			(type solid)
		)
		(fill yes)
		(layer "F.Cu")
		(net "GND")
	)
	(gr_poly
		(pts
			(xy 49.761394 -55.290974) (xy 49.761394 -36.520374) (xy 49.71542 -36.4744) (xy 43.65625 -36.4744)
			(arc
				(start 43.296586 -36.834064)
				(mid 43.285475 -36.850598)
				(end 43.2816 -36.870132)
			)
			(arc
				(start 43.2816 -41.769792)
				(mid 43.285501 -41.789315)
				(end 43.296586 -41.80586)
			)
			(arc
				(start 45.019722 -43.528996)
				(mid 45.030833 -43.54553)
				(end 45.034708 -43.565064)
			)
			(xy 45.034708 -54.699662)
			(arc
				(start 45.035978 -54.7116)
				(mid 45.085251 -54.981782)
				(end 45.101764 -55.255922)
			)
			(xy 45.099986 -55.342536) (xy 45.251116 -55.493666) (xy 49.558702 -55.493666)
		)
		(stroke
			(width 0)
			(type solid)
		)
		(fill yes)
		(layer "F.Cu")
		(net "GND")
	)
	(gr_poly
		(pts
			(xy 4.0513 -237.53572) (xy 4.0513 -230.147622) (xy 4.05892 -230.12908) (xy 4.063492 -230.124508)
			(xy 4.063492 -230.122222)
			(arc
				(start 9.205214 -224.9805)
				(mid 9.216325 -224.963966)
				(end 9.2202 -224.944432)
			)
			(arc
				(start 9.2202 -220.523308)
				(mid 9.205321 -220.487387)
				(end 9.1694 -220.472508)
			)
			(xy 7.281926 -220.472508)
			(arc
				(start 7.273036 -220.476318)
				(mid 7.263446 -220.479191)
				(end 7.253478 -220.480128)
			)
			(xy 6.304788 -220.480128) (xy 5.53466 -219.71) (xy 2.44348 -219.71) (xy 2.032 -220.12148) (xy 2.032 -238.00308)
			(xy 2.35458 -238.32566) (xy 3.26136 -238.32566)
		)
		(stroke
			(width 0)
			(type solid)
		)
		(fill yes)
		(layer "F.Cu")
		(net "GND")
	)
	(gr_poly
		(pts
			(arc
				(start 48.960786 -270.848074)
				(mid 48.988968 -270.849618)
				(end 49.013618 -270.835882)
			)
			(arc
				(start 49.121314 -270.728186)
				(mid 49.132425 -270.711652)
				(end 49.1363 -270.692118)
			)
			(arc
				(start 49.1363 -268.740382)
				(mid 49.132399 -268.720859)
				(end 49.121314 -268.704314)
			)
			(arc
				(start 48.833786 -268.416786)
				(mid 48.817252 -268.405675)
				(end 48.797718 -268.4018)
			)
			(xy 46.488858 -268.4018) (xy 45.81017 -269.080488) (xy 45.81017 -270.569182) (xy 45.97908 -270.738092)
			(arc
				(start 48.315372 -270.738092)
				(mid 48.642712 -270.765892)
				(end 48.960786 -270.848074)
			)
		)
		(stroke
			(width 0)
			(type solid)
		)
		(fill yes)
		(layer "F.Cu")
		(net "GND")
	)
	(gr_poly
		(pts
			(xy 17.8054 -247.755918)
			(arc
				(start 17.8054 -242.540282)
				(mid 17.801499 -242.520759)
				(end 17.790414 -242.504214)
			)
			(arc
				(start 17.617186 -242.330986)
				(mid 17.600652 -242.319875)
				(end 17.581118 -242.316)
			)
			(arc
				(start 7.793482 -242.316)
				(mid 7.773959 -242.319901)
				(end 7.757414 -242.330986)
			)
			(arc
				(start 6.509258 -243.579142)
				(mid 6.498147 -243.595676)
				(end 6.494272 -243.61521)
			)
			(arc
				(start 6.494272 -243.970048)
				(mid 6.506429 -244.001293)
				(end 6.53542 -244.018054)
			)
			(xy 6.53542 -244.41404) (xy 6.70814 -244.58676) (xy 10.58672 -244.58676) (xy 12.11834 -246.11838)
			(xy 12.11834 -247.74144) (xy 12.301728 -247.924828) (xy 17.63649 -247.924828)
		)
		(stroke
			(width 0)
			(type solid)
		)
		(fill yes)
		(layer "F.Cu")
		(net "P52V_HSC")
	)
	(gr_poly
		(pts
			(xy 16.861536 -253.462536)
			(arc
				(start 18.169382 -253.462536)
				(mid 18.188905 -253.458635)
				(end 18.20545 -253.44755)
			)
			(arc
				(start 18.323814 -253.329186)
				(mid 18.334925 -253.312652)
				(end 18.3388 -253.293118)
			)
			(arc
				(start 18.3388 -250.139708)
				(mid 18.323921 -250.103787)
				(end 18.288 -250.088908)
			)
			(arc
				(start 12.0396 -250.088908)
				(mid 12.003679 -250.103787)
				(end 11.9888 -250.139708)
			)
			(arc
				(start 11.9888 -253.343918)
				(mid 11.992701 -253.363441)
				(end 12.003786 -253.379986)
			)
			(arc
				(start 12.075414 -253.451614)
				(mid 12.091948 -253.462725)
				(end 12.111482 -253.4666)
			)
			(xy 16.857218 -253.4666)
		)
		(stroke
			(width 0)
			(type solid)
		)
		(fill yes)
		(layer "F.Cu")
		(net "GND")
	)
	(gr_poly
		(pts
			(arc
				(start 10.951718 -82.3976)
				(mid 10.971241 -82.393699)
				(end 10.987786 -82.382614)
			)
			(xy 13.624814 -79.745586) (xy 13.625068 -79.745332) (xy 13.6398 -79.7306) (xy 13.6398 -78.903576)
			(xy 13.625068 -78.888844) (xy 13.624814 -78.88859) (xy 13.495274 -78.75905) (xy 13.49502 -78.758796)
			(xy 13.480288 -78.744064) (xy 4.101846 -78.744064) (xy 3.901186 -78.944724) (xy 3.900932 -78.944978)
			(xy 3.8862 -78.95971)
			(arc
				(start 3.8862 -82.155538)
				(mid 3.890101 -82.175061)
				(end 3.901186 -82.191606)
			)
			(arc
				(start 4.064 -82.35442)
				(mid 4.080563 -82.365394)
				(end 4.100068 -82.369152)
			)
			(arc
				(start 7.532116 -82.369152)
				(mid 7.551639 -82.373053)
				(end 7.568184 -82.384138)
			)
			(xy 7.574026 -82.38998) (xy 7.592568 -82.3976)
		)
		(stroke
			(width 0)
			(type solid)
		)
		(fill yes)
		(layer "F.Cu")
		(net "P52V_HSC")
	)
	(gr_poly
		(pts
			(arc
				(start 48.340518 -68.8086)
				(mid 48.360041 -68.804699)
				(end 48.376586 -68.793614)
			)
			(arc
				(start 48.600614 -68.569586)
				(mid 48.611725 -68.553052)
				(end 48.6156 -68.533518)
			)
			(arc
				(start 48.6156 -64.308482)
				(mid 48.611699 -64.288959)
				(end 48.600614 -64.272414)
			)
			(arc
				(start 48.469042 -64.140842)
				(mid 48.452625 -64.12978)
				(end 48.433228 -64.125856)
			)
			(arc
				(start 43.616372 -64.125856)
				(mid 43.596985 -64.129806)
				(end 43.580558 -64.140842)
			)
			(arc
				(start 43.448986 -64.272414)
				(mid 43.437875 -64.288948)
				(end 43.434 -64.308482)
			)
			(arc
				(start 43.434 -68.635118)
				(mid 43.437901 -68.654641)
				(end 43.448986 -68.671186)
			)
			(arc
				(start 43.571414 -68.793614)
				(mid 43.587948 -68.804725)
				(end 43.607482 -68.8086)
			)
		)
		(stroke
			(width 0)
			(type solid)
		)
		(fill yes)
		(layer "F.Cu")
		(net "GND")
	)
	(gr_poly
		(pts
			(arc
				(start 48.924718 -253.7968)
				(mid 48.944241 -253.792899)
				(end 48.960786 -253.781814)
			)
			(arc
				(start 49.261014 -253.481586)
				(mid 49.272125 -253.465052)
				(end 49.276 -253.445518)
			)
			(arc
				(start 49.276 -249.322082)
				(mid 49.272099 -249.302559)
				(end 49.261014 -249.286014)
			)
			(arc
				(start 48.782986 -248.807986)
				(mid 48.766452 -248.796875)
				(end 48.746918 -248.793)
			)
			(arc
				(start 44.648882 -248.793)
				(mid 44.629359 -248.796901)
				(end 44.612814 -248.807986)
			)
			(arc
				(start 44.388786 -249.032014)
				(mid 44.377675 -249.048548)
				(end 44.3738 -249.068082)
			)
			(arc
				(start 44.3738 -251.997718)
				(mid 44.377701 -252.017241)
				(end 44.388786 -252.033786)
			)
			(arc
				(start 46.136814 -253.781814)
				(mid 46.153348 -253.792925)
				(end 46.172882 -253.7968)
			)
		)
		(stroke
			(width 0)
			(type solid)
		)
		(fill yes)
		(layer "F.Cu")
		(net "GND")
	)
	(gr_poly
		(pts
			(arc
				(start 16.277336 -69.596)
				(mid 16.296859 -69.592099)
				(end 16.313404 -69.581014)
			)
			(xy 16.679418 -69.215)
			(arc
				(start 16.70685 -69.187822)
				(mid 16.717961 -69.171288)
				(end 16.721836 -69.151754)
			)
			(arc
				(start 16.721836 -65.045082)
				(mid 16.717935 -65.025559)
				(end 16.70685 -65.009014)
			)
			(arc
				(start 16.457422 -64.759586)
				(mid 16.440888 -64.748475)
				(end 16.421354 -64.7446)
			)
			(arc
				(start 12.543282 -64.7446)
				(mid 12.523759 -64.748501)
				(end 12.507214 -64.759586)
			)
			(arc
				(start 12.308586 -64.958214)
				(mid 12.297475 -64.974748)
				(end 12.2936 -64.994282)
			)
			(arc
				(start 12.2936 -69.473318)
				(mid 12.297501 -69.492841)
				(end 12.308586 -69.509386)
			)
			(arc
				(start 12.380214 -69.581014)
				(mid 12.396748 -69.592125)
				(end 12.416282 -69.596)
			)
		)
		(stroke
			(width 0)
			(type solid)
		)
		(fill yes)
		(layer "F.Cu")
		(net "GND")
	)
	(gr_poly
		(pts
			(arc
				(start 36.255198 -83.53552)
				(mid 36.274721 -83.531619)
				(end 36.291266 -83.520534)
			)
			(arc
				(start 39.396924 -80.414876)
				(mid 39.413458 -80.403765)
				(end 39.432992 -80.39989)
			)
			(arc
				(start 40.872918 -80.39989)
				(mid 40.892441 -80.395989)
				(end 40.908986 -80.384904)
			)
			(arc
				(start 41.387014 -79.906876)
				(mid 41.398125 -79.890342)
				(end 41.402 -79.870808)
			)
			(arc
				(start 41.402 -78.843378)
				(mid 41.398099 -78.823855)
				(end 41.387014 -78.80731)
			)
			(xy 41.317926 -78.738222) (xy 41.300146 -78.730602) (xy 41.29024 -78.730348) (xy 41.237916 -78.728316)
			(xy 41.223184 -78.713584) (xy 30.303216 -78.713584) (xy 30.1752 -78.8416)
			(arc
				(start 30.1752 -83.326478)
				(mid 30.179101 -83.346001)
				(end 30.190186 -83.362546)
			)
			(arc
				(start 30.348174 -83.520534)
				(mid 30.364708 -83.531645)
				(end 30.384242 -83.53552)
			)
		)
		(stroke
			(width 0)
			(type solid)
		)
		(fill yes)
		(layer "F.Cu")
		(net "P52V_HSC")
	)
	(gr_poly
		(pts
			(arc
				(start 36.453318 -244.6528)
				(mid 36.472841 -244.648899)
				(end 36.489386 -244.637814)
			)
			(arc
				(start 40.396414 -240.730786)
				(mid 40.412948 -240.719675)
				(end 40.432482 -240.7158)
			)
			(arc
				(start 42.981118 -240.7158)
				(mid 43.000641 -240.711899)
				(end 43.017186 -240.700814)
			)
			(arc
				(start 43.419014 -240.298986)
				(mid 43.430125 -240.282452)
				(end 43.434 -240.262918)
			)
			(arc
				(start 43.434 -232.939082)
				(mid 43.430099 -232.919559)
				(end 43.419014 -232.903014)
			)
			(arc
				(start 39.956486 -229.440486)
				(mid 39.945375 -229.423952)
				(end 39.9415 -229.404418)
			)
			(arc
				(start 39.9415 -221.445582)
				(mid 39.937599 -221.426059)
				(end 39.926514 -221.409514)
			)
			(arc
				(start 39.511986 -220.994986)
				(mid 39.495452 -220.983875)
				(end 39.475918 -220.98)
			)
			(arc
				(start 34.061908 -220.98)
				(mid 34.025987 -220.994879)
				(end 34.011108 -221.0308)
			)
			(arc
				(start 34.011108 -244.602)
				(mid 34.025987 -244.637921)
				(end 34.061908 -244.6528)
			)
		)
		(stroke
			(width 0)
			(type solid)
		)
		(fill yes)
		(layer "F.Cu")
		(net "P52V_FAN_1")
	)
	(gr_poly
		(pts
			(arc
				(start 48.238918 -282.067)
				(mid 48.258441 -282.063099)
				(end 48.274986 -282.052014)
			)
			(arc
				(start 48.626014 -281.700986)
				(mid 48.637125 -281.684452)
				(end 48.641 -281.664918)
			)
			(arc
				(start 48.641 -272.969482)
				(mid 48.637099 -272.949959)
				(end 48.626014 -272.933414)
			)
			(arc
				(start 48.351186 -272.658586)
				(mid 48.334652 -272.647475)
				(end 48.315118 -272.6436)
			)
			(xy 44.217082 -272.6436) (xy 43.791632 -272.6436) (xy 43.511978 -272.363946) (xy 43.511978 -268.409928)
			(xy 45.4152 -266.506706)
			(arc
				(start 45.4152 -264.003282)
				(mid 45.411299 -263.983759)
				(end 45.400214 -263.967214)
			)
			(arc
				(start 45.176186 -263.743186)
				(mid 45.159652 -263.732075)
				(end 45.140118 -263.7282)
			)
			(xy 43.27398 -263.7282) (xy 42.6339 -264.36828) (xy 42.6339 -265.130534) (xy 41.226486 -266.537948)
			(arc
				(start 39.43604 -266.537948)
				(mid 39.416517 -266.541849)
				(end 39.399972 -266.552934)
			)
			(xy 38.848284 -267.104622) (xy 38.84803 -267.104876) (xy 35.744912 -270.207994) (xy 35.687 -270.207994)
			(arc
				(start 35.687 -281.664918)
				(mid 35.690901 -281.684441)
				(end 35.701986 -281.700986)
			)
			(arc
				(start 36.053014 -282.052014)
				(mid 36.069548 -282.063125)
				(end 36.089082 -282.067)
			)
		)
		(stroke
			(width 0)
			(type solid)
		)
		(fill yes)
		(layer "F.Cu")
		(net "P52V_FAN_0")
	)
	(gr_poly
		(pts
			(arc
				(start 22.330918 -12.319)
				(mid 22.350441 -12.315099)
				(end 22.366986 -12.304014)
			)
			(arc
				(start 22.718014 -11.952986)
				(mid 22.729125 -11.936452)
				(end 22.733 -11.916918)
			)
			(arc
				(start 22.733 -1.899412)
				(mid 22.720201 -1.865796)
				(end 22.688296 -1.84912)
			)
			(arc
				(start 21.98878 -1.84912)
				(mid 21.959108 -1.863644)
				(end 21.944584 -1.893316)
			)
			(xy 21.944584 -6.90372) (xy 21.48586 -6.90372)
			(arc
				(start 21.48586 -1.895856)
				(mid 21.471864 -1.864544)
				(end 21.441156 -1.84912)
			)
			(arc
				(start 20.745704 -1.84912)
				(mid 20.713736 -1.86574)
				(end 20.701 -1.899412)
			)
			(arc
				(start 20.701 -6.455918)
				(mid 20.697099 -6.475441)
				(end 20.686014 -6.491986)
			)
			(xy 20.68195 -6.49605) (xy 20.674584 -6.513576) (xy 20.674584 -6.90372)
			(arc
				(start 20.28952 -6.90372)
				(mid 20.273428 -6.908443)
				(end 20.259802 -6.918198)
			)
			(arc
				(start 19.674586 -7.503414)
				(mid 19.663475 -7.519948)
				(end 19.6596 -7.539482)
			)
			(arc
				(start 19.6596 -12.170918)
				(mid 19.663501 -12.190441)
				(end 19.674586 -12.206986)
			)
			(arc
				(start 19.771614 -12.304014)
				(mid 19.788148 -12.315125)
				(end 19.807682 -12.319)
			)
		)
		(stroke
			(width 0)
			(type solid)
		)
		(fill yes)
		(layer "F.Cu")
		(net "GND")
	)
	(gr_poly
		(pts
			(arc
				(start 47.706026 -246.887492)
				(mid 47.725549 -246.883591)
				(end 47.742094 -246.872506)
			)
			(arc
				(start 47.965614 -246.648986)
				(mid 47.976725 -246.632452)
				(end 47.9806 -246.612918)
			)
			(xy 47.9806 -242.04676) (xy 47.71136 -241.77752)
			(arc
				(start 40.716962 -241.77752)
				(mid 40.697439 -241.781421)
				(end 40.680894 -241.792506)
			)
			(xy 38.47084 -244.00256) (xy 38.45306 -244.00256) (xy 38.08476 -244.37086) (xy 38.08476 -244.38864)
			(arc
				(start 38.064186 -244.409214)
				(mid 38.053075 -244.425748)
				(end 38.0492 -244.445282)
			)
			(arc
				(start 38.0492 -244.513608)
				(mid 38.053171 -244.533297)
				(end 38.06444 -244.54993)
			)
			(xy 38.08476 -244.569742) (xy 38.08476 -245.24462) (xy 38.2397 -245.39956)
			(arc
				(start 41.819068 -245.39956)
				(mid 41.996812 -245.57667)
				(end 42.152824 -245.773194)
			)
			(arc
				(start 42.152824 -245.773194)
				(mid 42.17089 -245.789061)
				(end 42.194226 -245.794784)
			)
			(arc
				(start 43.358816 -245.794784)
				(mid 43.378339 -245.798685)
				(end 43.394884 -245.80977)
			)
			(xy 43.843194 -246.257826)
			(arc
				(start 43.847004 -246.260366)
				(mid 44.137622 -246.50391)
				(end 44.381166 -246.794528)
			)
			(xy 44.383706 -246.798338)
			(arc
				(start 44.457874 -246.872506)
				(mid 44.474408 -246.883617)
				(end 44.493942 -246.887492)
			)
		)
		(stroke
			(width 0)
			(type solid)
		)
		(fill yes)
		(layer "F.Cu")
		(net "P52V_HSC")
	)
	(gr_poly
		(pts
			(arc
				(start 14.844014 -218.835986)
				(mid 14.855125 -218.819452)
				(end 14.859 -218.799918)
			)
			(xy 14.859 -218.108276) (xy 14.857222 -218.094306) (xy 14.851634 -218.075002)
			(arc
				(start 14.848332 -218.069414)
				(mid 14.742304 -217.819782)
				(end 14.706092 -217.551)
			)
			(arc
				(start 14.706092 -216.535)
				(mid 14.736537 -216.288338)
				(end 14.82598 -216.056464)
			)
			(xy 14.828774 -216.05113)
			(arc
				(start 14.831822 -216.039446)
				(mid 14.833369 -216.027)
				(end 14.831822 -216.014554)
			)
			(xy 14.828774 -216.00287)
			(arc
				(start 14.82598 -215.997536)
				(mid 14.736595 -215.765648)
				(end 14.706092 -215.519)
			)
			(arc
				(start 14.706092 -215.3158)
				(mid 14.691213 -215.279879)
				(end 14.655292 -215.265)
			)
			(arc
				(start 2.0828 -215.265)
				(mid 2.046879 -215.279879)
				(end 2.032 -215.3158)
			)
			(xy 2.032 -216.006426) (xy 2.032254 -216.007696) (xy 2.033778 -216.070942) (xy 2.033778 -216.07145)
			(xy 2.032254 -216.13495) (xy 2.032 -216.13622) (xy 2.032 -219.32138) (xy 2.12344 -219.41282) (xy 14.26718 -219.41282)
		)
		(stroke
			(width 0)
			(type solid)
		)
		(fill yes)
		(layer "F.Cu")
		(net "P12V_LED_FAN6")
	)
	(gr_poly
		(pts
			(xy 14.985492 -94.107)
			(arc
				(start 14.985492 -86.404704)
				(mid 14.989393 -86.385181)
				(end 15.000478 -86.368636)
			)
			(arc
				(start 17.282414 -84.0867)
				(mid 17.293525 -84.070166)
				(end 17.2974 -84.050632)
			)
			(arc
				(start 17.2974 -79.802482)
				(mid 17.293499 -79.782959)
				(end 17.282414 -79.766414)
			)
			(arc
				(start 17.134586 -79.618586)
				(mid 17.118052 -79.607475)
				(end 17.098518 -79.6036)
			)
			(arc
				(start 14.981682 -79.6036)
				(mid 14.962159 -79.607501)
				(end 14.945614 -79.618586)
			)
			(arc
				(start 14.899386 -79.664814)
				(mid 14.888275 -79.681348)
				(end 14.8844 -79.700882)
			)
			(arc
				(start 14.8844 -80.242918)
				(mid 14.880499 -80.262441)
				(end 14.869414 -80.278986)
			)
			(arc
				(start 8.97382 -86.17458)
				(mid 8.962894 -86.191026)
				(end 8.959088 -86.210394)
			)
			(arc
				(start 8.959088 -86.251796)
				(mid 8.955187 -86.271319)
				(end 8.944102 -86.287864)
			)
			(arc
				(start 7.636764 -87.595202)
				(mid 7.62023 -87.606313)
				(end 7.600696 -87.610188)
			)
			(arc
				(start 4.333494 -87.610188)
				(mid 4.314137 -87.614021)
				(end 4.29768 -87.62492)
			)
			(arc
				(start 3.977386 -87.945214)
				(mid 3.966275 -87.961748)
				(end 3.9624 -87.981282)
			)
			(xy 3.9624 -92.329) (xy 4.4704 -92.837) (xy 8.763 -92.837) (xy 9.271 -92.837) (xy 10.033 -92.837)
			(xy 10.16 -92.837) (xy 11.684 -94.361) (xy 12.954 -94.361) (xy 14.731492 -94.361)
		)
		(stroke
			(width 0)
			(type solid)
		)
		(fill yes)
		(layer "F.Cu")
		(net "P52V_FAN_5")
	)
	(gr_poly
		(pts
			(arc
				(start 5.058918 -244.0178)
				(mid 5.078441 -244.013899)
				(end 5.094986 -244.002814)
			)
			(arc
				(start 5.293614 -243.804186)
				(mid 5.304725 -243.787652)
				(end 5.3086 -243.768118)
			)
			(arc
				(start 5.3086 -243.099082)
				(mid 5.312501 -243.079559)
				(end 5.323586 -243.063014)
			)
			(arc
				(start 7.122414 -241.264186)
				(mid 7.138948 -241.253075)
				(end 7.158482 -241.2492)
			)
			(arc
				(start 17.885918 -241.2492)
				(mid 17.905441 -241.245299)
				(end 17.921986 -241.234214)
			)
			(arc
				(start 18.527014 -240.629186)
				(mid 18.538125 -240.612652)
				(end 18.542 -240.593118)
			)
			(arc
				(start 18.542 -221.382082)
				(mid 18.538099 -221.362559)
				(end 18.527014 -221.346014)
			)
			(arc
				(start 18.175986 -220.994986)
				(mid 18.159452 -220.983875)
				(end 18.139918 -220.98)
			)
			(arc
				(start 15.415768 -220.98)
				(mid 15.396245 -220.983901)
				(end 15.3797 -220.994986)
			)
			(arc
				(start 15.028164 -221.346522)
				(mid 15.01163 -221.357633)
				(end 14.992096 -221.361508)
			)
			(arc
				(start 12.065 -221.361508)
				(mid 12.029079 -221.376387)
				(end 12.0142 -221.412308)
			)
			(arc
				(start 12.0142 -224.845118)
				(mid 12.010299 -224.864641)
				(end 11.999214 -224.881186)
			)
			(arc
				(start 5.983986 -230.896414)
				(mid 5.972875 -230.912948)
				(end 5.969 -230.932482)
			)
			(xy 5.969 -237.316518) (xy 3.2512 -240.034318)
			(arc
				(start 3.2512 -243.717318)
				(mid 3.255101 -243.736841)
				(end 3.266186 -243.753386)
			)
			(arc
				(start 3.515614 -244.002814)
				(mid 3.532148 -244.013925)
				(end 3.551682 -244.0178)
			)
		)
		(stroke
			(width 0)
			(type solid)
		)
		(fill yes)
		(layer "F.Cu")
		(net "P52V_FAN_6")
	)
	(gr_poly
		(pts
			(arc
				(start 47.676562 -94.8944)
				(mid 47.696085 -94.890499)
				(end 47.71263 -94.879414)
			)
			(arc
				(start 48.089058 -94.502986)
				(mid 48.100169 -94.486452)
				(end 48.104044 -94.466918)
			)
			(xy 48.104044 -91.163648) (xy 48.060356 -91.11996) (xy 44.064174 -91.11996)
			(arc
				(start 42.828718 -89.884504)
				(mid 42.817607 -89.86797)
				(end 42.813732 -89.848436)
			)
			(xy 42.813732 -84.061808) (xy 42.813732 -83.80476) (xy 44.8056 -81.812892)
			(arc
				(start 44.8056 -79.700882)
				(mid 44.801699 -79.681359)
				(end 44.790614 -79.664814)
			)
			(arc
				(start 44.566586 -79.440786)
				(mid 44.550052 -79.429675)
				(end 44.530518 -79.4258)
			)
			(arc
				(start 42.667682 -79.4258)
				(mid 42.648159 -79.429701)
				(end 42.631614 -79.440786)
			)
			(arc
				(start 42.509186 -79.563214)
				(mid 42.498075 -79.579748)
				(end 42.4942 -79.599282)
			)
			(arc
				(start 42.4942 -80.192118)
				(mid 42.490299 -80.211641)
				(end 42.479214 -80.228186)
			)
			(arc
				(start 41.442386 -81.265014)
				(mid 41.425852 -81.276125)
				(end 41.406318 -81.28)
			)
			(arc
				(start 40.280082 -81.28)
				(mid 40.260559 -81.283901)
				(end 40.244014 -81.294986)
			)
			(arc
				(start 35.701986 -85.837014)
				(mid 35.690875 -85.853548)
				(end 35.687 -85.873082)
			)
			(arc
				(start 35.687 -94.339918)
				(mid 35.690901 -94.359441)
				(end 35.701986 -94.375986)
			)
			(arc
				(start 36.07816 -94.75216)
				(mid 36.094606 -94.763086)
				(end 36.113974 -94.766892)
			)
			(arc
				(start 43.9928 -94.766892)
				(mid 44.357185 -94.79823)
				(end 44.710858 -94.891352)
			)
			(arc
				(start 44.710858 -94.891352)
				(mid 44.719237 -94.893595)
				(end 44.727876 -94.8944)
			)
		)
		(stroke
			(width 0)
			(type solid)
		)
		(fill yes)
		(layer "F.Cu")
		(net "P52V_FAN_2")
	)
	(gr_poly
		(pts
			(arc
				(start 5.109718 -59.2074)
				(mid 5.129241 -59.203499)
				(end 5.145786 -59.192414)
			)
			(arc
				(start 7.439914 -56.898286)
				(mid 7.456448 -56.887175)
				(end 7.475982 -56.8833)
			)
			(arc
				(start 17.771618 -56.8833)
				(mid 17.791141 -56.879399)
				(end 17.807686 -56.868314)
			)
			(xy 18.58391 -56.09209) (xy 18.588228 -56.0578)
			(arc
				(start 18.579592 -56.042814)
				(mid 18.361867 -55.523642)
				(end 18.287492 -54.9656)
			)
			(arc
				(start 18.287492 -37.6428)
				(mid 18.284698 -37.626437)
				(end 18.276824 -37.611812)
			)
			(arc
				(start 18.276824 -37.611812)
				(mid 18.191531 -37.491483)
				(end 18.115788 -37.364924)
			)
			(arc
				(start 18.115788 -37.364924)
				(mid 18.097166 -37.345681)
				(end 18.071338 -37.338508)
			)
			(arc
				(start 17.5514 -37.338508)
				(mid 17.049534 -37.271082)
				(end 16.583152 -37.07384)
			)
			(arc
				(start 16.583152 -37.07384)
				(mid 16.570676 -37.068544)
				(end 16.557244 -37.066728)
			)
			(arc
				(start 10.058908 -37.066728)
				(mid 10.022987 -37.081607)
				(end 10.008108 -37.117528)
			)
			(xy 10.008108 -43.262296) (xy 10.008108 -44.045632) (xy 9.188196 -44.865544) (xy 8.4963 -45.55744)
			(xy 8.4963 -51.09464) (xy 4.40944 -55.1815) (xy 3.658108 -55.932832) (xy 3.41884 -56.1721) (xy 3.41884 -57.81802)
			(xy 3.41884 -58.98642) (xy 3.63728 -59.20486)
			(arc
				(start 3.69316 -59.20486)
				(mid 3.700935 -59.206734)
				(end 3.708908 -59.2074)
			)
		)
		(stroke
			(width 0)
			(type solid)
		)
		(fill yes)
		(layer "F.Cu")
		(net "P52V_FAN_4")
	)
	(gr_poly
		(pts
			(xy 8.266938 -267.350748) (xy 8.267192 -267.350494)
			(arc
				(start 10.602976 -265.01471)
				(mid 10.619422 -265.003784)
				(end 10.63879 -264.999978)
			)
			(xy 13.1826 -264.999978) (xy 13.749528 -264.43305) (xy 13.749528 -263.53135) (xy 13.635736 -263.417558)
			(xy 7.093712 -263.417558)
			(arc
				(start 7.08787 -263.418828)
				(mid 6.845624 -263.460682)
				(end 6.60019 -263.474708)
			)
			(arc
				(start 6.599174 -263.474708)
				(mid 6.412803 -263.466607)
				(end 6.227826 -263.44245)
			)
			(arc
				(start 6.227826 -263.44245)
				(mid 6.21919 -263.44171)
				(end 6.210554 -263.44245)
			)
			(arc
				(start 6.210554 -263.44245)
				(mid 6.025324 -263.466627)
				(end 5.838698 -263.474708)
			)
			(arc
				(start 5.837682 -263.474708)
				(mid 5.651056 -263.466629)
				(end 5.465826 -263.44245)
			)
			(arc
				(start 5.465826 -263.44245)
				(mid 5.45719 -263.44171)
				(end 5.448554 -263.44245)
			)
			(arc
				(start 5.448554 -263.44245)
				(mid 5.263324 -263.466627)
				(end 5.076698 -263.474708)
			)
			(arc
				(start 5.075682 -263.474708)
				(mid 4.889056 -263.466629)
				(end 4.703826 -263.44245)
			)
			(arc
				(start 4.703826 -263.44245)
				(mid 4.69519 -263.44171)
				(end 4.686554 -263.44245)
			)
			(arc
				(start 4.686554 -263.44245)
				(mid 4.501577 -263.466605)
				(end 4.315206 -263.474708)
			)
			(arc
				(start 4.31419 -263.474708)
				(mid 4.068759 -263.460658)
				(end 3.82651 -263.418828)
			)
			(xy 3.820668 -263.417558)
			(arc
				(start 3.263138 -263.417558)
				(mid 3.243615 -263.421459)
				(end 3.22707 -263.432544)
			)
			(arc
				(start 3.088386 -263.571228)
				(mid 3.077275 -263.587762)
				(end 3.0734 -263.607296)
			)
			(xy 3.0734 -266.803632) (xy 3.0734 -266.803886) (xy 3.0734 -267.18514) (xy 3.30708 -267.41882) (xy 8.198866 -267.41882)
		)
		(stroke
			(width 0)
			(type solid)
		)
		(fill yes)
		(layer "F.Cu")
		(net "P52V_HSC")
	)
	(gr_poly
		(pts
			(arc
				(start 34.541206 -268.381226)
				(mid 34.560729 -268.377325)
				(end 34.577274 -268.36624)
			)
			(arc
				(start 37.155628 -265.787886)
				(mid 37.520284 -265.500894)
				(end 37.942266 -265.307826)
			)
			(xy 37.942774 -265.307572) (xy 37.948616 -265.30554) (xy 37.953442 -265.302746) (xy 37.963094 -265.295126)
			(arc
				(start 38.053518 -265.204702)
				(mid 38.687792 -264.781243)
				(end 39.435786 -264.63244)
			)
			(arc
				(start 41.19245 -264.63244)
				(mid 41.211973 -264.628539)
				(end 41.228518 -264.617454)
			)
			(arc
				(start 41.361614 -264.484358)
				(mid 41.372725 -264.467824)
				(end 41.3766 -264.44829)
			)
			(arc
				(start 41.3766 -263.430766)
				(mid 41.372699 -263.411243)
				(end 41.361614 -263.394698)
			)
			(arc
				(start 41.25341 -263.286494)
				(mid 41.236876 -263.275383)
				(end 41.217342 -263.271508)
			)
			(arc
				(start 39.923974 -263.271508)
				(mid 39.912635 -263.27279)
				(end 39.901876 -263.276588)
			)
			(arc
				(start 39.901876 -263.276588)
				(mid 39.824292 -263.312599)
				(end 39.745412 -263.345676)
			)
			(xy 39.735506 -263.34974)
			(arc
				(start 39.567612 -263.517634)
				(mid 39.551078 -263.528745)
				(end 39.531544 -263.53262)
			)
			(arc
				(start 30.308804 -263.53262)
				(mid 30.289281 -263.536521)
				(end 30.272736 -263.547606)
			)
			(arc
				(start 30.063186 -263.757156)
				(mid 30.052075 -263.77369)
				(end 30.0482 -263.793224)
			)
			(arc
				(start 30.0482 -268.330426)
				(mid 30.063079 -268.366347)
				(end 30.099 -268.381226)
			)
		)
		(stroke
			(width 0)
			(type solid)
		)
		(fill yes)
		(layer "F.Cu")
		(net "P52V_HSC")
	)
	(gr_poly
		(pts
			(arc
				(start 18.083276 -63.220092)
				(mid 18.102799 -63.216191)
				(end 18.119344 -63.205106)
			)
			(arc
				(start 18.222214 -63.102236)
				(mid 18.233325 -63.085702)
				(end 18.2372 -63.066168)
			)
			(arc
				(start 18.2372 -58.110882)
				(mid 18.233299 -58.091359)
				(end 18.222214 -58.074814)
			)
			(arc
				(start 17.998186 -57.850786)
				(mid 17.981652 -57.839675)
				(end 17.962118 -57.8358)
			)
			(arc
				(start 7.641082 -57.8358)
				(mid 7.621559 -57.839701)
				(end 7.605014 -57.850786)
			)
			(arc
				(start 6.542786 -58.913014)
				(mid 6.531675 -58.929548)
				(end 6.5278 -58.949082)
			)
			(arc
				(start 6.5278 -60.022232)
				(mid 6.531701 -60.041755)
				(end 6.542786 -60.0583)
			)
			(xy 6.562852 -60.078366) (xy 6.581394 -60.085986) (xy 6.600952 -60.085986) (xy 6.62686 -60.08624)
			(xy 6.888734 -60.348114) (xy 8.759952 -60.348114) (xy 8.76046 -60.348114)
			(arc
				(start 11.914632 -60.348114)
				(mid 11.934155 -60.352015)
				(end 11.9507 -60.3631)
			)
			(xy 12.07389 -60.48629)
			(arc
				(start 12.075668 -60.487814)
				(mid 12.23737 -60.63396)
				(end 12.383516 -60.795662)
			)
			(xy 12.38504 -60.79744) (xy 12.3952 -60.8076) (xy 12.3952 -60.809886)
			(arc
				(start 12.406122 -60.823602)
				(mid 12.75074 -61.453172)
				(end 12.869926 -62.160912)
			)
			(arc
				(start 12.869926 -62.160912)
				(mid 12.852021 -62.438678)
				(end 12.798552 -62.711838)
			)
			(xy 12.795504 -62.723268) (xy 12.800076 -62.746128)
			(arc
				(start 12.856464 -62.819534)
				(mid 12.874375 -62.83404)
				(end 12.89685 -62.839092)
			)
			(arc
				(start 17.210532 -62.839092)
				(mid 17.230055 -62.842993)
				(end 17.2466 -62.854078)
			)
			(arc
				(start 17.597628 -63.205106)
				(mid 17.614162 -63.216217)
				(end 17.633696 -63.220092)
			)
		)
		(stroke
			(width 0)
			(type solid)
		)
		(fill yes)
		(layer "F.Cu")
		(net "P52V_HSC")
	)
	(gr_poly
		(pts
			(arc
				(start 47.91202 -62.220602)
				(mid 47.931543 -62.216701)
				(end 47.948088 -62.205616)
			)
			(arc
				(start 48.092614 -62.06109)
				(mid 48.103725 -62.044556)
				(end 48.1076 -62.025022)
			)
			(xy 48.1076 -57.76722) (xy 47.83836 -57.49798) (xy 39.42842 -57.49798)
			(arc
				(start 37.784786 -59.141614)
				(mid 37.773675 -59.158148)
				(end 37.7698 -59.177682)
			)
			(arc
				(start 37.7698 -59.661298)
				(mid 37.773701 -59.680821)
				(end 37.784786 -59.697366)
			)
			(xy 37.97046 -59.88304) (xy 37.97046 -59.8932) (xy 38.08222 -60.00496) (xy 41.179496 -60.00496)
			(arc
				(start 41.18102 -60.005468)
				(mid 41.190436 -60.007528)
				(end 41.20007 -60.007754)
			)
			(xy 41.241726 -60.00496)
			(arc
				(start 41.490392 -60.00496)
				(mid 41.614759 -60.015724)
				(end 41.738296 -60.033662)
			)
			(arc
				(start 41.738296 -60.033662)
				(mid 41.746932 -60.034402)
				(end 41.755568 -60.033662)
			)
			(arc
				(start 41.755568 -60.033662)
				(mid 41.879105 -60.01573)
				(end 42.003472 -60.00496)
			)
			(arc
				(start 42.25163 -60.00496)
				(mid 42.791666 -60.105946)
				(end 43.288712 -60.339986)
			)
			(xy 43.28922 -60.340494)
			(arc
				(start 43.289474 -60.340494)
				(mid 43.302282 -60.346137)
				(end 43.316144 -60.348114)
			)
			(arc
				(start 43.359832 -60.348114)
				(mid 43.379355 -60.352015)
				(end 43.3959 -60.3631)
			)
			(xy 43.75658 -60.72378) (xy 43.7642 -60.742322) (xy 43.7642 -60.751466)
			(arc
				(start 43.776138 -60.76569)
				(mid 44.155591 -61.417932)
				(end 44.28744 -62.160912)
			)
			(arc
				(start 44.28744 -62.169802)
				(mid 44.302319 -62.205723)
				(end 44.33824 -62.220602)
			)
		)
		(stroke
			(width 0)
			(type solid)
		)
		(fill yes)
		(layer "F.Cu")
		(net "P52V_HSC")
	)
	(gr_poly
		(pts
			(arc
				(start 36.478718 -59.2328)
				(mid 36.498241 -59.228899)
				(end 36.514786 -59.217814)
			)
			(arc
				(start 39.863014 -55.869586)
				(mid 39.879548 -55.858475)
				(end 39.899082 -55.8546)
			)
			(xy 42.96664 -55.8546)
			(arc
				(start 42.970704 -55.850536)
				(mid 42.986786 -55.839694)
				(end 42.997628 -55.823612)
			)
			(xy 43.1292 -55.69204) (xy 43.1292 -44.33316) (xy 41.376092 -42.580052)
			(arc
				(start 41.376092 -36.951666)
				(mid 41.372259 -36.932309)
				(end 41.36136 -36.915852)
			)
			(arc
				(start 41.266618 -36.82111)
				(mid 41.250084 -36.809999)
				(end 41.23055 -36.806124)
			)
			(arc
				(start 34.123122 -36.806124)
				(mid 34.095549 -36.814258)
				(end 34.076894 -36.836096)
			)
			(arc
				(start 34.076894 -36.836096)
				(mid 33.896513 -37.158767)
				(end 33.663128 -37.445442)
			)
			(arc
				(start 33.663128 -37.445442)
				(mid 33.650022 -37.469975)
				(end 33.651698 -37.497766)
			)
			(arc
				(start 33.651698 -37.497766)
				(mid 33.74957 -37.873321)
				(end 33.782508 -38.26002)
			)
			(arc
				(start 33.782508 -38.260782)
				(mid 33.744867 -38.673451)
				(end 33.63341 -39.072566)
			)
			(arc
				(start 33.63341 -39.072566)
				(mid 33.630936 -39.081433)
				(end 33.630108 -39.0906)
			)
			(arc
				(start 33.630108 -54.864)
				(mid 33.467644 -55.680674)
				(end 33.005014 -56.373014)
			)
			(arc
				(start 32.755586 -56.622442)
				(mid 32.744524 -56.638859)
				(end 32.7406 -56.658256)
			)
			(xy 32.7406 -58.98896) (xy 32.95396 -59.20232) (xy 33.14192 -59.20232)
			(arc
				(start 33.157414 -59.217814)
				(mid 33.173948 -59.228925)
				(end 33.193482 -59.2328)
			)
		)
		(stroke
			(width 0)
			(type solid)
		)
		(fill yes)
		(layer "F.Cu")
		(net "P52V_FAN_3")
	)
	(gr_poly
		(pts
			(arc
				(start 4.314952 -261.5692)
				(mid 4.336877 -261.56823)
				(end 4.35864 -261.56539)
			)
			(arc
				(start 4.35864 -261.56539)
				(mid 4.69519 -261.536223)
				(end 5.03174 -261.56539)
			)
			(arc
				(start 5.03174 -261.56539)
				(mid 5.053628 -261.56826)
				(end 5.075682 -261.5692)
			)
			(arc
				(start 5.076698 -261.5692)
				(mid 5.098751 -261.568241)
				(end 5.12064 -261.56539)
			)
			(arc
				(start 5.12064 -261.56539)
				(mid 5.45719 -261.536223)
				(end 5.79374 -261.56539)
			)
			(arc
				(start 5.79374 -261.56539)
				(mid 5.815628 -261.56826)
				(end 5.837682 -261.5692)
			)
			(arc
				(start 5.838698 -261.5692)
				(mid 5.860751 -261.568241)
				(end 5.88264 -261.56539)
			)
			(arc
				(start 5.88264 -261.56539)
				(mid 6.21919 -261.536223)
				(end 6.55574 -261.56539)
			)
			(arc
				(start 6.55574 -261.56539)
				(mid 6.577501 -261.568249)
				(end 6.599428 -261.5692)
			)
			(arc
				(start 6.599936 -261.5692)
				(mid 6.62882 -261.567669)
				(end 6.65734 -261.56285)
			)
			(xy 6.669786 -261.559802) (xy 6.670548 -261.559802) (xy 6.883654 -261.51332) (xy 6.894576 -261.512304)
			(arc
				(start 8.258556 -261.512304)
				(mid 8.294477 -261.497425)
				(end 8.309356 -261.461504)
			)
			(arc
				(start 8.309356 -255.761236)
				(mid 8.305455 -255.741713)
				(end 8.29437 -255.725168)
			)
			(arc
				(start 7.951978 -255.382776)
				(mid 7.935444 -255.371665)
				(end 7.91591 -255.36779)
			)
			(arc
				(start 3.174492 -255.36779)
				(mid 3.154969 -255.371691)
				(end 3.138424 -255.382776)
			)
			(arc
				(start 2.935986 -255.585214)
				(mid 2.924875 -255.601748)
				(end 2.921 -255.621282)
			)
			(arc
				(start 2.921 -261.424674)
				(mid 2.925384 -261.445575)
				(end 2.938018 -261.462774)
			)
			(xy 3.003042 -261.520432) (xy 3.023362 -261.526782)
			(arc
				(start 3.034538 -261.525512)
				(mid 3.148518 -261.515574)
				(end 3.262884 -261.512304)
			)
			(xy 4.019804 -261.512304) (xy 4.030726 -261.51332) (xy 4.243832 -261.559802) (xy 4.244594 -261.559802)
			(arc
				(start 4.25704 -261.56285)
				(mid 4.285561 -261.567655)
				(end 4.314444 -261.5692)
			)
		)
		(stroke
			(width 0)
			(type solid)
		)
		(fill yes)
		(layer "F.Cu")
		(net "GND")
	)
	(gr_poly
		(pts
			(arc
				(start 14.78788 -281.559)
				(mid 14.805647 -281.555792)
				(end 14.821154 -281.546554)
			)
			(arc
				(start 14.821154 -281.546554)
				(mid 15.456531 -281.158632)
				(end 16.182848 -280.995374)
			)
			(arc
				(start 16.182848 -280.995374)
				(mid 16.21676 -280.979558)
				(end 16.2306 -280.944828)
			)
			(xy 16.2306 -269.921482) (xy 16.2306 -269.614396)
			(arc
				(start 16.484092 -269.360904)
				(mid 16.487993 -269.341381)
				(end 16.499078 -269.324836)
			)
			(xy 17.455896 -268.368018)
			(arc
				(start 17.458944 -268.363446)
				(mid 17.749845 -268.002075)
				(end 18.111216 -267.711174)
			)
			(xy 18.115788 -267.708126)
			(arc
				(start 18.146014 -267.6779)
				(mid 18.157125 -267.661366)
				(end 18.161 -267.641832)
			)
			(arc
				(start 18.161 -264.308082)
				(mid 18.157099 -264.288559)
				(end 18.146014 -264.272014)
			)
			(arc
				(start 18.048986 -264.174986)
				(mid 18.032452 -264.163875)
				(end 18.012918 -264.16)
			)
			(xy 15.705836 -264.16) (xy 15.22222 -264.16) (xy 15.16634 -264.21588) (xy 15.01902 -264.3632) (xy 15.01902 -265.77544)
			(xy 13.889228 -266.905232)
			(arc
				(start 11.46937 -266.905232)
				(mid 11.449847 -266.909133)
				(end 11.433302 -266.920218)
			)
			(arc
				(start 8.793734 -269.559786)
				(mid 8.782623 -269.57632)
				(end 8.778748 -269.595854)
			)
			(xy 8.778748 -271.514316) (xy 8.778748 -271.71777) (xy 8.778748 -271.738852) (xy 8.532368 -271.985232)
			(xy 8.532114 -271.985486)
			(arc
				(start 7.736586 -272.781014)
				(mid 7.720052 -272.792125)
				(end 7.700518 -272.796)
			)
			(arc
				(start 4.618482 -272.796)
				(mid 4.598959 -272.799901)
				(end 4.582414 -272.810986)
			)
			(arc
				(start 4.002786 -273.390614)
				(mid 3.991675 -273.407148)
				(end 3.9878 -273.426682)
			)
			(arc
				(start 3.9878 -281.106118)
				(mid 3.991701 -281.125641)
				(end 4.002786 -281.142186)
			)
			(arc
				(start 4.404614 -281.544014)
				(mid 4.421148 -281.555125)
				(end 4.440682 -281.559)
			)
		)
		(stroke
			(width 0)
			(type solid)
		)
		(fill yes)
		(layer "F.Cu")
		(net "P52V_FAN_7")
	)
	(gr_poly
		(pts
			(arc
				(start 47.69993 -336.492088)
				(mid 50.169141 -335.469307)
				(end 51.191922 -333.000096)
			)
			(xy 51.191922 -223.341692) (xy 51.191668 -223.336866) (xy 51.191668 -216.144856) (xy 51.191922 -216.144602)
			(xy 51.191922 -99.64801) (xy 51.191668 -99.64293) (xy 51.191668 -97.46107) (xy 51.191922 -97.45599)
			(arc
				(start 51.191922 -3.999992)
				(mid 50.322101 -1.693864)
				(end 48.145954 -0.536702)
			)
			(xy 48.13935 -0.536194)
			(arc
				(start 36.957762 -0.536194)
				(mid 36.938239 -0.540095)
				(end 36.921694 -0.55118)
			)
			(arc
				(start 35.762946 -1.709928)
				(mid 35.751835 -1.726462)
				(end 35.74796 -1.745996)
			)
			(arc
				(start 35.74796 -10.999978)
				(mid 35.263697 -12.191461)
				(end 34.08553 -12.707366)
			)
			(arc
				(start 34.08553 -12.707366)
				(mid 34.050422 -12.722686)
				(end 34.036 -12.758166)
			)
			(arc
				(start 34.036 -13.111988)
				(mid 34.040111 -13.132007)
				(end 34.051748 -13.148818)
			)
			(arc
				(start 34.104834 -13.199618)
				(mid 34.122077 -13.210411)
				(end 34.142172 -13.213588)
			)
			(arc
				(start 34.142172 -13.213588)
				(mid 35.642523 -12.530291)
				(end 36.255706 -10.999978)
			)
			(arc
				(start 36.255706 -1.94183)
				(mid 36.259607 -1.922307)
				(end 36.270692 -1.905762)
			)
			(arc
				(start 37.145722 -1.030732)
				(mid 37.162256 -1.019621)
				(end 37.18179 -1.015746)
			)
			(arc
				(start 47.69993 -1.015746)
				(mid 49.810111 -1.889811)
				(end 50.684176 -3.999992)
			)
			(arc
				(start 50.684176 -333.000096)
				(mid 49.810111 -335.110277)
				(end 47.69993 -335.984342)
			)
			(arc
				(start 3.999992 -335.984342)
				(mid 1.889811 -335.110277)
				(end 1.015746 -333.000096)
			)
			(xy 1.015746 -177.016664) (xy 1.015492 -177.00117) (xy 1.015492 -169.161714) (xy 1.015746 -169.14622)
			(arc
				(start 1.015746 -3.999992)
				(mid 1.889811 -1.889811)
				(end 3.999992 -1.015746)
			)
			(arc
				(start 14.518132 -1.015746)
				(mid 14.537655 -1.019647)
				(end 14.5542 -1.030732)
			)
			(arc
				(start 15.42923 -1.905762)
				(mid 15.440341 -1.922296)
				(end 15.444216 -1.94183)
			)
			(arc
				(start 15.444216 -10.999978)
				(mid 16.053524 -12.526006)
				(end 17.54632 -13.212826)
			)
			(arc
				(start 17.54632 -13.212826)
				(mid 17.566557 -13.209712)
				(end 17.583912 -13.198856)
			)
			(arc
				(start 17.637252 -13.148056)
				(mid 17.648929 -13.131262)
				(end 17.653 -13.111226)
			)
			(arc
				(start 17.653 -12.757658)
				(mid 17.638744 -12.722371)
				(end 17.603978 -12.706858)
			)
			(arc
				(start 17.603978 -12.706858)
				(mid 16.432667 -12.18765)
				(end 15.951962 -10.999978)
			)
			(arc
				(start 15.951962 -1.740154)
				(mid 15.948061 -1.720631)
				(end 15.936976 -1.704086)
			)
			(arc
				(start 14.75867 -0.52578)
				(mid 14.742136 -0.514669)
				(end 14.722602 -0.510794)
			)
			(arc
				(start 3.859276 -0.510794)
				(mid 1.481492 -1.581013)
				(end 0.508 -3.999992)
			)
			(xy 0.508 -10.657586) (xy 0.508254 -10.662412) (xy 0.508254 -95.103188) (xy 0.508 -95.108014) (xy 0.508 -124.25045)
			(xy 0.508254 -124.255784) (xy 0.508254 -125.007116) (xy 0.508 -125.01245) (xy 0.508 -214.974932)
			(xy 0.508254 -214.980012) (xy 0.508254 -219.806266) (xy 0.508 -219.80652)
			(arc
				(start 0.508 -333.000096)
				(mid 1.530781 -335.469307)
				(end 3.999992 -336.492088)
			)
		)
		(stroke
			(width 0)
			(type solid)
		)
		(fill yes)
		(layer "F.Cu")
		(net "GND")
	)
	(gr_poly
		(pts
			(xy 7.17042 -88.22182) (xy 7.17042 -85.256116) (xy 6.930898 -85.016594) (xy 2.075942 -85.016594)
			(xy 1.8796 -85.212936)
			(arc
				(start 1.8796 -88.182958)
				(mid 1.883501 -88.202481)
				(end 1.894586 -88.219026)
			)
			(arc
				(start 2.083054 -88.407494)
				(mid 2.099588 -88.418605)
				(end 2.119122 -88.42248)
			)
			(xy 6.96976 -88.42248)
		)
		(stroke
			(width 0)
			(type solid)
		)
		(fill yes)
		(layer "B.Cu")
		(net "GND")
	)
	(gr_poly
		(pts
			(xy 48.778668 -273.304) (xy 48.778668 -268.605) (xy 48.651668 -268.478) (xy 46.361096 -268.478) (xy 44.9834 -269.855696)
			(arc
				(start 44.9834 -273.232118)
				(mid 44.987301 -273.251641)
				(end 44.998386 -273.268186)
			)
			(arc
				(start 45.120814 -273.390614)
				(mid 45.137348 -273.401725)
				(end 45.156882 -273.4056)
			)
			(xy 48.677068 -273.4056)
		)
		(stroke
			(width 0)
			(type solid)
		)
		(fill yes)
		(layer "B.Cu")
		(net "GND")
	)
	(gr_poly
		(pts
			(xy 49.5046 -88.532716)
			(arc
				(start 49.5046 -85.085682)
				(mid 49.500699 -85.066159)
				(end 49.489614 -85.049614)
			)
			(arc
				(start 48.935386 -84.495386)
				(mid 48.918852 -84.484275)
				(end 48.899318 -84.4804)
			)
			(xy 45.011594 -84.4804) (xy 44.36491 -85.127084) (xy 44.36491 -88.48471) (xy 44.365164 -88.484964)
			(xy 44.365164 -88.529414) (xy 44.619926 -88.784176) (xy 49.25314 -88.784176)
		)
		(stroke
			(width 0)
			(type solid)
		)
		(fill yes)
		(layer "B.Cu")
		(net "GND")
	)
	(gr_poly
		(pts
			(xy 5.169154 -53.682646) (xy 5.169154 -52.427124) (xy 5.169154 -51.757326) (xy 5.21208 -51.7144)
			(xy 5.21208 -39.60368) (xy 4.699 -39.0906) (xy 1.7018 -39.0906) (xy 1.538986 -39.253414) (xy 1.53162 -39.260526)
			(xy 1.531366 -39.261034) (xy 1.524 -39.2684)
			(arc
				(start 1.524 -53.623718)
				(mid 1.527901 -53.643241)
				(end 1.538986 -53.659786)
			)
			(xy 1.62052 -53.74132) (xy 4.7498 -53.74132) (xy 5.11048 -53.74132)
		)
		(stroke
			(width 0)
			(type solid)
		)
		(fill yes)
		(layer "B.Cu")
		(net "GND")
	)
	(gr_poly
		(pts
			(xy 29.86786 -13.43914) (xy 29.86786 -13.31214) (xy 29.86786 -13.078714) (xy 29.86786 -8.20674) (xy 30.18028 -7.89432)
			(xy 31.786068 -7.89432) (xy 31.857188 -7.8232) (xy 31.857188 -2.189988) (xy 31.5468 -1.8796) (xy 28.540964 -1.8796)
			(xy 28.159964 -2.2606) (xy 27.9908 -2.429764) (xy 27.9908 -8.128) (xy 28.067 -8.2042) (xy 28.067 -12.94892)
			(xy 28.067 -13.462) (xy 28.194 -13.589) (xy 29.591 -13.589) (xy 29.718 -13.589)
		)
		(stroke
			(width 0)
			(type solid)
		)
		(fill yes)
		(layer "B.Cu")
		(net "P52V_HSC")
	)
	(gr_poly
		(pts
			(arc
				(start 7.655306 -273.431)
				(mid 7.674829 -273.427099)
				(end 7.691374 -273.416014)
			)
			(arc
				(start 7.864094 -273.243294)
				(mid 7.875205 -273.22676)
				(end 7.87908 -273.207226)
			)
			(xy 7.87908 -269.896844) (xy 7.652004 -269.669768) (xy 2.166366 -269.669768) (xy 1.918208 -269.917926)
			(arc
				(start 1.918208 -273.130264)
				(mid 1.922109 -273.149787)
				(end 1.933194 -273.166332)
			)
			(arc
				(start 2.182876 -273.416014)
				(mid 2.19941 -273.427125)
				(end 2.218944 -273.431)
			)
		)
		(stroke
			(width 0)
			(type solid)
		)
		(fill yes)
		(layer "B.Cu")
		(net "GND")
	)
	(gr_poly
		(pts
			(xy 8.1788 -76.72324)
			(arc
				(start 8.1788 -72.639682)
				(mid 8.174899 -72.620159)
				(end 8.163814 -72.603614)
			)
			(arc
				(start 7.896098 -72.335898)
				(mid 7.879564 -72.324787)
				(end 7.86003 -72.320912)
			)
			(arc
				(start 3.751072 -72.320912)
				(mid 3.731549 -72.324813)
				(end 3.715004 -72.335898)
			)
			(arc
				(start 3.490976 -72.559926)
				(mid 3.479865 -72.57646)
				(end 3.47599 -72.595994)
			)
			(xy 3.47599 -76.87437) (xy 3.62204 -77.02042) (xy 7.88162 -77.02042)
		)
		(stroke
			(width 0)
			(type solid)
		)
		(fill yes)
		(layer "B.Cu")
		(net "GND")
	)
	(gr_poly
		(pts
			(arc
				(start 22.432518 -95.561912)
				(mid 22.452041 -95.558011)
				(end 22.468586 -95.546926)
			)
			(arc
				(start 22.819614 -95.195898)
				(mid 22.830725 -95.179364)
				(end 22.8346 -95.15983)
			)
			(arc
				(start 22.8346 -85.619082)
				(mid 22.830699 -85.599559)
				(end 22.819614 -85.583014)
			)
			(arc
				(start 22.595586 -85.358986)
				(mid 22.579052 -85.347875)
				(end 22.559518 -85.344)
			)
			(xy 17.272 -85.344) (xy 17.145 -85.471) (xy 17.145 -87.52586) (xy 17.09166 -87.5792) (xy 17.09166 -94.54896)
			(xy 18.104612 -95.561912)
		)
		(stroke
			(width 0)
			(type solid)
		)
		(fill yes)
		(layer "B.Cu")
		(net "GND")
	)
	(gr_poly
		(pts
			(xy 36.195 -76.78674)
			(arc
				(start 36.195 -72.588882)
				(mid 36.191099 -72.569359)
				(end 36.180014 -72.552814)
			)
			(arc
				(start 35.963098 -72.335898)
				(mid 35.946564 -72.324787)
				(end 35.92703 -72.320912)
			)
			(arc
				(start 30.39237 -72.320912)
				(mid 30.372847 -72.324813)
				(end 30.356302 -72.335898)
			)
			(arc
				(start 30.012386 -72.679814)
				(mid 30.001275 -72.696348)
				(end 29.9974 -72.715882)
			)
			(xy 29.9974 -76.681838) (xy 29.9974 -76.682092) (xy 29.9974 -76.7969) (xy 30.20822 -77.00772) (xy 35.97402 -77.00772)
		)
		(stroke
			(width 0)
			(type solid)
		)
		(fill yes)
		(layer "B.Cu")
		(net "GND")
	)
	(gr_poly
		(pts
			(arc
				(start 23.29815 -279.110694)
				(mid 23.317673 -279.106793)
				(end 23.334218 -279.095708)
			)
			(arc
				(start 23.685246 -278.74468)
				(mid 23.696357 -278.728146)
				(end 23.700232 -278.708612)
			)
			(arc
				(start 23.700232 -268.7828)
				(mid 23.696331 -268.763277)
				(end 23.685246 -268.746732)
			)
			(arc
				(start 23.590758 -268.652244)
				(mid 23.574224 -268.641133)
				(end 23.55469 -268.637258)
			)
			(xy 18.161 -268.637258) (xy 17.690846 -269.107412) (xy 17.690846 -271.284954) (xy 17.671796 -271.304004)
			(xy 17.671796 -278.631396) (xy 17.68094 -278.64054) (xy 18.151094 -279.110694)
		)
		(stroke
			(width 0)
			(type solid)
		)
		(fill yes)
		(layer "B.Cu")
		(net "GND")
	)
	(gr_poly
		(pts
			(arc
				(start 16.277336 -69.596)
				(mid 16.296859 -69.592099)
				(end 16.313404 -69.581014)
			)
			(xy 16.679418 -69.215)
			(arc
				(start 16.70685 -69.187822)
				(mid 16.717961 -69.171288)
				(end 16.721836 -69.151754)
			)
			(xy 16.721836 -65.187068) (xy 16.721836 -65.024254) (xy 16.538956 -64.841374) (xy 12.639294 -64.841374)
			(xy 12.400534 -64.841374) (xy 12.2936 -64.948308) (xy 12.2936 -65.187068)
			(arc
				(start 12.2936 -69.473318)
				(mid 12.297501 -69.492841)
				(end 12.308586 -69.509386)
			)
			(arc
				(start 12.380214 -69.581014)
				(mid 12.396748 -69.592125)
				(end 12.416282 -69.596)
			)
		)
		(stroke
			(width 0)
			(type solid)
		)
		(fill yes)
		(layer "B.Cu")
		(net "GND")
	)
	(gr_poly
		(pts
			(xy 34.116772 -95.095568) (xy 34.117026 -95.095314) (xy 34.23666 -94.97568) (xy 34.2646 -94.94774)
			(xy 34.2646 -87.122) (xy 34.544 -86.8426) (xy 34.544 -86.106) (xy 34.544 -85.3948) (xy 34.4678 -85.3186)
			(arc
				(start 28.900882 -85.3186)
				(mid 28.881359 -85.322501)
				(end 28.864814 -85.333586)
			)
			(xy 28.666186 -85.532214) (xy 28.65882 -85.539326) (xy 28.6512 -85.558122)
			(arc
				(start 28.6512 -94.720918)
				(mid 28.655101 -94.740441)
				(end 28.666186 -94.756986)
			)
			(arc
				(start 29.004514 -95.095314)
				(mid 29.021048 -95.106425)
				(end 29.040582 -95.1103)
			)
			(xy 34.10204 -95.1103)
		)
		(stroke
			(width 0)
			(type solid)
		)
		(fill yes)
		(layer "B.Cu")
		(net "GND")
	)
	(gr_poly
		(pts
			(arc
				(start 8.308594 -261.139686)
				(mid 8.319083 -261.131633)
				(end 8.327136 -261.121144)
			)
			(xy 8.333994 -261.114286)
			(arc
				(start 8.333994 -256.741676)
				(mid 8.330093 -256.722153)
				(end 8.319008 -256.705608)
			)
			(arc
				(start 7.990586 -256.377186)
				(mid 7.974052 -256.366075)
				(end 7.954518 -256.3622)
			)
			(arc
				(start 2.327402 -256.3622)
				(mid 2.307879 -256.366101)
				(end 2.291334 -256.377186)
			)
			(arc
				(start 1.965706 -256.702814)
				(mid 1.954595 -256.719348)
				(end 1.95072 -256.738882)
			)
			(xy 1.95072 -261.116572) (xy 1.95072 -261.116826) (xy 1.95072 -261.3533) (xy 2.16916 -261.57174)
			(xy 7.87654 -261.57174)
		)
		(stroke
			(width 0)
			(type solid)
		)
		(fill yes)
		(layer "B.Cu")
		(net "GND")
	)
	(gr_poly
		(pts
			(xy 4.689348 -238.312452) (xy 4.689348 -236.928152) (xy 4.689348 -236.331252) (xy 4.7371 -236.2835)
			(xy 4.7371 -227.875846) (xy 5.423154 -227.189792)
			(arc
				(start 5.42544 -227.186998)
				(mid 5.432993 -227.172582)
				(end 5.4356 -227.156518)
			)
			(arc
				(start 5.4356 -220.950282)
				(mid 5.431699 -220.930759)
				(end 5.420614 -220.914214)
			)
			(xy 5.196586 -220.690186) (xy 5.189474 -220.68282) (xy 5.170678 -220.6752)
			(arc
				(start 2.256282 -220.6752)
				(mid 2.236759 -220.679101)
				(end 2.220214 -220.690186)
			)
			(xy 1.996186 -220.914214) (xy 1.98882 -220.921326) (xy 1.9812 -220.940122) (xy 1.9812 -238.12246)
			(xy 2.23012 -238.37138) (xy 4.63042 -238.37138)
		)
		(stroke
			(width 0)
			(type solid)
		)
		(fill yes)
		(layer "B.Cu")
		(net "GND")
	)
	(gr_poly
		(pts
			(arc
				(start 49.653698 -239.86998)
				(mid 49.673055 -239.866147)
				(end 49.689512 -239.855248)
			)
			(arc
				(start 50.175414 -239.369346)
				(mid 50.186525 -239.352812)
				(end 50.1904 -239.333278)
			)
			(arc
				(start 50.1904 -224.963482)
				(mid 50.186499 -224.943959)
				(end 50.175414 -224.927414)
			)
			(arc
				(start 49.938686 -224.690686)
				(mid 49.922152 -224.679575)
				(end 49.902618 -224.6757)
			)
			(arc
				(start 46.642782 -224.6757)
				(mid 46.623259 -224.679601)
				(end 46.606714 -224.690686)
			)
			(xy 44.96816 -226.32924) (xy 44.958 -226.3394) (xy 44.958 -237.7948) (xy 45.002958 -237.839758) (xy 45.002958 -239.8014)
			(xy 45.071538 -239.86998) (xy 45.3898 -239.86998)
		)
		(stroke
			(width 0)
			(type solid)
		)
		(fill yes)
		(layer "B.Cu")
		(net "GND")
	)
	(gr_poly
		(pts
			(arc
				(start 8.36168 -82.930238)
				(mid 8.381203 -82.926337)
				(end 8.397748 -82.915252)
			)
			(xy 10.898124 -80.414876) (xy 10.955782 -80.357218) (xy 11.448034 -80.357218) (xy 13.8938 -80.357218)
			(xy 13.962634 -80.288384) (xy 13.962634 -78.932278) (xy 14.13764 -78.757272) (xy 14.1986 -78.757272)
			(xy 17.06245 -78.757272) (xy 17.102582 -78.71714)
			(arc
				(start 17.102582 -78.50251)
				(mid 17.087703 -78.466589)
				(end 17.051782 -78.45171)
			)
			(xy 11.43 -78.45171) (xy 11.083798 -78.797912) (xy 8.44804 -78.797912) (xy 8.283702 -78.96225) (xy 3.557016 -78.96225)
			(xy 3.297936 -79.22133) (xy 3.297936 -82.634328) (xy 3.593846 -82.930238)
		)
		(stroke
			(width 0)
			(type solid)
		)
		(fill yes)
		(layer "B.Cu")
		(net "P52V_HSC")
	)
	(gr_poly
		(pts
			(xy 32.56788 -279.97912) (xy 32.56788 -273.42846) (xy 33.782 -272.21434) (xy 33.782 -270.8783) (xy 33.6931 -270.7894)
			(arc
				(start 28.951428 -270.7894)
				(mid 28.94159 -270.790362)
				(end 28.932124 -270.79321)
			)
			(arc
				(start 28.919932 -270.79829)
				(mid 28.910466 -270.801139)
				(end 28.900628 -270.8021)
			)
			(arc
				(start 28.557982 -270.8021)
				(mid 28.538459 -270.806001)
				(end 28.521914 -270.817086)
			)
			(xy 28.208986 -271.130014) (xy 28.20162 -271.137126) (xy 28.194 -271.155922)
			(arc
				(start 28.194 -279.632918)
				(mid 28.197901 -279.652441)
				(end 28.208986 -279.668986)
			)
			(arc
				(start 28.560014 -280.020014)
				(mid 28.576548 -280.031125)
				(end 28.596082 -280.035)
			)
			(xy 32.512 -280.035)
		)
		(stroke
			(width 0)
			(type solid)
		)
		(fill yes)
		(layer "B.Cu")
		(net "GND")
	)
	(gr_poly
		(pts
			(arc
				(start 49.666398 -55.47106)
				(mid 49.685921 -55.467159)
				(end 49.702466 -55.456074)
			)
			(arc
				(start 50.023014 -55.135526)
				(mid 50.034125 -55.118992)
				(end 50.038 -55.099458)
			)
			(xy 50.038 -39.7002) (xy 50.023268 -39.685468) (xy 50.023014 -39.685214) (xy 49.824386 -39.486586)
			(xy 49.817274 -39.47922) (xy 49.816766 -39.478966) (xy 49.8094 -39.4716) (xy 47.0408 -39.4716) (xy 47.026068 -39.486332)
			(xy 47.025814 -39.486586) (xy 45.19422 -41.31818) (xy 45.19422 -44.79798) (xy 45.5676 -45.17136)
			(xy 45.5676 -50.2412) (xy 45.5676 -53.467) (xy 45.5676 -53.6956) (xy 45.5168 -53.7464) (xy 45.2374 -54.0258)
			(xy 45.0596 -54.2036) (xy 45.0596 -55.4228) (xy 45.10786 -55.47106)
		)
		(stroke
			(width 0)
			(type solid)
		)
		(fill yes)
		(layer "B.Cu")
		(net "GND")
	)
	(gr_poly
		(pts
			(xy 17.8054 -247.65)
			(arc
				(start 17.8054 -242.540282)
				(mid 17.801499 -242.520759)
				(end 17.790414 -242.504214)
			)
			(arc
				(start 17.617186 -242.330986)
				(mid 17.600652 -242.319875)
				(end 17.581118 -242.316)
			)
			(arc
				(start 9.761728 -242.316)
				(mid 9.742205 -242.319901)
				(end 9.72566 -242.330986)
			)
			(xy 9.124696 -242.931696) (xy 9.013698 -243.042694) (xy 6.232906 -243.042694) (xy 6.192774 -243.082826)
			(xy 6.192774 -244.479826) (xy 6.02996 -244.64264) (xy 3.092958 -244.64264) (xy 3.052826 -244.682772)
			(xy 3.052826 -244.907308) (xy 3.092958 -244.94744) (xy 8.700008 -244.94744) (xy 11.873484 -244.94744)
			(xy 11.874246 -244.948202) (xy 12.044172 -245.118128) (xy 12.044172 -247.772174) (xy 12.15009 -247.878092)
			(xy 17.577308 -247.878092)
		)
		(stroke
			(width 0)
			(type solid)
		)
		(fill yes)
		(layer "B.Cu")
		(net "P52V_HSC")
	)
	(gr_poly
		(pts
			(arc
				(start 10.439908 -78.035912)
				(mid 10.459431 -78.032011)
				(end 10.475976 -78.020926)
			)
			(arc
				(start 10.573004 -77.923898)
				(mid 10.584115 -77.907364)
				(end 10.58799 -77.88783)
			)
			(arc
				(start 10.58799 -76.532994)
				(mid 10.584089 -76.513471)
				(end 10.573004 -76.496926)
			)
			(arc
				(start 10.475976 -76.399898)
				(mid 10.459442 -76.388787)
				(end 10.439908 -76.384912)
			)
			(arc
				(start 9.212072 -76.384912)
				(mid 9.192549 -76.388813)
				(end 9.176004 -76.399898)
			)
			(arc
				(start 9.078976 -76.496926)
				(mid 9.067865 -76.51346)
				(end 9.06399 -76.532994)
			)
			(arc
				(start 9.06399 -77.88783)
				(mid 9.067891 -77.907353)
				(end 9.078976 -77.923898)
			)
			(arc
				(start 9.176004 -78.020926)
				(mid 9.192538 -78.032037)
				(end 9.212072 -78.035912)
			)
		)
		(stroke
			(width 0)
			(type solid)
		)
		(fill yes)
		(layer "B.Cu")
		(net "GND")
	)
	(gr_poly
		(pts
			(arc
				(start 10.533888 -262.297672)
				(mid 10.553411 -262.293771)
				(end 10.569956 -262.282686)
			)
			(arc
				(start 10.666984 -262.185658)
				(mid 10.678095 -262.169124)
				(end 10.68197 -262.14959)
			)
			(arc
				(start 10.68197 -260.794754)
				(mid 10.678069 -260.775231)
				(end 10.666984 -260.758686)
			)
			(arc
				(start 10.569956 -260.661658)
				(mid 10.553422 -260.650547)
				(end 10.533888 -260.646672)
			)
			(arc
				(start 9.306052 -260.646672)
				(mid 9.286529 -260.650573)
				(end 9.269984 -260.661658)
			)
			(arc
				(start 9.172956 -260.758686)
				(mid 9.161845 -260.77522)
				(end 9.15797 -260.794754)
			)
			(arc
				(start 9.15797 -262.14959)
				(mid 9.161871 -262.169113)
				(end 9.172956 -262.185658)
			)
			(arc
				(start 9.269984 -262.282686)
				(mid 9.286518 -262.293797)
				(end 9.306052 -262.297672)
			)
		)
		(stroke
			(width 0)
			(type solid)
		)
		(fill yes)
		(layer "B.Cu")
		(net "GND")
	)
	(gr_poly
		(pts
			(arc
				(start 10.994136 -247.3452)
				(mid 11.013659 -247.341299)
				(end 11.030204 -247.330214)
			)
			(arc
				(start 11.127232 -247.233186)
				(mid 11.138343 -247.216652)
				(end 11.142218 -247.197118)
			)
			(arc
				(start 11.142218 -245.842282)
				(mid 11.138317 -245.822759)
				(end 11.127232 -245.806214)
			)
			(arc
				(start 11.030204 -245.709186)
				(mid 11.01367 -245.698075)
				(end 10.994136 -245.6942)
			)
			(arc
				(start 9.7663 -245.6942)
				(mid 9.746777 -245.698101)
				(end 9.730232 -245.709186)
			)
			(arc
				(start 9.633204 -245.806214)
				(mid 9.622093 -245.822748)
				(end 9.618218 -245.842282)
			)
			(arc
				(start 9.618218 -247.197118)
				(mid 9.622119 -247.216641)
				(end 9.633204 -247.233186)
			)
			(arc
				(start 9.730232 -247.330214)
				(mid 9.746766 -247.341325)
				(end 9.7663 -247.3452)
			)
		)
		(stroke
			(width 0)
			(type solid)
		)
		(fill yes)
		(layer "B.Cu")
		(net "GND")
	)
	(gr_poly
		(pts
			(arc
				(start 38.201346 -262.636)
				(mid 38.220869 -262.632099)
				(end 38.237414 -262.621014)
			)
			(arc
				(start 38.334442 -262.523986)
				(mid 38.345553 -262.507452)
				(end 38.349428 -262.487918)
			)
			(arc
				(start 38.349428 -261.133082)
				(mid 38.345527 -261.113559)
				(end 38.334442 -261.097014)
			)
			(arc
				(start 38.237414 -260.999986)
				(mid 38.22088 -260.988875)
				(end 38.201346 -260.985)
			)
			(arc
				(start 36.97351 -260.985)
				(mid 36.953987 -260.988901)
				(end 36.937442 -260.999986)
			)
			(arc
				(start 36.840414 -261.097014)
				(mid 36.829303 -261.113548)
				(end 36.825428 -261.133082)
			)
			(arc
				(start 36.825428 -262.487918)
				(mid 36.829329 -262.507441)
				(end 36.840414 -262.523986)
			)
			(arc
				(start 36.937442 -262.621014)
				(mid 36.953976 -262.632125)
				(end 36.97351 -262.636)
			)
		)
		(stroke
			(width 0)
			(type solid)
		)
		(fill yes)
		(layer "B.Cu")
		(net "GND")
	)
	(gr_poly
		(pts
			(arc
				(start 38.201346 -78.035912)
				(mid 38.220869 -78.032011)
				(end 38.237414 -78.020926)
			)
			(arc
				(start 38.334442 -77.923898)
				(mid 38.345553 -77.907364)
				(end 38.349428 -77.88783)
			)
			(arc
				(start 38.349428 -76.532994)
				(mid 38.345527 -76.513471)
				(end 38.334442 -76.496926)
			)
			(arc
				(start 38.237414 -76.399898)
				(mid 38.22088 -76.388787)
				(end 38.201346 -76.384912)
			)
			(arc
				(start 36.97351 -76.384912)
				(mid 36.953987 -76.388813)
				(end 36.937442 -76.399898)
			)
			(arc
				(start 36.840414 -76.496926)
				(mid 36.829303 -76.51346)
				(end 36.825428 -76.532994)
			)
			(arc
				(start 36.825428 -77.88783)
				(mid 36.829329 -77.907353)
				(end 36.840414 -77.923898)
			)
			(arc
				(start 36.937442 -78.020926)
				(mid 36.953976 -78.032037)
				(end 36.97351 -78.035912)
			)
		)
		(stroke
			(width 0)
			(type solid)
		)
		(fill yes)
		(layer "B.Cu")
		(net "GND")
	)
	(gr_poly
		(pts
			(arc
				(start 42.36085 -62.414912)
				(mid 42.380373 -62.411011)
				(end 42.396918 -62.399926)
			)
			(arc
				(start 42.493946 -62.302898)
				(mid 42.505057 -62.286364)
				(end 42.508932 -62.26683)
			)
			(arc
				(start 42.508932 -60.911994)
				(mid 42.505031 -60.892471)
				(end 42.493946 -60.875926)
			)
			(arc
				(start 42.396918 -60.778898)
				(mid 42.380384 -60.767787)
				(end 42.36085 -60.763912)
			)
			(arc
				(start 41.133014 -60.763912)
				(mid 41.113491 -60.767813)
				(end 41.096946 -60.778898)
			)
			(arc
				(start 40.999918 -60.875926)
				(mid 40.988807 -60.89246)
				(end 40.984932 -60.911994)
			)
			(arc
				(start 40.984932 -62.26683)
				(mid 40.988833 -62.286353)
				(end 40.999918 -62.302898)
			)
			(arc
				(start 41.096946 -62.399926)
				(mid 41.11348 -62.411037)
				(end 41.133014 -62.414912)
			)
		)
		(stroke
			(width 0)
			(type solid)
		)
		(fill yes)
		(layer "B.Cu")
		(net "GND")
	)
	(gr_poly
		(pts
			(arc
				(start 42.84345 -248.195846)
				(mid 42.862973 -248.191945)
				(end 42.879518 -248.18086)
			)
			(arc
				(start 42.976546 -248.083832)
				(mid 42.987657 -248.067298)
				(end 42.991532 -248.047764)
			)
			(arc
				(start 42.991532 -246.692928)
				(mid 42.987631 -246.673405)
				(end 42.976546 -246.65686)
			)
			(arc
				(start 42.879518 -246.559832)
				(mid 42.862984 -246.548721)
				(end 42.84345 -246.544846)
			)
			(arc
				(start 41.615614 -246.544846)
				(mid 41.596091 -246.548747)
				(end 41.579546 -246.559832)
			)
			(arc
				(start 41.482518 -246.65686)
				(mid 41.471407 -246.673394)
				(end 41.467532 -246.692928)
			)
			(arc
				(start 41.467532 -248.047764)
				(mid 41.471433 -248.067287)
				(end 41.482518 -248.083832)
			)
			(arc
				(start 41.579546 -248.18086)
				(mid 41.59608 -248.191971)
				(end 41.615614 -248.195846)
			)
		)
		(stroke
			(width 0)
			(type solid)
		)
		(fill yes)
		(layer "B.Cu")
		(net "GND")
	)
	(gr_poly
		(pts
			(arc
				(start 8.042148 -267.554456)
				(mid 8.061505 -267.550623)
				(end 8.077962 -267.539724)
			)
			(xy 10.602722 -265.014964) (xy 10.66038 -264.957306) (xy 11.575034 -264.957306) (xy 14.0462 -264.957306)
			(xy 14.089634 -264.913872) (xy 14.089634 -263.532366) (xy 14.097762 -263.524238) (xy 14.245082 -263.376918)
			(xy 14.26464 -263.35736) (xy 17.18945 -263.35736) (xy 17.21104 -263.35736) (xy 17.2212 -263.3472)
			(xy 17.2212 -263.32561) (xy 17.2212 -263.1948) (xy 17.2212 -263.08431) (xy 17.18945 -263.05256) (xy 14.11224 -263.05256)
			(xy 14.109954 -263.054846) (xy 11.773154 -263.054846) (xy 11.569954 -263.054846) (xy 11.565128 -263.059672)
			(xy 9.685528 -263.059672) (xy 9.226296 -263.059672) (xy 9.117584 -263.168384) (xy 8.755126 -263.530588)
			(xy 3.359912 -263.530588) (xy 3.179826 -263.710674) (xy 3.179826 -267.361416) (xy 3.372866 -267.554456)
		)
		(stroke
			(width 0)
			(type solid)
		)
		(fill yes)
		(layer "B.Cu")
		(net "P52V_HSC")
	)
	(gr_poly
		(pts
			(arc
				(start 10.943336 -62.414912)
				(mid 10.962859 -62.411011)
				(end 10.979404 -62.399926)
			)
			(arc
				(start 11.076432 -62.302898)
				(mid 11.087543 -62.286364)
				(end 11.091418 -62.26683)
			)
			(arc
				(start 11.091418 -60.911994)
				(mid 11.087517 -60.892471)
				(end 11.076432 -60.875926)
			)
			(arc
				(start 10.979404 -60.778898)
				(mid 10.96287 -60.767787)
				(end 10.943336 -60.763912)
			)
			(arc
				(start 9.7155 -60.763912)
				(mid 9.695977 -60.767813)
				(end 9.679432 -60.778898)
			)
			(arc
				(start 9.582404 -60.875926)
				(mid 9.571293 -60.89246)
				(end 9.567418 -60.911994)
			)
			(arc
				(start 9.567418 -62.066932)
				(mid 9.571368 -62.086319)
				(end 9.582404 -62.102746)
			)
			(arc
				(start 9.646158 -62.166754)
				(mid 9.716232 -62.261875)
				(end 9.75487 -62.37351)
			)
			(xy 9.758426 -62.391798) (xy 9.786366 -62.414912)
		)
		(stroke
			(width 0)
			(type solid)
		)
		(fill yes)
		(layer "B.Cu")
		(net "GND")
	)
	(gr_poly
		(pts
			(xy 16.861536 -253.462536)
			(arc
				(start 18.169382 -253.462536)
				(mid 18.188905 -253.458635)
				(end 18.20545 -253.44755)
			)
			(arc
				(start 18.323814 -253.329186)
				(mid 18.334925 -253.312652)
				(end 18.3388 -253.293118)
			)
			(arc
				(start 18.3388 -249.827796)
				(mid 18.333773 -249.805507)
				(end 18.319496 -249.787664)
			)
			(xy 18.247614 -249.731022) (xy 18.224754 -249.726196)
			(arc
				(start 18.213324 -249.72899)
				(mid 17.985579 -249.76988)
				(end 17.7546 -249.7836)
			)
			(arc
				(start 12.0396 -249.7836)
				(mid 12.003679 -249.798479)
				(end 11.9888 -249.8344)
			)
			(arc
				(start 11.9888 -253.343918)
				(mid 11.992701 -253.363441)
				(end 12.003786 -253.379986)
			)
			(arc
				(start 12.075414 -253.451614)
				(mid 12.091948 -253.462725)
				(end 12.111482 -253.4666)
			)
			(xy 16.857218 -253.4666)
		)
		(stroke
			(width 0)
			(type solid)
		)
		(fill yes)
		(layer "B.Cu")
		(net "GND")
	)
	(gr_poly
		(pts
			(arc
				(start 35.069018 -268.6939)
				(mid 35.088541 -268.689999)
				(end 35.105086 -268.678914)
			)
			(xy 38.769036 -265.014964) (xy 38.826694 -264.957306) (xy 39.209472 -264.957306) (xy 41.656 -264.957306)
			(xy 41.724072 -264.889234) (xy 41.724072 -263.532366) (xy 41.7322 -263.524238) (xy 41.87952 -263.376918)
			(xy 41.899078 -263.35736) (xy 44.68876 -263.35736) (xy 44.823888 -263.35736) (xy 44.86402 -263.317228)
			(xy 44.86402 -263.144) (xy 44.86402 -263.092692) (xy 44.823888 -263.05256) (xy 42.25544 -263.05256)
			(xy 39.210996 -263.05256) (xy 39.20871 -263.054846) (xy 39.119556 -263.144) (xy 38.869112 -263.394444)
			(xy 36.957 -263.394444) (xy 36.699444 -263.652) (xy 30.226 -263.652) (xy 30.0482 -263.8298)
			(arc
				(start 30.0482 -268.304518)
				(mid 30.052101 -268.324041)
				(end 30.063186 -268.340586)
			)
			(arc
				(start 30.401514 -268.678914)
				(mid 30.418048 -268.690025)
				(end 30.437582 -268.6939)
			)
		)
		(stroke
			(width 0)
			(type solid)
		)
		(fill yes)
		(layer "B.Cu")
		(net "P52V_HSC")
	)
	(gr_poly
		(pts
			(xy 48.140366 -61.970666) (xy 48.140366 -57.656222) (xy 47.939452 -57.455308)
			(arc
				(start 44.754038 -57.455308)
				(mid 44.734651 -57.451358)
				(end 44.718224 -57.440322)
			)
			(arc
				(start 44.645834 -57.368186)
				(mid 44.629417 -57.357124)
				(end 44.61002 -57.3532)
			)
			(arc
				(start 41.541954 -57.3532)
				(mid 41.522431 -57.357101)
				(end 41.505886 -57.368186)
			)
			(xy 40.431466 -58.442606) (xy 37.644832 -58.442606) (xy 37.610288 -58.47715) (xy 37.610288 -59.92241)
			(xy 37.490146 -60.042552) (xy 34.510472 -60.042552) (xy 34.47034 -60.082684)
			(arc
				(start 34.47034 -60.297314)
				(mid 34.482204 -60.329942)
				(end 34.51225 -60.347352)
			)
			(xy 40.117522 -60.347352) (xy 40.177212 -60.347352) (xy 40.491918 -60.032646) (xy 44.02328 -60.032646)
			(xy 44.665392 -60.674758) (xy 44.665392 -62.026546) (xy 44.834556 -62.19571) (xy 47.915322 -62.19571)
		)
		(stroke
			(width 0)
			(type solid)
		)
		(fill yes)
		(layer "B.Cu")
		(net "P52V_HSC")
	)
	(gr_poly
		(pts
			(xy 35.174428 -82.910172)
			(arc
				(start 35.174428 -82.397854)
				(mid 35.178329 -82.378331)
				(end 35.189414 -82.361786)
			)
			(arc
				(start 36.307014 -81.244186)
				(mid 36.323548 -81.233075)
				(end 36.343082 -81.2292)
			)
			(arc
				(start 38.00983 -81.2292)
				(mid 38.029353 -81.225299)
				(end 38.045898 -81.214214)
			)
			(xy 38.902894 -80.357218) (xy 41.6814 -80.357218) (xy 41.724072 -80.314546) (xy 41.724072 -78.932278)
			(xy 41.899078 -78.757272) (xy 44.823888 -78.757272) (xy 44.86402 -78.71714)
			(arc
				(start 44.86402 -78.50251)
				(mid 44.852156 -78.469882)
				(end 44.82211 -78.452472)
			)
			(xy 39.216838 -78.452472) (xy 39.193724 -78.452472) (xy 38.974776 -78.67142) (xy 38.848284 -78.797912)
			(xy 36.693094 -78.797912) (xy 36.46678 -79.024226) (xy 30.376368 -79.024226) (xy 30.1752 -79.225394)
			(xy 30.1752 -82.808826) (xy 30.558232 -83.191858) (xy 34.892742 -83.191858)
		)
		(stroke
			(width 0)
			(type solid)
		)
		(fill yes)
		(layer "B.Cu")
		(net "P52V_HSC")
	)
	(gr_poly
		(pts
			(xy 48.665638 -247.014492) (xy 48.665638 -242.02517) (xy 48.415956 -241.775488) (xy 44.820332 -241.775488)
			(xy 44.33062 -242.2652)
			(arc
				(start 42.01795 -242.2652)
				(mid 41.998427 -242.269101)
				(end 41.981882 -242.280186)
			)
			(xy 40.419528 -243.84254) (xy 37.644832 -243.84254) (xy 37.610288 -243.877084) (xy 37.610288 -245.322344)
			(xy 37.490146 -245.442486) (xy 34.510472 -245.442486) (xy 34.441384 -245.511574)
			(arc
				(start 34.441384 -245.712488)
				(mid 34.445285 -245.732011)
				(end 34.45637 -245.748556)
			)
			(arc
				(start 34.497772 -245.789958)
				(mid 34.503742 -245.795173)
				(end 34.510472 -245.799356)
			)
			(xy 34.510472 -245.747286) (xy 40.117522 -245.747286) (xy 41.531286 -245.747286) (xy 41.558972 -245.747286)
			(xy 41.594532 -245.782846) (xy 43.36796 -245.782846) (xy 43.39463 -245.809516) (xy 43.394884 -245.80977)
			(xy 43.890184 -246.304816)
			(arc
				(start 44.788582 -247.203214)
				(mid 44.805116 -247.214325)
				(end 44.82465 -247.2182)
			)
			(xy 48.46193 -247.2182)
		)
		(stroke
			(width 0)
			(type solid)
		)
		(fill yes)
		(layer "B.Cu")
		(net "P52V_HSC")
	)
	(gr_poly
		(pts
			(arc
				(start 35.869626 -261.746492)
				(mid 35.888983 -261.742659)
				(end 35.90544 -261.73176)
			)
			(arc
				(start 36.129214 -261.507986)
				(mid 36.140325 -261.491452)
				(end 36.1442 -261.471918)
			)
			(arc
				(start 36.1442 -257.170682)
				(mid 36.140299 -257.151159)
				(end 36.129214 -257.134614)
			)
			(arc
				(start 35.930586 -256.935986)
				(mid 35.914052 -256.924875)
				(end 35.894518 -256.921)
			)
			(arc
				(start 30.323282 -256.921)
				(mid 30.303759 -256.924901)
				(end 30.287214 -256.935986)
			)
			(arc
				(start 29.961586 -257.261614)
				(mid 29.950475 -257.278148)
				(end 29.9466 -257.297682)
			)
			(arc
				(start 29.9466 -261.471918)
				(mid 29.950501 -261.491441)
				(end 29.961586 -261.507986)
			)
			(arc
				(start 30.18536 -261.73176)
				(mid 30.201806 -261.742686)
				(end 30.221174 -261.746492)
			)
			(xy 32.281114 -261.746492) (xy 32.304228 -261.746492) (xy 33.093914 -261.746492) (xy 33.117028 -261.746492)
			(xy 33.855914 -261.746492) (xy 33.879028 -261.746492) (xy 33.902396 -261.746492)
		)
		(stroke
			(width 0)
			(type solid)
		)
		(fill yes)
		(layer "B.Cu")
		(net "GND")
	)
	(gr_poly
		(pts
			(xy 18.2372 -62.804294)
			(arc
				(start 18.2372 -58.390282)
				(mid 18.233299 -58.370759)
				(end 18.222214 -58.354214)
			)
			(arc
				(start 18.030698 -58.162698)
				(mid 18.014164 -58.151587)
				(end 17.99463 -58.147712)
			)
			(arc
				(start 9.329928 -58.147712)
				(mid 9.310405 -58.151613)
				(end 9.29386 -58.162698)
			)
			(xy 9.013952 -58.442606) (xy 6.227318 -58.442606) (xy 6.192774 -58.47715) (xy 6.192774 -59.92241)
			(xy 6.072632 -60.042552) (xy 3.076448 -60.042552) (xy 3.052826 -60.066174)
			(arc
				(start 3.052826 -60.297314)
				(mid 3.06469 -60.329942)
				(end 3.094736 -60.347352)
			)
			(xy 8.700008 -60.347352) (xy 8.709152 -60.347352) (xy 8.709914 -60.348114) (xy 8.968486 -60.348114)
			(xy 9.314688 -60.001912) (xy 9.591802 -60.001912) (xy 10.979912 -60.001912) (xy 11.464798 -60.001912)
			(xy 11.811 -60.348114) (xy 12.41806 -60.348114) (xy 12.615672 -60.545726) (xy 12.615672 -62.753494)
			(xy 12.796012 -62.933834) (xy 18.10766 -62.933834)
		)
		(stroke
			(width 0)
			(type solid)
		)
		(fill yes)
		(layer "B.Cu")
		(net "P52V_HSC")
	)
	(gr_poly
		(pts
			(arc
				(start 49.508918 -253.7968)
				(mid 49.528441 -253.792899)
				(end 49.544986 -253.781814)
			)
			(arc
				(start 49.896014 -253.430786)
				(mid 49.907125 -253.414252)
				(end 49.911 -253.394718)
			)
			(arc
				(start 49.911 -250.084082)
				(mid 49.907099 -250.064559)
				(end 49.896014 -250.048014)
			)
			(xy 49.89322 -250.04522) (xy 49.8856 -250.026678)
			(arc
				(start 49.8856 -249.476768)
				(mid 49.881699 -249.457245)
				(end 49.870614 -249.4407)
			)
			(arc
				(start 49.613312 -249.183398)
				(mid 49.596778 -249.172287)
				(end 49.577244 -249.168412)
			)
			(arc
				(start 43.993562 -249.168412)
				(mid 43.974039 -249.172313)
				(end 43.957494 -249.183398)
			)
			(arc
				(start 43.677586 -249.463306)
				(mid 43.666475 -249.47984)
				(end 43.6626 -249.499374)
			)
			(xy 43.6626 -252.007878) (xy 43.67022 -252.02642) (xy 43.6753 -252.0315)
			(arc
				(start 43.6753 -253.534418)
				(mid 43.679201 -253.553941)
				(end 43.690286 -253.570486)
			)
			(arc
				(start 43.901614 -253.781814)
				(mid 43.918148 -253.792925)
				(end 43.937682 -253.7968)
			)
		)
		(stroke
			(width 0)
			(type solid)
		)
		(fill yes)
		(layer "B.Cu")
		(net "GND")
	)
	(gr_poly
		(pts
			(arc
				(start 49.483518 -68.8086)
				(mid 49.503041 -68.804699)
				(end 49.519586 -68.793614)
			)
			(arc
				(start 49.692814 -68.620386)
				(mid 49.703925 -68.603852)
				(end 49.7078 -68.584318)
			)
			(arc
				(start 49.7078 -64.232282)
				(mid 49.703899 -64.212759)
				(end 49.692814 -64.196214)
			)
			(arc
				(start 49.443386 -63.946786)
				(mid 49.426852 -63.935675)
				(end 49.407318 -63.9318)
			)
			(arc
				(start 48.895 -63.9318)
				(mid 48.875477 -63.935701)
				(end 48.858932 -63.946786)
			)
			(arc
				(start 48.719486 -64.086232)
				(mid 48.702923 -64.097206)
				(end 48.683418 -64.100964)
			)
			(arc
				(start 44.06646 -64.100964)
				(mid 44.046966 -64.09718)
				(end 44.030392 -64.086232)
			)
			(arc
				(start 43.890946 -63.946786)
				(mid 43.874412 -63.935675)
				(end 43.854878 -63.9318)
			)
			(arc
				(start 43.810682 -63.9318)
				(mid 43.791159 -63.935701)
				(end 43.774614 -63.946786)
			)
			(arc
				(start 43.448986 -64.272414)
				(mid 43.437875 -64.288948)
				(end 43.434 -64.308482)
			)
			(arc
				(start 43.434 -68.635118)
				(mid 43.437901 -68.654641)
				(end 43.448986 -68.671186)
			)
			(arc
				(start 43.571414 -68.793614)
				(mid 43.587948 -68.804725)
				(end 43.607482 -68.8086)
			)
		)
		(stroke
			(width 0)
			(type solid)
		)
		(fill yes)
		(layer "B.Cu")
		(net "GND")
	)
	(gr_poly
		(pts
			(xy 5.607558 -244.125242) (xy 5.607558 -243.566442) (xy 5.607558 -242.702842) (xy 5.762752 -242.547648)
			(xy 8.709152 -242.547648) (xy 8.7376 -242.5192) (xy 8.7376 -241.45494) (xy 8.79348 -241.39906) (xy 9.09574 -241.0968)
			(xy 17.5006 -241.0968) (xy 17.8054 -240.792) (xy 17.8054 -218.469718) (xy 15.69339 -216.357708) (xy 15.69339 -214.25789)
			(xy 16.406368 -213.544912) (xy 16.45031 -213.544912) (xy 16.463518 -213.529672) (xy 16.461994 -213.489794)
			(xy 16.156178 -213.183978) (xy 16.133318 -213.176358)
			(arc
				(start 16.12138 -213.178136)
				(mid 15.962559 -213.195844)
				(end 15.802864 -213.201758)
			)
			(arc
				(start 15.802864 -213.201758)
				(mid 14.951629 -213.026909)
				(end 14.238224 -212.53069)
			)
			(xy 14.229842 -212.5218) (xy 14.20622 -212.513672)
			(arc
				(start 14.123924 -212.526118)
				(mid 14.112344 -212.529245)
				(end 14.101826 -212.535008)
			)
			(xy 14.078966 -212.551518) (xy 14.071092 -212.560408)
			(arc
				(start 14.068298 -212.565996)
				(mid 13.272612 -213.426649)
				(end 12.144502 -213.74481)
			)
			(arc
				(start 12.144502 -213.74481)
				(mid 11.252938 -213.55206)
				(end 10.520426 -213.008464)
			)
			(xy 10.513822 -213.001098)
			(arc
				(start 10.488168 -212.988144)
				(mid 10.479012 -212.984713)
				(end 10.469372 -212.983064)
			)
			(xy 10.408412 -212.978238)
			(arc
				(start 10.405364 -212.977984)
				(mid 10.387359 -212.980994)
				(end 10.371582 -212.990176)
			)
			(arc
				(start 10.371582 -212.990176)
				(mid 9.589903 -213.443743)
				(end 8.700008 -213.6013)
			)
			(arc
				(start 8.699754 -213.6013)
				(mid 8.200148 -213.552632)
				(end 7.719314 -213.408514)
			)
			(xy 7.709916 -213.404704) (xy 7.690104 -213.404704)
			(arc
				(start 7.680706 -213.408514)
				(mid 7.199864 -213.552592)
				(end 6.700266 -213.6013)
			)
			(arc
				(start 6.700012 -213.6013)
				(mid 4.867681 -212.842323)
				(end 4.108704 -211.009992)
			)
			(arc
				(start 4.108704 -211.009738)
				(mid 4.157372 -210.510132)
				(end 4.30149 -210.029298)
			)
			(xy 4.3053 -210.0199) (xy 4.3053 -210.000088)
			(arc
				(start 4.30149 -209.99069)
				(mid 4.157412 -209.509848)
				(end 4.108704 -209.01025)
			)
			(arc
				(start 4.108704 -209.009996)
				(mid 4.332348 -207.95683)
				(end 4.964684 -207.085438)
			)
			(xy 4.972812 -207.078072) (xy 4.981448 -207.058514) (xy 4.981448 -206.961486) (xy 4.972812 -206.941928)
			(arc
				(start 4.964684 -206.934562)
				(mid 4.332353 -206.063168)
				(end 4.108704 -205.010004)
			)
			(arc
				(start 4.108704 -205.00975)
				(mid 4.157372 -204.510144)
				(end 4.30149 -204.02931)
			)
			(xy 4.3053 -204.019912) (xy 4.3053 -204.0001)
			(arc
				(start 4.30149 -203.990702)
				(mid 4.157387 -203.509736)
				(end 4.108704 -203.010008)
			)
			(arc
				(start 4.108704 -203.009754)
				(mid 4.157348 -202.510018)
				(end 4.30149 -202.02906)
			)
			(arc
				(start 4.302506 -202.026266)
				(mid 4.305182 -202.009608)
				(end 4.302252 -201.992992)
			)
			(xy 4.30149 -201.990706)
			(arc
				(start 4.29006 -201.962258)
				(mid 4.271406 -201.938866)
				(end 4.242816 -201.93)
			)
			(arc
				(start 3.091434 -201.93)
				(mid 3.071911 -201.933901)
				(end 3.055366 -201.944986)
			)
			(xy 2.935986 -202.064366) (xy 2.92862 -202.071478) (xy 2.921 -202.090274) (xy 2.921 -205.822296)
			(xy 2.922778 -205.91145) (xy 2.921 -206.000604) (xy 2.921 -210.902296) (xy 2.922778 -210.99145) (xy 2.921 -211.080604)
			(xy 2.921 -215.232234) (xy 7.326122 -219.637356)
			(arc
				(start 7.326122 -220.125036)
				(mid 7.337233 -220.14157)
				(end 7.341108 -220.161104)
			)
			(arc
				(start 7.341108 -227.945696)
				(mid 7.338024 -227.963127)
				(end 7.32917 -227.978462)
			)
			(xy 6.49478 -228.812852) (xy 6.485128 -228.822504) (xy 6.485128 -235.962952) (xy 5.45084 -236.99724)
			(xy 5.45084 -239.50422) (xy 4.84886 -240.1062) (xy 3.24612 -240.1062) (xy 3.045714 -240.306606) (xy 3.045714 -244.122194)
			(xy 3.071114 -244.147594) (xy 5.585206 -244.147594)
		)
		(stroke
			(width 0)
			(type solid)
		)
		(fill yes)
		(layer "B.Cu")
		(net "P52V_FAN_6")
	)
	(gr_poly
		(pts
			(arc
				(start 47.69993 -336.492088)
				(mid 50.169141 -335.469307)
				(end 51.191922 -333.000096)
			)
			(arc
				(start 51.191922 -3.999992)
				(mid 50.169141 -1.530781)
				(end 47.69993 -0.508)
			)
			(xy 36.950396 -0.508) (xy 35.74796 -1.710436)
			(arc
				(start 35.74796 -10.999978)
				(mid 35.246291 -12.209079)
				(end 34.036 -12.707874)
			)
			(arc
				(start 34.036 -13.21562)
				(mid 35.605325 -12.568112)
				(end 36.255706 -10.999978)
			)
			(xy 36.255706 -1.920748) (xy 37.160708 -1.015746)
			(arc
				(start 47.69993 -1.015746)
				(mid 49.810111 -1.889811)
				(end 50.684176 -3.999992)
			)
			(arc
				(start 50.684176 -333.000096)
				(mid 49.810111 -335.110277)
				(end 47.69993 -335.984342)
			)
			(arc
				(start 3.999992 -335.984342)
				(mid 1.889811 -335.110277)
				(end 1.015746 -333.000096)
			)
			(arc
				(start 1.015746 -3.999992)
				(mid 1.889811 -1.889811)
				(end 3.999992 -1.015746)
			)
			(xy 14.539214 -1.015746) (xy 15.444216 -1.920748)
			(arc
				(start 15.444216 -10.999978)
				(mid 16.09074 -12.564247)
				(end 17.653 -13.21562)
			)
			(arc
				(start 17.653 -12.707874)
				(mid 16.449761 -12.205225)
				(end 15.951962 -10.999978)
			)
			(xy 15.951962 -1.710436) (xy 14.749526 -0.508)
			(arc
				(start 3.999992 -0.508)
				(mid 1.530781 -1.530781)
				(end 0.508 -3.999992)
			)
			(arc
				(start 0.508 -333.000096)
				(mid 1.530781 -335.469307)
				(end 3.999992 -336.492088)
			)
		)
		(stroke
			(width 0)
			(type solid)
		)
		(fill yes)
		(layer "B.Cu")
		(net "GND")
	)
	(gr_poly
		(pts
			(arc
				(start 48.727868 -298.5516)
				(mid 48.763789 -298.536721)
				(end 48.778668 -298.5008)
			)
			(xy 48.778668 -297.034458) (xy 48.776636 -296.941748) (xy 48.776636 -296.940224) (xy 48.778668 -296.847514)
			(xy 48.778668 -291.954458) (xy 48.776636 -291.861748) (xy 48.776636 -291.860224) (xy 48.778668 -291.767514)
			(xy 48.778668 -286.874458) (xy 48.776636 -286.781748) (xy 48.776636 -286.780224) (xy 48.778668 -286.687514)
			(xy 48.778668 -281.794458) (xy 48.776636 -281.701748) (xy 48.776636 -281.700224) (xy 48.778668 -281.607514)
			(xy 48.778668 -276.714458) (xy 48.776636 -276.621748) (xy 48.776636 -276.620224) (xy 48.778668 -276.527514)
			(arc
				(start 48.778668 -275.361908)
				(mid 48.763789 -275.325987)
				(end 48.727868 -275.311108)
			)
			(arc
				(start 45.156628 -275.311108)
				(mid 44.40762 -275.161938)
				(end 43.772836 -274.737322)
			)
			(arc
				(start 43.651678 -274.616164)
				(mid 43.227107 -273.981361)
				(end 43.077892 -273.232372)
			)
			(xy 43.077892 -268.773148) (xy 44.84878 -267.00226) (xy 44.871132 -266.979908) (xy 44.871132 -266.58824)
			(xy 44.871132 -265.3538) (xy 44.871132 -263.892792) (xy 44.84878 -263.87044) (xy 44.830746 -263.852406)
			(xy 44.823888 -263.852406) (xy 42.343832 -263.852406) (xy 42.309288 -263.88695) (xy 42.309288 -265.33221)
			(xy 42.189146 -265.452352) (xy 39.209472 -265.452352) (xy 39.182548 -265.452352) (xy 39.1541 -265.4808)
			(xy 39.02202 -265.61288) (xy 39.02202 -267.456412)
			(arc
				(start 36.453064 -270.025622)
				(mid 36.131824 -270.285384)
				(end 35.7632 -270.4719)
			)
			(xy 35.756088 -270.474694) (xy 35.74415 -270.484092) (xy 35.726116 -270.51) (xy 35.67684 -270.51)
			(xy 35.55492 -270.63192) (xy 34.6964 -270.63192) (xy 34.544 -270.78432) (xy 34.544 -270.8402) (xy 34.544 -272.48612)
			(xy 34.5059 -272.52422) (xy 34.3408 -272.68932) (xy 34.3408 -281.6606) (xy 34.406332 -281.726132)
			(arc
				(start 34.415984 -281.729942)
				(mid 35.153426 -282.219574)
				(end 35.643058 -282.957016)
			)
			(xy 35.646868 -282.966668)
			(arc
				(start 38.636194 -285.955994)
				(mid 38.647305 -285.972528)
				(end 38.65118 -285.992062)
			)
			(xy 38.65118 -297.6372) (xy 38.72738 -297.7134) (xy 39.3954 -297.7134) (xy 39.47287 -297.63593) (xy 39.4716 -297.562016)
			(arc
				(start 39.4716 -297.561)
				(mid 39.966911 -296.17578)
				(end 41.228264 -295.418764)
			)
			(xy 41.264586 -295.38549) (xy 41.272714 -295.378124) (xy 41.28135 -295.358566) (xy 41.28135 -295.261538)
			(xy 41.272714 -295.24198)
			(arc
				(start 41.264586 -295.234614)
				(mid 40.632255 -294.36322)
				(end 40.408606 -293.310056)
			)
			(arc
				(start 40.408606 -293.309802)
				(mid 40.457274 -292.810196)
				(end 40.601392 -292.329362)
			)
			(xy 40.605202 -292.319964) (xy 40.605202 -292.300152)
			(arc
				(start 40.601392 -292.290754)
				(mid 40.457289 -291.809788)
				(end 40.408606 -291.31006)
			)
			(arc
				(start 40.408606 -291.31006)
				(mid 40.45725 -290.810324)
				(end 40.601392 -290.329366)
			)
			(xy 40.605202 -290.319968) (xy 40.605202 -290.300156)
			(arc
				(start 40.601392 -290.290758)
				(mid 40.457314 -289.809916)
				(end 40.408606 -289.310318)
			)
			(arc
				(start 40.408606 -289.310064)
				(mid 41.167583 -287.477733)
				(end 42.999914 -286.718756)
			)
			(arc
				(start 43.000168 -286.718756)
				(mid 43.499774 -286.767424)
				(end 43.980608 -286.911542)
			)
			(xy 43.990006 -286.915352) (xy 44.009818 -286.915352)
			(arc
				(start 44.019216 -286.911542)
				(mid 44.500058 -286.767464)
				(end 44.999656 -286.718756)
			)
			(arc
				(start 44.99991 -286.718756)
				(mid 46.832241 -287.477733)
				(end 47.591218 -289.310064)
			)
			(arc
				(start 47.591218 -289.310318)
				(mid 47.54255 -289.809924)
				(end 47.398432 -290.290758)
			)
			(xy 47.394622 -290.300156) (xy 47.394622 -290.319968)
			(arc
				(start 47.398432 -290.329366)
				(mid 47.54251 -290.810208)
				(end 47.591218 -291.309806)
			)
			(arc
				(start 47.591218 -291.31006)
				(mid 47.367574 -292.363226)
				(end 46.735238 -293.234618)
			)
			(xy 46.72711 -293.241984) (xy 46.718474 -293.261542) (xy 46.718474 -293.35857) (xy 46.72711 -293.378128)
			(arc
				(start 46.735238 -293.385494)
				(mid 47.367569 -294.256888)
				(end 47.591218 -295.310052)
			)
			(arc
				(start 47.591218 -295.310306)
				(mid 47.54255 -295.809912)
				(end 47.398432 -296.290746)
			)
			(xy 47.394622 -296.300144) (xy 47.394622 -296.319956)
			(arc
				(start 47.398432 -296.329354)
				(mid 47.542535 -296.81032)
				(end 47.591218 -297.310048)
			)
			(arc
				(start 47.591218 -297.310048)
				(mid 47.542574 -297.809784)
				(end 47.398432 -298.290742)
			)
			(xy 47.394622 -298.30014) (xy 47.394622 -298.320206)
			(arc
				(start 47.398432 -298.32935)
				(mid 47.434263 -298.422168)
				(end 47.466504 -298.516294)
			)
			(arc
				(start 47.466504 -298.516294)
				(mid 47.483281 -298.540523)
				(end 47.5107 -298.551346)
			)
			(xy 47.515018 -298.5516)
		)
		(stroke
			(width 0)
			(type solid)
		)
		(fill yes)
		(layer "B.Cu")
		(net "P52V_FAN_0")
	)
	(gr_poly
		(pts
			(xy 5.607558 -59.477148) (xy 5.607558 -58.122566) (xy 5.782564 -57.94756) (xy 5.8928 -57.94756) (xy 8.707374 -57.94756)
			(xy 8.72998 -57.94756) (xy 8.8265 -57.85104) (xy 8.8265 -56.97982) (xy 9.564116 -56.242204) (xy 17.798796 -56.242204)
			(xy 18.161 -55.88) (xy 18.161 -38.64102) (xy 13.4239 -33.90392)
			(arc
				(start 13.4239 -31.303976)
				(mid 13.412789 -31.287442)
				(end 13.408914 -31.267908)
			)
			(arc
				(start 13.408914 -29.742638)
				(mid 13.404895 -29.723086)
				(end 13.393674 -29.70657)
			)
			(arc
				(start 13.393674 -29.70657)
				(mid 12.750173 -28.1686)
				(end 13.393674 -26.63063)
			)
			(arc
				(start 13.393674 -26.63063)
				(mid 13.404923 -26.614126)
				(end 13.408914 -26.594562)
			)
			(arc
				(start 13.408914 -22.20087)
				(mid 13.40808 -22.191704)
				(end 13.405612 -22.182836)
			)
			(arc
				(start 13.405612 -22.182836)
				(mid 13.295424 -21.790544)
				(end 13.258292 -21.384768)
			)
			(arc
				(start 13.258292 -21.383752)
				(mid 13.270161 -21.15419)
				(end 13.305536 -20.92706)
			)
			(arc
				(start 13.305536 -20.92706)
				(mid 13.306611 -20.914018)
				(end 13.304266 -20.901152)
			)
			(arc
				(start 13.304266 -20.901152)
				(mid 13.227094 -20.575594)
				(end 13.201142 -20.242022)
			)
			(arc
				(start 13.201142 -20.241768)
				(mid 13.252501 -19.773572)
				(end 13.404088 -19.327622)
			)
			(arc
				(start 13.404088 -19.327622)
				(mid 13.407686 -19.317092)
				(end 13.408914 -19.306032)
			)
			(arc
				(start 13.408914 -17.824196)
				(mid 13.405013 -17.804673)
				(end 13.393928 -17.788128)
			)
			(arc
				(start 12.994386 -17.388586)
				(mid 12.977852 -17.377475)
				(end 12.958318 -17.3736)
			)
			(arc
				(start 11.225276 -17.3736)
				(mid 11.201742 -17.37938)
				(end 11.18362 -17.395444)
			)
			(xy 11.128756 -17.474184) (xy 11.125708 -17.498568)
			(arc
				(start 11.13028 -17.510506)
				(mid 11.250715 -17.952936)
				(end 11.291316 -18.409666)
			)
			(arc
				(start 11.291316 -18.40992)
				(mid 11.067672 -19.463086)
				(end 10.435336 -20.334478)
			)
			(arc
				(start 10.435082 -20.334478)
				(mid 10.422874 -20.351408)
				(end 10.418572 -20.371816)
			)
			(arc
				(start 10.418572 -20.448016)
				(mid 10.422948 -20.468391)
				(end 10.435082 -20.485354)
			)
			(arc
				(start 10.435336 -20.485354)
				(mid 11.067667 -21.356748)
				(end 11.291316 -22.409912)
			)
			(arc
				(start 11.291316 -22.410166)
				(mid 11.242648 -22.909772)
				(end 11.09853 -23.390606)
			)
			(arc
				(start 11.09853 -23.390606)
				(mid 11.094719 -23.40991)
				(end 11.09853 -23.429214)
			)
			(arc
				(start 11.09853 -23.429214)
				(mid 11.242633 -23.91018)
				(end 11.291316 -24.409908)
			)
			(arc
				(start 11.291316 -24.409908)
				(mid 11.242672 -24.909644)
				(end 11.09853 -25.390602)
			)
			(arc
				(start 11.09853 -25.390602)
				(mid 11.094719 -25.409906)
				(end 11.09853 -25.42921)
			)
			(arc
				(start 11.09853 -25.42921)
				(mid 11.242608 -25.910052)
				(end 11.291316 -26.40965)
			)
			(arc
				(start 11.291316 -26.409904)
				(mid 10.532339 -28.242235)
				(end 8.700008 -29.001212)
			)
			(arc
				(start 8.699754 -29.001212)
				(mid 8.200148 -28.952544)
				(end 7.719314 -28.808426)
			)
			(arc
				(start 7.719314 -28.808426)
				(mid 7.70001 -28.804615)
				(end 7.680706 -28.808426)
			)
			(arc
				(start 7.680706 -28.808426)
				(mid 7.199864 -28.952504)
				(end 6.700266 -29.001212)
			)
			(arc
				(start 6.700012 -29.001212)
				(mid 4.867681 -28.242235)
				(end 4.108704 -26.409904)
			)
			(arc
				(start 4.108704 -26.40965)
				(mid 4.157372 -25.910044)
				(end 4.30149 -25.42921)
			)
			(arc
				(start 4.30149 -25.42921)
				(mid 4.305301 -25.409906)
				(end 4.30149 -25.390602)
			)
			(arc
				(start 4.30149 -25.390602)
				(mid 4.157412 -24.90976)
				(end 4.108704 -24.410162)
			)
			(arc
				(start 4.108704 -24.409908)
				(mid 4.332348 -23.356742)
				(end 4.964684 -22.48535)
			)
			(arc
				(start 4.964938 -22.48535)
				(mid 4.977197 -22.468303)
				(end 4.981448 -22.447758)
			)
			(arc
				(start 4.981448 -22.372066)
				(mid 4.977123 -22.351554)
				(end 4.964938 -22.334474)
			)
			(arc
				(start 4.964684 -22.334474)
				(mid 4.332353 -21.46308)
				(end 4.108704 -20.409916)
			)
			(arc
				(start 4.108704 -20.409662)
				(mid 4.157372 -19.910056)
				(end 4.30149 -19.429222)
			)
			(arc
				(start 4.30149 -19.429222)
				(mid 4.305301 -19.409918)
				(end 4.30149 -19.390614)
			)
			(arc
				(start 4.30149 -19.390614)
				(mid 4.157387 -18.909648)
				(end 4.108704 -18.40992)
			)
			(arc
				(start 4.108704 -18.409666)
				(mid 4.149273 -17.95293)
				(end 4.26974 -17.510506)
			)
			(xy 4.274312 -17.498568) (xy 4.271264 -17.474184)
			(arc
				(start 4.2164 -17.395444)
				(mid 4.198246 -17.379441)
				(end 4.174744 -17.3736)
			)
			(arc
				(start 3.3401 -17.3736)
				(mid 3.320577 -17.377501)
				(end 3.304032 -17.388586)
			)
			(arc
				(start 2.935986 -17.756632)
				(mid 2.924875 -17.773166)
				(end 2.921 -17.7927)
			)
			(xy 2.921 -17.867122) (xy 2.921254 -17.867884) (xy 2.922778 -17.95145) (xy 2.921254 -18.035016) (xy 2.921 -18.035778)
			(xy 2.921 -22.947122) (xy 2.921254 -22.947884) (xy 2.922778 -23.03145) (xy 2.921254 -23.115016) (xy 2.921 -23.115778)
			(xy 2.921 -28.027122) (xy 2.921254 -28.027884) (xy 2.922778 -28.11145) (xy 2.921254 -28.195016) (xy 2.921 -28.195778)
			(xy 2.921 -33.107122) (xy 2.921254 -33.107884) (xy 2.922778 -33.19145) (xy 2.921254 -33.275016) (xy 2.921 -33.275778)
			(xy 2.921 -34.73704) (xy 7.0104 -38.82644) (xy 7.0104 -51.3207) (xy 6.1976 -52.1335) (xy 5.931154 -52.399946)
			(xy 5.931154 -54.579266) (xy 5.92074 -54.58968) (xy 5.12064 -55.38978) (xy 3.030728 -55.38978) (xy 2.985262 -55.435246)
			(xy 2.985262 -59.485022) (xy 3.047746 -59.547506) (xy 3.092958 -59.547506) (xy 5.5372 -59.547506)
		)
		(stroke
			(width 0)
			(type solid)
		)
		(fill yes)
		(layer "B.Cu")
		(net "P52V_FAN_4")
	)
	(gr_poly
		(pts
			(xy 37.025072 -59.504834) (xy 37.025072 -58.122566) (xy 37.200078 -57.94756) (xy 40.124888 -57.94756)
			(xy 40.18026 -57.892188)
			(arc
				(start 40.18026 -55.99938)
				(mid 40.53813 -55.724862)
				(end 40.949372 -55.53964)
			)
			(xy 44.25188 -55.53964) (xy 44.2976 -55.49392) (xy 44.2976 -55.4736) (xy 44.2976 -54.2036) (xy 43.815 -53.721)
			(xy 43.815 -46.10354) (xy 43.7896 -46.07814) (xy 43.29176 -45.5803)
			(arc
				(start 43.29176 -40.532812)
				(mid 43.296706 -40.522767)
				(end 43.303698 -40.514016)
			)
			(xy 48.778668 -35.039046)
			(arc
				(start 48.778668 -32.875474)
				(mid 48.777134 -32.828241)
				(end 48.776636 -32.780986)
			)
			(arc
				(start 48.776636 -32.780986)
				(mid 48.777136 -32.733731)
				(end 48.778668 -32.686498)
			)
			(arc
				(start 48.778668 -27.795474)
				(mid 48.777134 -27.748241)
				(end 48.776636 -27.700986)
			)
			(arc
				(start 48.776636 -27.700986)
				(mid 48.777136 -27.653731)
				(end 48.778668 -27.606498)
			)
			(arc
				(start 48.778668 -22.715474)
				(mid 48.777134 -22.668241)
				(end 48.776636 -22.620986)
			)
			(arc
				(start 48.776636 -22.620986)
				(mid 48.777136 -22.573731)
				(end 48.778668 -22.526498)
			)
			(arc
				(start 48.778668 -17.635474)
				(mid 48.777134 -17.588241)
				(end 48.776636 -17.540986)
			)
			(arc
				(start 48.776636 -17.540986)
				(mid 48.777136 -17.493731)
				(end 48.778668 -17.446498)
			)
			(arc
				(start 48.778668 -15.13713)
				(mid 48.774884 -15.117636)
				(end 48.763936 -15.101062)
			)
			(arc
				(start 48.590708 -14.927834)
				(mid 48.574174 -14.916723)
				(end 48.55464 -14.912848)
			)
			(arc
				(start 47.58309 -14.912848)
				(mid 47.551308 -14.924222)
				(end 47.53356 -14.95298)
			)
			(arc
				(start 47.53356 -14.95298)
				(mid 47.243382 -15.706712)
				(end 46.735238 -16.334486)
			)
			(arc
				(start 46.734984 -16.334486)
				(mid 46.722776 -16.351416)
				(end 46.718474 -16.371824)
			)
			(arc
				(start 46.718474 -16.448024)
				(mid 46.72285 -16.468399)
				(end 46.734984 -16.485362)
			)
			(arc
				(start 46.735238 -16.485362)
				(mid 47.367569 -17.356756)
				(end 47.591218 -18.40992)
			)
			(arc
				(start 47.591218 -18.410174)
				(mid 47.54255 -18.90978)
				(end 47.398432 -19.390614)
			)
			(arc
				(start 47.398432 -19.390614)
				(mid 47.394621 -19.409918)
				(end 47.398432 -19.429222)
			)
			(arc
				(start 47.398432 -19.429222)
				(mid 47.542535 -19.910188)
				(end 47.591218 -20.409916)
			)
			(arc
				(start 47.591218 -20.409916)
				(mid 47.542574 -20.909652)
				(end 47.398432 -21.39061)
			)
			(arc
				(start 47.398432 -21.39061)
				(mid 47.394621 -21.409914)
				(end 47.398432 -21.429218)
			)
			(arc
				(start 47.398432 -21.429218)
				(mid 47.542535 -21.910184)
				(end 47.591218 -22.409912)
			)
			(arc
				(start 47.591218 -22.409912)
				(mid 47.542574 -22.909648)
				(end 47.398432 -23.390606)
			)
			(arc
				(start 47.398432 -23.390606)
				(mid 47.394621 -23.40991)
				(end 47.398432 -23.429214)
			)
			(arc
				(start 47.398432 -23.429214)
				(mid 47.542535 -23.91018)
				(end 47.591218 -24.409908)
			)
			(arc
				(start 47.591218 -24.409908)
				(mid 47.56743 -24.760219)
				(end 47.496476 -25.10409)
			)
			(arc
				(start 47.496476 -25.10409)
				(mid 47.494675 -25.118757)
				(end 47.497238 -25.1333)
			)
			(arc
				(start 47.497238 -25.1333)
				(mid 47.567384 -25.424623)
				(end 47.590964 -25.723342)
			)
			(arc
				(start 47.590964 -27.095704)
				(mid 47.032943 -28.443012)
				(end 45.68571 -29.001212)
			)
			(arc
				(start 45.077888 -29.001212)
				(mid 45.054339 -29.007133)
				(end 45.036232 -29.02331)
			)
			(arc
				(start 45.036232 -29.02331)
				(mid 43.999355 -29.567796)
				(end 42.963084 -29.02204)
			)
			(arc
				(start 42.963084 -29.02204)
				(mid 42.945534 -29.006168)
				(end 42.922698 -28.999942)
			)
			(arc
				(start 42.922698 -28.999942)
				(mid 41.140567 -28.214645)
				(end 40.408606 -26.409904)
			)
			(arc
				(start 40.408606 -26.40965)
				(mid 40.457274 -25.910044)
				(end 40.601392 -25.42921)
			)
			(arc
				(start 40.601392 -25.42921)
				(mid 40.605203 -25.409906)
				(end 40.601392 -25.390602)
			)
			(arc
				(start 40.601392 -25.390602)
				(mid 40.457289 -24.909636)
				(end 40.408606 -24.409908)
			)
			(arc
				(start 40.408606 -24.409908)
				(mid 40.45725 -23.910172)
				(end 40.601392 -23.429214)
			)
			(arc
				(start 40.601392 -23.429214)
				(mid 40.605203 -23.40991)
				(end 40.601392 -23.390606)
			)
			(arc
				(start 40.601392 -23.390606)
				(mid 40.457289 -22.90964)
				(end 40.408606 -22.409912)
			)
			(arc
				(start 40.408606 -22.409912)
				(mid 40.45725 -21.910176)
				(end 40.601392 -21.429218)
			)
			(arc
				(start 40.601392 -21.429218)
				(mid 40.605203 -21.409914)
				(end 40.601392 -21.39061)
			)
			(arc
				(start 40.601392 -21.39061)
				(mid 40.457314 -20.909768)
				(end 40.408606 -20.41017)
			)
			(arc
				(start 40.408606 -20.409916)
				(mid 40.63225 -19.35675)
				(end 41.264586 -18.485358)
			)
			(arc
				(start 41.26484 -18.485358)
				(mid 41.277048 -18.468428)
				(end 41.28135 -18.44802)
			)
			(arc
				(start 41.28135 -18.37182)
				(mid 41.276974 -18.351445)
				(end 41.26484 -18.334482)
			)
			(arc
				(start 41.264586 -18.334482)
				(mid 41.007435 -18.066864)
				(end 40.79113 -17.765268)
			)
			(xy 39.751 -17.765268)
			(arc
				(start 38.284912 -19.231356)
				(mid 38.269307 -19.332476)
				(end 38.249098 -19.432778)
			)
			(arc
				(start 38.249098 -19.432778)
				(mid 38.248022 -19.448093)
				(end 38.251638 -19.463004)
			)
			(arc
				(start 38.251638 -19.463004)
				(mid 38.371652 -19.863626)
				(end 38.412166 -20.279868)
			)
			(arc
				(start 38.412166 -20.279868)
				(mid 38.367936 -20.714467)
				(end 38.23716 -21.131276)
			)
			(arc
				(start 38.23716 -21.131276)
				(mid 38.234151 -21.14098)
				(end 38.233096 -21.151088)
			)
			(arc
				(start 38.233096 -23.00478)
				(mid 38.234113 -23.014896)
				(end 38.23716 -23.024592)
			)
			(arc
				(start 38.23716 -23.024592)
				(mid 38.367939 -23.441401)
				(end 38.412166 -23.876)
			)
			(arc
				(start 38.412166 -23.876)
				(mid 38.367931 -24.310596)
				(end 38.23716 -24.727408)
			)
			(xy 38.233096 -24.73706) (xy 38.233096 -25.329896)
			(arc
				(start 38.237414 -25.339548)
				(mid 38.381855 -25.784049)
				(end 38.430708 -26.248868)
			)
			(arc
				(start 38.430708 -26.248868)
				(mid 38.381823 -26.713556)
				(end 38.237414 -27.157934)
			)
			(arc
				(start 38.237414 -27.157934)
				(mid 38.234137 -27.168118)
				(end 38.233096 -27.178762)
			)
			(arc
				(start 38.233096 -29.12999)
				(mid 38.229195 -29.149513)
				(end 38.21811 -29.166058)
			)
			(xy 38.213284 -29.170884) (xy 38.213284 -33.922716) (xy 33.401 -38.735) (xy 33.401 -59.32678) (xy 33.621726 -59.547506)
			(xy 36.9824 -59.547506)
		)
		(stroke
			(width 0)
			(type solid)
		)
		(fill yes)
		(layer "B.Cu")
		(net "P52V_FAN_3")
	)
	(gr_poly
		(pts
			(arc
				(start 40.513 -113.8682)
				(mid 40.54233 -113.859057)
				(end 40.561006 -113.834672)
			)
			(arc
				(start 40.561006 -113.834672)
				(mid 40.580627 -113.781748)
				(end 40.601392 -113.729262)
			)
			(arc
				(start 40.601392 -113.729262)
				(mid 40.605203 -113.709958)
				(end 40.601392 -113.690654)
			)
			(arc
				(start 40.601392 -113.690654)
				(mid 40.457314 -113.209812)
				(end 40.408606 -112.710214)
			)
			(arc
				(start 40.408606 -112.70996)
				(mid 40.63225 -111.656794)
				(end 41.264586 -110.785402)
			)
			(arc
				(start 41.26484 -110.785402)
				(mid 41.277048 -110.768472)
				(end 41.28135 -110.748064)
			)
			(arc
				(start 41.28135 -110.671864)
				(mid 41.276974 -110.651489)
				(end 41.26484 -110.634526)
			)
			(arc
				(start 41.264586 -110.634526)
				(mid 40.632255 -109.763132)
				(end 40.408606 -108.709968)
			)
			(arc
				(start 40.408606 -108.709714)
				(mid 40.457274 -108.210108)
				(end 40.601392 -107.729274)
			)
			(arc
				(start 40.601392 -107.729274)
				(mid 40.605203 -107.70997)
				(end 40.601392 -107.690666)
			)
			(arc
				(start 40.601392 -107.690666)
				(mid 40.457289 -107.2097)
				(end 40.408606 -106.709972)
			)
			(arc
				(start 40.408606 -106.709972)
				(mid 40.45725 -106.210236)
				(end 40.601392 -105.729278)
			)
			(arc
				(start 40.601392 -105.729278)
				(mid 40.605203 -105.709974)
				(end 40.601392 -105.69067)
			)
			(arc
				(start 40.601392 -105.69067)
				(mid 40.457314 -105.209828)
				(end 40.408606 -104.71023)
			)
			(arc
				(start 40.408606 -104.709976)
				(mid 41.167583 -102.877645)
				(end 42.999914 -102.118668)
			)
			(arc
				(start 43.000168 -102.118668)
				(mid 43.499774 -102.167336)
				(end 43.980608 -102.311454)
			)
			(arc
				(start 43.980608 -102.311454)
				(mid 43.999912 -102.315265)
				(end 44.019216 -102.311454)
			)
			(arc
				(start 44.019216 -102.311454)
				(mid 44.500058 -102.167376)
				(end 44.999656 -102.118668)
			)
			(arc
				(start 44.99991 -102.118668)
				(mid 46.832241 -102.877645)
				(end 47.591218 -104.709976)
			)
			(arc
				(start 47.591218 -104.71023)
				(mid 47.54255 -105.209836)
				(end 47.398432 -105.69067)
			)
			(arc
				(start 47.398432 -105.69067)
				(mid 47.394621 -105.709974)
				(end 47.398432 -105.729278)
			)
			(arc
				(start 47.398432 -105.729278)
				(mid 47.54251 -106.21012)
				(end 47.591218 -106.709718)
			)
			(arc
				(start 47.591218 -106.709972)
				(mid 47.367574 -107.763138)
				(end 46.735238 -108.63453)
			)
			(arc
				(start 46.734984 -108.63453)
				(mid 46.722776 -108.65146)
				(end 46.718474 -108.671868)
			)
			(arc
				(start 46.718474 -108.748068)
				(mid 46.72285 -108.768443)
				(end 46.734984 -108.785406)
			)
			(arc
				(start 46.735238 -108.785406)
				(mid 47.367569 -109.6568)
				(end 47.591218 -110.709964)
			)
			(arc
				(start 47.591218 -110.710218)
				(mid 47.54255 -111.209824)
				(end 47.398432 -111.690658)
			)
			(arc
				(start 47.398432 -111.690658)
				(mid 47.394621 -111.709962)
				(end 47.398432 -111.729266)
			)
			(arc
				(start 47.398432 -111.729266)
				(mid 47.542535 -112.210232)
				(end 47.591218 -112.70996)
			)
			(arc
				(start 47.591218 -112.70996)
				(mid 47.542574 -113.209696)
				(end 47.398432 -113.690654)
			)
			(arc
				(start 47.398432 -113.690654)
				(mid 47.394621 -113.709958)
				(end 47.398432 -113.729262)
			)
			(arc
				(start 47.398432 -113.729262)
				(mid 47.419201 -113.781746)
				(end 47.438818 -113.834672)
			)
			(arc
				(start 47.438818 -113.834672)
				(mid 47.457506 -113.85904)
				(end 47.486824 -113.8682)
			)
			(arc
				(start 48.528478 -113.8682)
				(mid 48.548001 -113.864299)
				(end 48.564546 -113.853214)
			)
			(arc
				(start 48.763682 -113.653824)
				(mid 48.774793 -113.63729)
				(end 48.778668 -113.617756)
			)
			(arc
				(start 48.778668 -109.075474)
				(mid 48.777134 -109.028241)
				(end 48.776636 -108.980986)
			)
			(arc
				(start 48.776636 -108.980986)
				(mid 48.777136 -108.933731)
				(end 48.778668 -108.886498)
			)
			(arc
				(start 48.778668 -103.995474)
				(mid 48.777134 -103.948241)
				(end 48.776636 -103.900986)
			)
			(arc
				(start 48.776636 -103.900986)
				(mid 48.777136 -103.853731)
				(end 48.778668 -103.806498)
			)
			(arc
				(start 48.778668 -98.915474)
				(mid 48.777134 -98.868241)
				(end 48.776636 -98.820986)
			)
			(arc
				(start 48.776636 -98.820986)
				(mid 48.777136 -98.773731)
				(end 48.778668 -98.726498)
			)
			(arc
				(start 48.778668 -93.835474)
				(mid 48.777134 -93.788241)
				(end 48.776636 -93.740986)
			)
			(arc
				(start 48.776636 -93.740986)
				(mid 48.777136 -93.693731)
				(end 48.778668 -93.646498)
			)
			(xy 48.778668 -91.37523) (xy 48.564546 -91.161108)
			(arc
				(start 43.910504 -91.161108)
				(mid 43.890981 -91.157207)
				(end 43.874436 -91.146122)
			)
			(arc
				(start 42.474642 -89.746074)
				(mid 42.463531 -89.72954)
				(end 42.459656 -89.710006)
			)
			(arc
				(start 42.459656 -83.644994)
				(mid 42.463489 -83.625637)
				(end 42.474388 -83.60918)
			)
			(xy 43.442128 -82.64144) (xy 44.49318 -82.64144)
			(arc
				(start 44.84624 -82.28838)
				(mid 44.856248 -82.280608)
				(end 44.86402 -82.2706)
			)
			(xy 44.871132 -82.263488) (xy 44.871132 -79.280512) (xy 44.842938 -79.252318) (xy 44.823888 -79.252318)
			(xy 42.343832 -79.252318) (xy 42.309288 -79.286862) (xy 42.309288 -80.732122) (xy 42.189146 -80.852264)
			(xy 39.226236 -80.852264) (xy 39.188136 -80.852264) (xy 39.1668 -80.8736) (xy 39.1668 -82.42046)
			(xy 38.52037 -83.06689) (xy 36.459668 -85.127592) (xy 36.29152 -85.29574) (xy 35.5092 -85.29574)
			(xy 35.48126 -85.29574) (xy 35.306 -85.471) (xy 35.306 -86.81466) (xy 35.5092 -87.01786) (xy 36.0426 -87.55126)
			(xy 36.0426 -95.864426)
			(arc
				(start 35.320986 -96.58604)
				(mid 35.309875 -96.602574)
				(end 35.306 -96.622108)
			)
			(arc
				(start 35.306 -98.884486)
				(mid 35.311005 -98.906474)
				(end 35.32505 -98.92411)
			)
			(arc
				(start 35.387026 -98.973894)
				(mid 35.407117 -98.983689)
				(end 35.429444 -98.9838)
			)
			(arc
				(start 35.429698 -98.9838)
				(mid 35.661978 -98.945397)
				(end 35.897058 -98.932492)
			)
			(arc
				(start 35.897058 -98.932492)
				(mid 37.424061 -99.564997)
				(end 38.056566 -101.092)
			)
			(arc
				(start 38.056566 -101.092508)
				(mid 37.998021 -101.591681)
				(end 37.82568 -102.063804)
			)
			(xy 37.818314 -102.078536) (xy 37.823394 -102.110794)
			(arc
				(start 38.247066 -102.534466)
				(mid 38.258177 -102.551)
				(end 38.262052 -102.570534)
			)
			(arc
				(start 38.262052 -104.080564)
				(mid 38.266903 -104.102229)
				(end 38.280594 -104.11968)
			)
			(arc
				(start 38.280594 -104.11968)
				(mid 39.072564 -105.791)
				(end 38.280594 -107.46232)
			)
			(xy 38.271704 -107.469686) (xy 38.262052 -107.490006) (xy 38.262052 -107.92079)
			(arc
				(start 38.265608 -107.92968)
				(mid 38.375184 -108.313654)
				(end 38.412166 -108.711238)
			)
			(arc
				(start 38.412166 -108.712)
				(mid 38.375204 -109.109837)
				(end 38.265608 -109.494066)
			)
			(arc
				(start 38.265608 -109.494066)
				(mid 38.262984 -109.503173)
				(end 38.262052 -109.512608)
			)
			(arc
				(start 38.262052 -113.62817)
				(mid 38.265953 -113.647693)
				(end 38.277038 -113.664238)
			)
			(arc
				(start 38.466014 -113.853214)
				(mid 38.482548 -113.864325)
				(end 38.502082 -113.8682)
			)
		)
		(stroke
			(width 0)
			(type solid)
		)
		(fill yes)
		(layer "B.Cu")
		(net "P52V_FAN_2")
	)
	(gr_poly
		(pts
			(arc
				(start 4.240022 -117.8052)
				(mid 4.26688 -117.795412)
				(end 4.284218 -117.772688)
			)
			(xy 4.30149 -117.729254) (xy 4.3053 -117.72011) (xy 4.3053 -117.700044)
			(arc
				(start 4.30149 -117.690646)
				(mid 4.157412 -117.209804)
				(end 4.108704 -116.710206)
			)
			(arc
				(start 4.108704 -116.709952)
				(mid 4.332348 -115.656786)
				(end 4.964684 -114.785394)
			)
			(xy 4.972812 -114.778028) (xy 4.981448 -114.75847) (xy 4.981448 -114.661442) (xy 4.972812 -114.641884)
			(arc
				(start 4.964684 -114.634518)
				(mid 4.332353 -113.763124)
				(end 4.108704 -112.70996)
			)
			(arc
				(start 4.108704 -112.709706)
				(mid 4.157372 -112.2101)
				(end 4.30149 -111.729266)
			)
			(xy 4.3053 -111.719868) (xy 4.3053 -111.700056)
			(arc
				(start 4.30149 -111.690658)
				(mid 4.157387 -111.209692)
				(end 4.108704 -110.709964)
			)
			(arc
				(start 4.108704 -110.709964)
				(mid 4.157348 -110.210228)
				(end 4.30149 -109.72927)
			)
			(xy 4.3053 -109.719872) (xy 4.3053 -109.70006)
			(arc
				(start 4.30149 -109.690662)
				(mid 4.157387 -109.209696)
				(end 4.108704 -108.709968)
			)
			(arc
				(start 4.108704 -108.709968)
				(mid 4.157348 -108.210232)
				(end 4.30149 -107.729274)
			)
			(xy 4.3053 -107.719876) (xy 4.3053 -107.700064)
			(arc
				(start 4.30149 -107.690666)
				(mid 4.157387 -107.2097)
				(end 4.108704 -106.709972)
			)
			(arc
				(start 4.108704 -106.709972)
				(mid 4.132509 -106.35979)
				(end 4.203446 -106.016044)
			)
			(arc
				(start 4.203446 -106.016044)
				(mid 4.205244 -106.001256)
				(end 4.202684 -105.98658)
			)
			(arc
				(start 4.202684 -105.98658)
				(mid 4.132361 -105.694889)
				(end 4.108704 -105.395776)
			)
			(arc
				(start 4.108704 -104.024176)
				(mid 4.666814 -102.676778)
				(end 6.014212 -102.118668)
			)
			(arc
				(start 6.609334 -102.118668)
				(mid 6.621633 -102.11722)
				(end 6.63321 -102.112826)
			)
			(xy 6.658102 -102.099364) (xy 6.666992 -102.091744)
			(arc
				(start 6.670548 -102.086664)
				(mid 7.706591 -101.552074)
				(end 8.736838 -102.09784)
			)
			(arc
				(start 8.736838 -102.09784)
				(mid 8.753592 -102.113364)
				(end 8.775446 -102.119938)
			)
			(arc
				(start 8.777224 -102.119938)
				(mid 10.559355 -102.905235)
				(end 11.291316 -104.709976)
			)
			(arc
				(start 11.291316 -104.71023)
				(mid 11.242648 -105.209836)
				(end 11.09853 -105.69067)
			)
			(xy 11.09472 -105.700068) (xy 11.09472 -105.71988)
			(arc
				(start 11.09853 -105.729278)
				(mid 11.242633 -106.210244)
				(end 11.291316 -106.709972)
			)
			(arc
				(start 11.291316 -106.709972)
				(mid 11.242672 -107.209708)
				(end 11.09853 -107.690666)
			)
			(xy 11.09472 -107.700064) (xy 11.09472 -107.719876)
			(arc
				(start 11.09853 -107.729274)
				(mid 11.242633 -108.21024)
				(end 11.291316 -108.709968)
			)
			(arc
				(start 11.291316 -108.709968)
				(mid 11.242672 -109.209704)
				(end 11.09853 -109.690662)
			)
			(xy 11.09472 -109.70006) (xy 11.09472 -109.719872)
			(arc
				(start 11.09853 -109.72927)
				(mid 11.242608 -110.210112)
				(end 11.291316 -110.70971)
			)
			(arc
				(start 11.291316 -110.709964)
				(mid 11.067672 -111.76313)
				(end 10.435336 -112.634522)
			)
			(xy 10.427208 -112.641888) (xy 10.418572 -112.661446) (xy 10.418572 -112.758474) (xy 10.427208 -112.778032)
			(arc
				(start 10.435336 -112.785398)
				(mid 11.067667 -113.656792)
				(end 11.291316 -114.709956)
			)
			(arc
				(start 11.291316 -114.71021)
				(mid 11.242648 -115.209816)
				(end 11.09853 -115.69065)
			)
			(xy 11.09472 -115.700048) (xy 11.09472 -115.71986)
			(arc
				(start 11.09853 -115.729258)
				(mid 11.242608 -116.2101)
				(end 11.291316 -116.709698)
			)
			(arc
				(start 11.291316 -116.709952)
				(mid 11.282815 -116.918659)
				(end 11.257534 -117.126004)
			)
			(xy 11.377422 -117.245892)
			(arc
				(start 13.1699 -117.245892)
				(mid 13.205821 -117.231013)
				(end 13.2207 -117.195092)
			)
			(xy 13.2207 -116.985796) (xy 13.211302 -116.96573)
			(arc
				(start 13.20292 -116.958364)
				(mid 12.445469 -115.316)
				(end 13.20292 -113.673636)
			)
			(arc
				(start 13.20292 -113.673636)
				(mid 13.216043 -113.656281)
				(end 13.2207 -113.635028)
			)
			(xy 13.2207 -113.430558) (xy 13.214604 -113.413794)
			(arc
				(start 13.208762 -113.406936)
				(mid 12.699478 -112.018423)
				(end 13.203174 -110.627922)
			)
			(xy 13.208762 -110.621064)
			(arc
				(start 13.217652 -110.596934)
				(mid 13.219939 -110.588305)
				(end 13.2207 -110.579408)
			)
			(xy 13.2207 -109.314488)
			(arc
				(start 13.220192 -109.311186)
				(mid 13.205888 -109.16812)
				(end 13.201142 -109.02442)
			)
			(arc
				(start 13.201142 -109.023404)
				(mid 13.205895 -108.879704)
				(end 13.220192 -108.736638)
			)
			(xy 13.2207 -108.733336) (xy 13.2207 -108.171488)
			(arc
				(start 13.220192 -108.168186)
				(mid 13.205888 -108.02512)
				(end 13.201142 -107.88142)
			)
			(arc
				(start 13.201142 -107.880404)
				(mid 13.205895 -107.736704)
				(end 13.220192 -107.593638)
			)
			(xy 13.2207 -107.590336) (xy 13.2207 -99.865942) (xy 15.31874 -97.767902) (xy 15.31874 -95.47098)
			(xy 15.2654 -95.41764) (xy 15.31874 -95.3643) (xy 15.31874 -87.91194) (xy 16.38554 -86.84514) (xy 16.38554 -84.45881)
			(xy 17.145 -83.69935) (xy 17.145 -79.375) (xy 17.145 -79.2988) (xy 17.098518 -79.252318) (xy 17.022318 -79.252318)
			(xy 14.582394 -79.252318) (xy 14.54785 -79.286862) (xy 14.54785 -80.732122) (xy 14.527022 -80.75295)
			(xy 14.443202 -80.83677) (xy 14.427708 -80.852264) (xy 11.448034 -80.852264) (xy 11.438636 -80.852264)
			(xy 11.40968 -80.88122) (xy 11.40968 -82.597752) (xy 9.37514 -84.632292) (xy 9.37514 -89.668604)
			(xy 8.71093 -90.332814)
			(arc
				(start 7.863586 -90.332814)
				(mid 7.847052 -90.343925)
				(end 7.827518 -90.3478)
			)
			(arc
				(start 3.036824 -90.3478)
				(mid 3.017301 -90.351701)
				(end 3.000756 -90.362786)
			)
			(xy 2.935986 -90.427556) (xy 2.92862 -90.434668) (xy 2.921 -90.453464) (xy 2.921 -94.062296) (xy 2.922778 -94.15145)
			(xy 2.921 -94.240604) (xy 2.921 -99.142296) (xy 2.922778 -99.23145) (xy 2.921 -99.320604) (xy 2.921 -104.222296)
			(xy 2.922778 -104.31145) (xy 2.921 -104.400604) (xy 2.921 -109.302296) (xy 2.922778 -109.39145) (xy 2.921 -109.480604)
			(xy 2.921 -114.382296) (xy 2.922778 -114.47145) (xy 2.921 -114.560604)
			(arc
				(start 2.921 -117.59692)
				(mid 2.924765 -117.616111)
				(end 2.935478 -117.63248)
			)
			(xy 3.093212 -117.790214)
			(arc
				(start 3.09372 -117.790722)
				(mid 3.110077 -117.801464)
				(end 3.12928 -117.8052)
			)
		)
		(stroke
			(width 0)
			(type solid)
		)
		(fill yes)
		(layer "B.Cu")
		(net "P52V_FAN_5")
	)
	(gr_poly
		(pts
			(arc
				(start 4.410964 -304.830226)
				(mid 4.436747 -304.823197)
				(end 4.455414 -304.804064)
			)
			(arc
				(start 4.498594 -304.726594)
				(mid 4.504949 -304.70065)
				(end 4.497324 -304.675032)
			)
			(arc
				(start 4.497324 -304.675032)
				(mid 4.207755 -304.019655)
				(end 4.108704 -303.310036)
			)
			(arc
				(start 4.108704 -303.309782)
				(mid 4.157372 -302.810176)
				(end 4.30149 -302.329342)
			)
			(xy 4.3053 -302.319944) (xy 4.3053 -302.300132)
			(arc
				(start 4.30149 -302.290734)
				(mid 4.157412 -301.809892)
				(end 4.108704 -301.310294)
			)
			(arc
				(start 4.108704 -301.31004)
				(mid 4.332348 -300.256874)
				(end 4.964684 -299.385482)
			)
			(xy 4.972812 -299.378116) (xy 4.981448 -299.358558) (xy 4.981448 -299.26153) (xy 4.972812 -299.241972)
			(arc
				(start 4.964684 -299.234606)
				(mid 4.332353 -298.363212)
				(end 4.108704 -297.310048)
			)
			(arc
				(start 4.108704 -297.309794)
				(mid 4.157372 -296.810188)
				(end 4.30149 -296.329354)
			)
			(xy 4.3053 -296.319956) (xy 4.3053 -296.300144)
			(arc
				(start 4.30149 -296.290746)
				(mid 4.157387 -295.80978)
				(end 4.108704 -295.310052)
			)
			(arc
				(start 4.108704 -295.310052)
				(mid 4.157348 -294.810316)
				(end 4.30149 -294.329358)
			)
			(xy 4.3053 -294.31996) (xy 4.3053 -294.300148)
			(arc
				(start 4.30149 -294.29075)
				(mid 4.157387 -293.809784)
				(end 4.108704 -293.310056)
			)
			(arc
				(start 4.108704 -293.310056)
				(mid 4.157348 -292.81032)
				(end 4.30149 -292.329362)
			)
			(xy 4.3053 -292.319964) (xy 4.3053 -292.300152)
			(arc
				(start 4.30149 -292.290754)
				(mid 4.157387 -291.809788)
				(end 4.108704 -291.31006)
			)
			(arc
				(start 4.108704 -291.31006)
				(mid 4.132509 -290.959878)
				(end 4.203446 -290.616132)
			)
			(arc
				(start 4.203446 -290.616132)
				(mid 4.205244 -290.601344)
				(end 4.202684 -290.586668)
			)
			(arc
				(start 4.202684 -290.586668)
				(mid 4.132361 -290.294977)
				(end 4.108704 -289.995864)
			)
			(arc
				(start 4.108704 -288.624264)
				(mid 4.666814 -287.276866)
				(end 6.014212 -286.718756)
			)
			(arc
				(start 6.609334 -286.718756)
				(mid 6.621633 -286.717308)
				(end 6.63321 -286.712914)
			)
			(xy 6.658102 -286.699452) (xy 6.666992 -286.691832)
			(arc
				(start 6.670548 -286.686752)
				(mid 7.706591 -286.152162)
				(end 8.736838 -286.697928)
			)
			(arc
				(start 8.736838 -286.697928)
				(mid 8.753592 -286.713452)
				(end 8.775446 -286.720026)
			)
			(arc
				(start 8.777224 -286.720026)
				(mid 10.559355 -287.505323)
				(end 11.291316 -289.310064)
			)
			(arc
				(start 11.291316 -289.310318)
				(mid 11.242648 -289.809924)
				(end 11.09853 -290.290758)
			)
			(xy 11.09472 -290.300156) (xy 11.09472 -290.319968)
			(arc
				(start 11.09853 -290.329366)
				(mid 11.242633 -290.810332)
				(end 11.291316 -291.31006)
			)
			(arc
				(start 11.291316 -291.31006)
				(mid 11.242672 -291.809796)
				(end 11.09853 -292.290754)
			)
			(xy 11.09472 -292.300152) (xy 11.09472 -292.319964)
			(arc
				(start 11.09853 -292.329362)
				(mid 11.242633 -292.810328)
				(end 11.291316 -293.310056)
			)
			(arc
				(start 11.291316 -293.310056)
				(mid 11.283853 -293.506071)
				(end 11.261598 -293.700962)
			)
			(arc
				(start 11.261598 -293.700962)
				(mid 12.144457 -294.506469)
				(end 12.4714 -295.656)
			)
			(arc
				(start 12.4714 -295.656)
				(mid 12.000936 -297.010262)
				(end 10.792206 -297.781218)
			)
			(arc
				(start 10.792206 -297.781218)
				(mid 11.163376 -298.505932)
				(end 11.291316 -299.310044)
			)
			(arc
				(start 11.291316 -299.310298)
				(mid 11.242648 -299.809904)
				(end 11.09853 -300.290738)
			)
			(xy 11.09472 -300.300136) (xy 11.09472 -300.319948)
			(arc
				(start 11.09853 -300.329346)
				(mid 11.242633 -300.810312)
				(end 11.291316 -301.31004)
			)
			(arc
				(start 11.291316 -301.31004)
				(mid 11.242672 -301.809776)
				(end 11.09853 -302.290734)
			)
			(xy 11.09472 -302.300132) (xy 11.09472 -302.319944)
			(arc
				(start 11.09853 -302.329342)
				(mid 11.242608 -302.810184)
				(end 11.291316 -303.309782)
			)
			(arc
				(start 11.291316 -303.310036)
				(mid 11.192269 -304.019656)
				(end 10.902696 -304.675032)
			)
			(arc
				(start 10.902696 -304.675032)
				(mid 10.895007 -304.700648)
				(end 10.901426 -304.726594)
			)
			(arc
				(start 10.944606 -304.804064)
				(mid 10.963262 -304.823215)
				(end 10.989056 -304.830226)
			)
			(arc
				(start 12.16914 -304.830226)
				(mid 12.183863 -304.827969)
				(end 12.197334 -304.82159)
			)
			(xy 12.22502 -304.803302) (xy 12.234164 -304.792126)
			(arc
				(start 12.237212 -304.785014)
				(mid 12.81333 -303.996437)
				(end 13.6779 -303.542192)
			)
			(arc
				(start 13.68298 -303.540668)
				(mid 13.706949 -303.521966)
				(end 13.716 -303.492916)
			)
			(arc
				(start 13.716 -301.974504)
				(mid 13.708081 -301.947267)
				(end 13.68679 -301.92853)
			)
			(arc
				(start 13.68679 -301.92853)
				(mid 12.782071 -301.131682)
				(end 12.445492 -299.974)
			)
			(arc
				(start 12.445492 -299.974)
				(mid 12.665765 -299.023878)
				(end 13.28166 -298.267628)
			)
			(arc
				(start 13.28166 -297.324272)
				(mid 13.278042 -297.252176)
				(end 13.276834 -297.18)
			)
			(arc
				(start 13.276834 -297.18)
				(mid 13.27804 -297.107824)
				(end 13.28166 -297.035728)
			)
			(arc
				(start 13.28166 -297.03522)
				(mid 13.301026 -296.857587)
				(end 13.335 -296.68216)
			)
			(arc
				(start 13.335 -294.499792)
				(mid 13.234854 -294.131462)
				(end 13.201142 -293.751254)
			)
			(arc
				(start 13.201142 -293.751)
				(mid 13.219574 -293.469452)
				(end 13.274548 -293.192708)
			)
			(arc
				(start 13.274548 -293.192708)
				(mid 13.276296 -293.1795)
				(end 13.274548 -293.166292)
			)
			(arc
				(start 13.274548 -293.166292)
				(mid 13.219582 -292.889675)
				(end 13.201142 -292.608254)
			)
			(arc
				(start 13.201142 -292.607746)
				(mid 13.292947 -291.984747)
				(end 13.560552 -291.414708)
			)
			(xy 13.560552 -282.732226) (xy 15.9258 -280.366978) (xy 15.9258 -271.64792) (xy 16.928846 -270.644874)
			(xy 16.928846 -267.776706) (xy 17.079976 -267.625576) (xy 17.199356 -267.505942) (xy 17.199356 -266.8524)
			(xy 17.200372 -266.84224) (xy 17.200372 -265.332972) (xy 17.199356 -265.322812) (xy 17.199356 -263.862312)
			(xy 17.18945 -263.852406) (xy 14.709394 -263.852406) (xy 14.67485 -263.88695) (xy 14.67485 -265.33221)
			(xy 14.554708 -265.452352) (xy 11.575034 -265.452352) (xy 11.554968 -265.452352) (xy 11.49858 -265.50874)
			(xy 11.49858 -266.813538)
			(arc
				(start 9.79932 -268.512798)
				(mid 9.788298 -268.529479)
				(end 9.784588 -268.54912)
			)
			(arc
				(start 9.784588 -273.996404)
				(mid 9.780687 -274.015927)
				(end 9.769602 -274.032472)
			)
			(arc
				(start 8.480552 -275.321522)
				(mid 8.464018 -275.332633)
				(end 8.444484 -275.336508)
			)
			(arc
				(start 2.9718 -275.336508)
				(mid 2.935879 -275.351387)
				(end 2.921 -275.387308)
			)
			(xy 2.921 -276.942296) (xy 2.922778 -277.03145) (xy 2.921 -277.120604) (xy 2.921 -282.022296) (xy 2.922778 -282.11145)
			(xy 2.921 -282.200604) (xy 2.921 -287.102296) (xy 2.922778 -287.19145) (xy 2.921 -287.280604) (xy 2.921 -292.182296)
			(xy 2.922778 -292.27145) (xy 2.921 -292.360604) (xy 2.921 -297.262296) (xy 2.922778 -297.35145) (xy 2.921 -297.440604)
			(xy 2.921 -302.342296) (xy 2.922778 -302.43145) (xy 2.921 -302.520604) (xy 2.921 -304.82286) (xy 2.928366 -304.830226)
		)
		(stroke
			(width 0)
			(type solid)
		)
		(fill yes)
		(layer "B.Cu")
		(net "P52V_FAN_7")
	)
	(gr_poly
		(pts
			(xy 37.025072 -244.930168) (xy 37.025072 -243.5225) (xy 37.04082 -243.506752) (xy 37.192712 -243.35486)
			(xy 37.200078 -243.347494) (xy 40.124888 -243.347494) (xy 40.13962 -243.332762) (xy 40.13962 -241.427762)
			(arc
				(start 40.633904 -240.933478)
				(mid 41.268707 -240.508907)
				(end 42.017696 -240.359692)
			)
			(xy 43.716448 -240.359692) (xy 44.03217 -240.04397) (xy 44.240958 -239.835182) (xy 44.240958 -238.556038)
			(xy 43.815 -238.13008) (xy 43.47464 -238.13008) (xy 43.18762 -237.84306) (xy 43.18762 -225.088958)
			(xy 45.583602 -222.692976) (xy 48.502062 -222.692976) (xy 48.778668 -222.41637) (xy 48.778668 -220.834458)
			(xy 48.776636 -220.741748) (xy 48.776636 -220.740224) (xy 48.778668 -220.647514) (xy 48.778668 -215.754458)
			(xy 48.776636 -215.661748) (xy 48.776636 -215.660224) (xy 48.778668 -215.567514) (xy 48.778668 -210.674458)
			(xy 48.776636 -210.581748) (xy 48.776636 -210.580224) (xy 48.778668 -210.487514) (xy 48.778668 -205.594458)
			(xy 48.776636 -205.501748) (xy 48.776636 -205.500224) (xy 48.778668 -205.407514) (xy 48.778668 -200.514458)
			(xy 48.776636 -200.421748) (xy 48.776636 -200.420224) (xy 48.778668 -200.327514) (xy 48.778668 -195.679822)
			(xy 48.771048 -195.661026) (xy 48.763682 -195.653914) (xy 48.50003 -195.390008) (xy 48.492918 -195.382642)
			(xy 48.474122 -195.375022)
			(arc
				(start 47.21352 -195.375022)
				(mid 47.187249 -195.382342)
				(end 47.168562 -195.4022)
			)
			(xy 47.120048 -195.494656) (xy 47.121826 -195.52285)
			(arc
				(start 47.129954 -195.534534)
				(mid 47.47318 -196.237078)
				(end 47.591218 -197.01002)
			)
			(arc
				(start 47.591218 -197.010274)
				(mid 47.54255 -197.50988)
				(end 47.398432 -197.990714)
			)
			(xy 47.394622 -198.000112) (xy 47.394622 -198.019924)
			(arc
				(start 47.398432 -198.029322)
				(mid 47.54251 -198.510164)
				(end 47.591218 -199.009762)
			)
			(arc
				(start 47.591218 -199.010016)
				(mid 47.367574 -200.063182)
				(end 46.735238 -200.934574)
			)
			(xy 46.72711 -200.94194) (xy 46.718474 -200.961498) (xy 46.718474 -201.058526) (xy 46.72711 -201.078084)
			(arc
				(start 46.735238 -201.08545)
				(mid 47.367569 -201.956844)
				(end 47.591218 -203.010008)
			)
			(arc
				(start 47.591218 -203.010262)
				(mid 47.54255 -203.509868)
				(end 47.398432 -203.990702)
			)
			(xy 47.394622 -204.0001) (xy 47.394622 -204.019912)
			(arc
				(start 47.398432 -204.02931)
				(mid 47.542535 -204.510276)
				(end 47.591218 -205.010004)
			)
			(arc
				(start 47.591218 -205.010004)
				(mid 47.542574 -205.50974)
				(end 47.398432 -205.990698)
			)
			(xy 47.394622 -206.000096) (xy 47.394622 -206.019908)
			(arc
				(start 47.398432 -206.029306)
				(mid 47.542535 -206.510272)
				(end 47.591218 -207.01)
			)
			(arc
				(start 47.591218 -207.01)
				(mid 47.542574 -207.509736)
				(end 47.398432 -207.990694)
			)
			(xy 47.394622 -208.000092) (xy 47.394622 -208.019904)
			(arc
				(start 47.398432 -208.029302)
				(mid 47.542535 -208.510268)
				(end 47.591218 -209.009996)
			)
			(arc
				(start 47.591218 -209.009996)
				(mid 47.567413 -209.360178)
				(end 47.496476 -209.703924)
			)
			(arc
				(start 47.496476 -209.703924)
				(mid 47.494675 -209.718591)
				(end 47.497238 -209.733134)
			)
			(arc
				(start 47.497238 -209.733134)
				(mid 47.567404 -210.024583)
				(end 47.590964 -210.32343)
			)
			(arc
				(start 47.590964 -211.695792)
				(mid 47.032943 -213.0431)
				(end 45.68571 -213.6013)
			)
			(arc
				(start 45.090588 -213.6013)
				(mid 45.078289 -213.602748)
				(end 45.066712 -213.607142)
			)
			(xy 45.04182 -213.620604) (xy 45.03293 -213.628224)
			(arc
				(start 45.029374 -213.633304)
				(mid 43.993331 -214.167894)
				(end 42.963084 -213.622128)
			)
			(arc
				(start 42.963084 -213.622128)
				(mid 42.94633 -213.606604)
				(end 42.924476 -213.60003)
			)
			(arc
				(start 42.922698 -213.60003)
				(mid 41.140567 -212.814733)
				(end 40.408606 -211.009992)
			)
			(arc
				(start 40.408606 -211.009738)
				(mid 40.457274 -210.510132)
				(end 40.601392 -210.029298)
			)
			(xy 40.605202 -210.0199) (xy 40.605202 -210.000088)
			(arc
				(start 40.601392 -209.99069)
				(mid 40.457289 -209.509724)
				(end 40.408606 -209.009996)
			)
			(arc
				(start 40.408606 -209.009996)
				(mid 40.45725 -208.51026)
				(end 40.601392 -208.029302)
			)
			(xy 40.605202 -208.019904) (xy 40.605202 -208.000092)
			(arc
				(start 40.601392 -207.990694)
				(mid 40.457289 -207.509728)
				(end 40.408606 -207.01)
			)
			(arc
				(start 40.408606 -207.01)
				(mid 40.45725 -206.510264)
				(end 40.601392 -206.029306)
			)
			(xy 40.605202 -206.019908) (xy 40.605202 -206.000096)
			(arc
				(start 40.601392 -205.990698)
				(mid 40.457314 -205.509856)
				(end 40.408606 -205.010258)
			)
			(arc
				(start 40.408606 -205.010004)
				(mid 40.63225 -203.956838)
				(end 41.264586 -203.085446)
			)
			(xy 41.272714 -203.07808) (xy 41.28135 -203.058522) (xy 41.28135 -202.961494) (xy 41.272714 -202.941936)
			(arc
				(start 41.264586 -202.93457)
				(mid 40.632255 -202.063176)
				(end 40.408606 -201.010012)
			)
			(arc
				(start 40.408606 -201.009758)
				(mid 40.457274 -200.510152)
				(end 40.601392 -200.029318)
			)
			(xy 40.605202 -200.01992) (xy 40.605202 -200.000108)
			(arc
				(start 40.601392 -199.99071)
				(mid 40.457289 -199.509744)
				(end 40.408606 -199.010016)
			)
			(arc
				(start 40.408606 -199.010016)
				(mid 40.45725 -198.51028)
				(end 40.601392 -198.029322)
			)
			(xy 40.605202 -198.019924) (xy 40.605202 -198.000112)
			(arc
				(start 40.601392 -197.990714)
				(mid 40.457314 -197.509872)
				(end 40.408606 -197.010274)
			)
			(arc
				(start 40.408606 -197.01002)
				(mid 40.524352 -196.244713)
				(end 40.86098 -195.547742)
			)
			(xy 40.865298 -195.541138) (xy 40.86987 -195.526914)
			(arc
				(start 40.86987 -195.488306)
				(mid 40.868361 -195.476268)
				(end 40.864028 -195.464938)
			)
			(arc
				(start 40.831262 -195.4022)
				(mid 40.812568 -195.382354)
				(end 40.786304 -195.375022)
			)
			(arc
				(start 39.435278 -195.375022)
				(mid 39.415755 -195.378923)
				(end 39.39921 -195.390008)
			)
			(xy 38.685216 -196.104002) (xy 38.67785 -196.111114) (xy 38.67023 -196.12991)
			(arc
				(start 38.67023 -211.135214)
				(mid 38.672005 -211.14878)
				(end 38.677342 -211.161376)
			)
			(xy 38.680898 -211.167472) (xy 38.69055 -211.176616)
			(arc
				(start 38.696646 -211.179918)
				(mid 39.272669 -211.636036)
				(end 39.662354 -212.25891)
			)
			(arc
				(start 39.662354 -212.25891)
				(mid 39.812035 -213.292317)
				(end 39.459408 -214.275162)
			)
			(arc
				(start 39.459408 -214.275416)
				(mid 39.453037 -214.288878)
				(end 39.450772 -214.30361)
			)
			(xy 39.450772 -214.441024) (xy 39.4589 -214.45982)
			(arc
				(start 39.46652 -214.467186)
				(mid 39.959069 -215.178972)
				(end 40.132508 -216.027)
			)
			(arc
				(start 40.132508 -216.027)
				(mid 40.098007 -216.411476)
				(end 39.995602 -216.783666)
			)
			(arc
				(start 39.995602 -216.783666)
				(mid 39.992715 -216.795171)
				(end 39.992554 -216.807034)
			)
			(arc
				(start 39.992554 -216.807034)
				(mid 40.002236 -216.924332)
				(end 40.005508 -217.041984)
			)
			(arc
				(start 40.005508 -217.043)
				(mid 39.373003 -218.570003)
				(end 37.846 -219.202508)
			)
			(arc
				(start 37.844984 -219.202508)
				(mid 37.658613 -219.194407)
				(end 37.473636 -219.17025)
			)
			(arc
				(start 37.473636 -219.17025)
				(mid 37.465 -219.16951)
				(end 37.456364 -219.17025)
			)
			(arc
				(start 37.456364 -219.17025)
				(mid 37.271387 -219.194405)
				(end 37.085016 -219.202508)
			)
			(arc
				(start 37.084 -219.202508)
				(mid 36.221533 -219.022828)
				(end 35.502596 -218.51366)
			)
			(arc
				(start 35.502596 -218.51366)
				(mid 35.485749 -218.501647)
				(end 35.465512 -218.497404)
			)
			(xy 33.724596 -218.497404) (xy 33.274 -218.948) (xy 33.274 -244.59946) (xy 33.62198 -244.94744) (xy 34.510472 -244.94744)
			(xy 37.0078 -244.94744)
		)
		(stroke
			(width 0)
			(type solid)
		)
		(fill yes)
		(layer "B.Cu")
		(net "P52V_FAN_1")
	)
	(gr_poly
		(pts
			(xy 49.05121 -193.038984) (xy 49.058457 -193.037362) (xy 49.071635 -193.03053) (xy 49.077118 -193.025522)
			(xy 49.81321 -192.28943) (xy 49.818192 -192.283929) (xy 49.825024 -192.27076) (xy 49.826672 -192.263522)
			(xy 49.827688 -192.25387) (xy 49.827688 -163.294822) (xy 49.827517 -163.288813) (xy 49.824687 -163.277134)
			(xy 49.8221 -163.271708) (xy 49.820262 -163.268233) (xy 49.815671 -163.261851) (xy 49.812956 -163.259008)
			(xy 48.87468 -162.320732) (xy 48.871828 -162.318027) (xy 48.865449 -162.313437) (xy 48.86198 -162.311588)
			(xy 48.856553 -162.309003) (xy 48.844874 -162.306175) (xy 48.838866 -162.306) (xy 37.613082 -162.306)
			(xy 37.603013 -162.305573) (xy 37.584414 -162.297854) (xy 37.577014 -162.291014) (xy 35.828986 -160.542986)
			(xy 35.822132 -160.535591) (xy 35.81439 -160.516992) (xy 35.814 -160.506918) (xy 35.814 -141.753082)
			(xy 35.814427 -141.743013) (xy 35.822146 -141.724414) (xy 35.828986 -141.717014) (xy 36.561522 -140.984478)
			(xy 36.566509 -140.978979) (xy 36.573351 -140.965812) (xy 36.574984 -140.95857) (xy 36.576 -140.948918)
			(xy 36.576 -140.907008) (xy 36.575582 -140.896986) (xy 36.567913 -140.878466) (xy 36.553741 -140.864291)
			(xy 36.535222 -140.85662) (xy 36.5252 -140.856208) (xy 35.432746 -140.856208) (xy 35.406941 -140.85577)
			(xy 35.355776 -140.849005) (xy 35.30593 -140.835625) (xy 35.258256 -140.815856) (xy 35.213567 -140.790039)
			(xy 35.172628 -140.758613) (xy 35.154108 -140.740638) (xy 32.87141 -138.45794) (xy 32.864003 -138.45125)
			(xy 32.845566 -138.443658) (xy 32.835596 -138.443208) (xy 27.686 -138.443208) (xy 27.657842 -138.442706)
			(xy 27.602098 -138.434691) (xy 27.548062 -138.418825) (xy 27.496835 -138.39543) (xy 27.449458 -138.364983)
			(xy 27.406897 -138.328103) (xy 27.370017 -138.285542) (xy 27.33957 -138.238165) (xy 27.316175 -138.186938)
			(xy 27.300309 -138.132902) (xy 27.292294 -138.077158) (xy 27.291792 -138.049) (xy 27.292237 -138.021882)
			(xy 27.299662 -137.968157) (xy 27.314386 -137.915959) (xy 27.33613 -137.866273) (xy 27.364484 -137.820039)
			(xy 27.39891 -137.778131) (xy 27.43876 -137.741341) (xy 27.483279 -137.710364) (xy 27.531625 -137.685786)
			(xy 27.582886 -137.668071) (xy 27.636093 -137.657555) (xy 27.66314 -137.655554) (xy 27.663394 -137.655554)
			(xy 27.673046 -137.655046) (xy 27.690064 -137.646918) (xy 27.694636 -137.642092) (xy 27.700953 -137.63488)
			(xy 27.708141 -137.617123) (xy 27.708606 -137.607548) (xy 27.708606 -137.589768) (xy 27.704914 -137.579616)
			(xy 27.690581 -137.563479) (xy 27.670884 -137.554655) (xy 27.660092 -137.554208) (xy 27.558746 -137.554208)
			(xy 27.532941 -137.55377) (xy 27.481776 -137.547005) (xy 27.43193 -137.533625) (xy 27.384256 -137.513856)
			(xy 27.339567 -137.488039) (xy 27.298628 -137.456613) (xy 27.280108 -137.438638) (xy 27.153362 -137.311892)
			(xy 27.133628 -137.291472) (xy 27.099628 -137.245991) (xy 27.072494 -137.196108) (xy 27.062176 -137.169652)
			(xy 27.050956 -137.137059) (xy 27.038685 -137.069236) (xy 27.037792 -137.034778) (xy 27.037792 -137.033)
			(xy 27.038294 -137.004842) (xy 27.046309 -136.949098) (xy 27.062175 -136.895062) (xy 27.08557 -136.843835)
			(xy 27.116017 -136.796458) (xy 27.152897 -136.753897) (xy 27.195458 -136.717017) (xy 27.242835 -136.68657)
			(xy 27.294062 -136.663175) (xy 27.348098 -136.647309) (xy 27.403842 -136.639294) (xy 27.432 -136.638792)
			(xy 27.46165 -136.639326) (xy 27.520281 -136.648201) (xy 27.576924 -136.665751) (xy 27.630302 -136.691582)
			(xy 27.679213 -136.72511) (xy 27.70124 -136.744964) (xy 27.708098 -136.751314) (xy 27.73426 -136.761982)
			(xy 27.738826 -136.76374) (xy 27.748419 -136.765666) (xy 27.75331 -136.765792) (xy 33.388554 -136.765792)
			(xy 33.414359 -136.76623) (xy 33.465524 -136.772995) (xy 33.51537 -136.786375) (xy 33.563044 -136.806144)
			(xy 33.607733 -136.831961) (xy 33.648672 -136.863387) (xy 33.667192 -136.881362) (xy 35.08883 -138.303)
			(xy 37.844982 -138.303) (xy 37.849053 -138.247378) (xy 37.861179 -138.192941) (xy 37.881102 -138.14085)
			(xy 37.908398 -138.092215) (xy 37.942484 -138.048072) (xy 37.982633 -138.009363) (xy 38.027991 -137.976912)
			(xy 38.077591 -137.951411) (xy 38.130375 -137.933404) (xy 38.185218 -137.923274) (xy 38.240952 -137.921237)
			(xy 38.296389 -137.927337) (xy 38.350346 -137.941443) (xy 38.401675 -137.963255) (xy 38.449281 -137.992309)
			(xy 38.492149 -138.027984) (xy 38.529366 -138.069521) (xy 38.560139 -138.116034) (xy 38.583811 -138.166531)
			(xy 38.599879 -138.219938) (xy 38.607999 -138.275114) (xy 38.608508 -138.303) (xy 38.607999 -138.330886)
			(xy 38.599879 -138.386062) (xy 38.583811 -138.439469) (xy 38.560139 -138.489966) (xy 38.529366 -138.536479)
			(xy 38.492149 -138.578016) (xy 38.449281 -138.613691) (xy 38.401675 -138.642745) (xy 38.350346 -138.664557)
			(xy 38.296389 -138.678663) (xy 38.240952 -138.684763) (xy 38.185218 -138.682726) (xy 38.130375 -138.672596)
			(xy 38.077591 -138.654589) (xy 38.027991 -138.629088) (xy 37.982633 -138.596637) (xy 37.942484 -138.557928)
			(xy 37.908398 -138.513785) (xy 37.881102 -138.46515) (xy 37.861179 -138.413059) (xy 37.849053 -138.358622)
			(xy 37.844982 -138.303) (xy 35.08883 -138.303) (xy 35.950144 -139.164314) (xy 35.95513 -139.168904)
			(xy 35.966978 -139.17547) (xy 35.973512 -139.177268) (xy 35.985704 -139.178792) (xy 43.590718 -139.178792)
			(xy 43.602402 -139.177522) (xy 43.609093 -139.175734) (xy 43.62121 -139.169035) (xy 43.626278 -139.164314)
			(xy 46.213268 -136.577578) (xy 46.2178 -136.572697) (xy 46.224363 -136.561113) (xy 46.226222 -136.554718)
			(xy 46.228 -136.541764) (xy 46.228 -135.276082) (xy 46.228427 -135.266013) (xy 46.236146 -135.247414)
			(xy 46.242986 -135.240014) (xy 48.251364 -133.231636) (xy 48.254072 -133.228786) (xy 48.258669 -133.22241)
			(xy 48.260508 -133.218936) (xy 48.263089 -133.213509) (xy 48.265907 -133.201829) (xy 48.266096 -133.195822)
			(xy 48.266096 -133.096) (xy 48.266517 -133.070204) (xy 48.273244 -133.019051) (xy 48.286584 -132.969213)
			(xy 48.306308 -132.921539) (xy 48.332081 -132.876845) (xy 48.363461 -132.835892) (xy 48.381412 -132.817362)
			(xy 48.830484 -132.368036) (xy 48.837176 -132.360629) (xy 48.844773 -132.342193) (xy 48.845216 -132.332222)
			(xy 48.845216 -132.174742) (xy 48.84465 -132.164296) (xy 48.836255 -132.145156) (xy 48.82896 -132.137658)
			(xy 48.777652 -132.094478) (xy 48.767492 -132.085842) (xy 48.760527 -132.08046) (xy 48.744026 -132.07437)
			(xy 48.735234 -132.073904) (xy 48.727106 -132.074666) (xy 48.72482 -132.07492) (xy 48.708754 -132.077525)
			(xy 48.676325 -132.080321) (xy 48.66005 -132.080508) (xy 48.63309 -132.080046) (xy 48.579706 -132.072461)
			(xy 48.527922 -132.057435) (xy 48.478769 -132.035268) (xy 48.433228 -132.0064) (xy 48.392205 -131.971408)
			(xy 48.374046 -131.951476) (xy 48.373538 -131.950968) (xy 48.36922 -131.946142) (xy 48.349662 -131.937506)
			(xy 48.252126 -131.93776) (xy 48.232314 -131.94665) (xy 48.225202 -131.954778) (xy 48.203389 -131.978492)
			(xy 48.154252 -132.020172) (xy 48.099755 -132.054548) (xy 48.040977 -132.080941) (xy 47.979077 -132.098831)
			(xy 47.91528 -132.107862) (xy 47.883064 -132.108448) (xy 47.853095 -132.107956) (xy 47.793671 -132.100128)
			(xy 47.735777 -132.084611) (xy 47.680403 -132.061671) (xy 47.628497 -132.031699) (xy 47.580947 -131.995209)
			(xy 47.538567 -131.952826) (xy 47.502081 -131.905273) (xy 47.472113 -131.853365) (xy 47.449177 -131.797989)
			(xy 47.433665 -131.740094) (xy 47.425842 -131.680669) (xy 47.425842 -131.620731) (xy 47.433665 -131.561306)
			(xy 47.449177 -131.503411) (xy 47.472113 -131.448036) (xy 47.502081 -131.396127) (xy 47.538567 -131.348574)
			(xy 47.580947 -131.306191) (xy 47.628497 -131.269701) (xy 47.680403 -131.239729) (xy 47.735777 -131.216789)
			(xy 47.793671 -131.201272) (xy 47.853095 -131.193444) (xy 47.883064 -131.193032) (xy 47.91474 -131.193573)
			(xy 47.977486 -131.202316) (xy 48.038427 -131.219625) (xy 48.0964 -131.245171) (xy 48.150298 -131.278466)
			(xy 48.199091 -131.318873) (xy 48.241847 -131.365621) (xy 48.260254 -131.391406) (xy 48.26635 -131.400296)
			(xy 48.284638 -131.411472) (xy 48.37049 -131.422648) (xy 48.381262 -131.423502) (xy 48.401904 -131.417176)
			(xy 48.410368 -131.410456) (xy 48.431281 -131.393015) (xy 48.477117 -131.363618) (xy 48.526666 -131.341033)
			(xy 48.578922 -131.325719) (xy 48.632823 -131.317987) (xy 48.66005 -131.317492) (xy 48.676648 -131.317694)
			(xy 48.709715 -131.320619) (xy 48.72609 -131.323334) (xy 48.73752 -131.325366) (xy 48.758856 -131.319524)
			(xy 48.760888 -131.318) (xy 48.827182 -131.26212) (xy 48.828706 -131.260596) (xy 48.835875 -131.253459)
			(xy 48.844371 -131.235118) (xy 48.845216 -131.225036) (xy 48.845216 -129.130552) (xy 48.844785 -129.120485)
			(xy 48.83706 -129.101892) (xy 48.83023 -129.094484) (xy 46.457108 -126.721108) (xy 44.083732 -124.347732)
			(xy 44.079338 -124.343663) (xy 44.069071 -124.3375) (xy 44.063412 -124.33554) (xy 44.05964 -124.334394)
			(xy 44.051859 -124.333118) (xy 44.047918 -124.333) (xy 42.947082 -124.333) (xy 42.937013 -124.332573)
			(xy 42.918414 -124.324854) (xy 42.911014 -124.318014) (xy 39.957248 -121.364502) (xy 39.949847 -121.357663)
			(xy 39.931249 -121.349948) (xy 39.92118 -121.349516) (xy 29.843222 -121.349516) (xy 29.833261 -121.350005)
			(xy 29.814841 -121.357597) (xy 29.807408 -121.364248) (xy 29.188918 -121.982738) (xy 29.170394 -122.00071)
			(xy 29.129462 -122.03215) (xy 29.084777 -122.057978) (xy 29.037102 -122.077752) (xy 28.987254 -122.091134)
			(xy 28.936086 -122.097895) (xy 28.91028 -122.098308) (xy 28.418028 -122.098308) (xy 28.408066 -122.098795)
			(xy 28.389644 -122.106385) (xy 28.382214 -122.11304) (xy 27.872944 -122.622056) (xy 27.864891 -122.630982)
			(xy 27.857344 -122.653774) (xy 27.858466 -122.665744) (xy 27.860963 -122.682) (xy 37.209982 -122.682)
			(xy 37.214053 -122.626378) (xy 37.226179 -122.571941) (xy 37.246102 -122.51985) (xy 37.273398 -122.471215)
			(xy 37.307484 -122.427072) (xy 37.347633 -122.388363) (xy 37.392991 -122.355912) (xy 37.442591 -122.330411)
			(xy 37.495375 -122.312404) (xy 37.550218 -122.302274) (xy 37.605952 -122.300237) (xy 37.661389 -122.306337)
			(xy 37.715346 -122.320443) (xy 37.766675 -122.342255) (xy 37.814281 -122.371309) (xy 37.857149 -122.406984)
			(xy 37.894366 -122.448521) (xy 37.925139 -122.495034) (xy 37.948811 -122.545531) (xy 37.964879 -122.598938)
			(xy 37.972999 -122.654114) (xy 37.973508 -122.682) (xy 37.972999 -122.709886) (xy 37.964879 -122.765062)
			(xy 37.948811 -122.818469) (xy 37.925139 -122.868966) (xy 37.894366 -122.915479) (xy 37.857149 -122.957016)
			(xy 37.814281 -122.992691) (xy 37.766675 -123.021745) (xy 37.715346 -123.043557) (xy 37.661389 -123.057663)
			(xy 37.605952 -123.063763) (xy 37.550218 -123.061726) (xy 37.495375 -123.051596) (xy 37.442591 -123.033589)
			(xy 37.392991 -123.008088) (xy 37.347633 -122.975637) (xy 37.307484 -122.936928) (xy 37.273398 -122.892785)
			(xy 37.246102 -122.84415) (xy 37.226179 -122.792059) (xy 37.214053 -122.737622) (xy 37.209982 -122.682)
			(xy 27.860963 -122.682) (xy 27.870912 -122.74677) (xy 27.873336 -122.758518) (xy 27.887248 -122.77802)
			(xy 27.897582 -122.784108) (xy 27.925008 -122.798998) (xy 27.975915 -122.835092) (xy 28.021445 -122.87777)
			(xy 28.060753 -122.92624) (xy 28.093109 -122.979602) (xy 28.117912 -123.036866) (xy 28.134704 -123.096969)
			(xy 28.143171 -123.158797) (xy 28.143708 -123.19) (xy 28.143218 -123.219968) (xy 28.135395 -123.27939)
			(xy 28.119882 -123.337283) (xy 28.096946 -123.392656) (xy 28.066979 -123.444562) (xy 28.030492 -123.492112)
			(xy 27.988112 -123.534492) (xy 27.940562 -123.570979) (xy 27.888656 -123.600946) (xy 27.833283 -123.623882)
			(xy 27.77539 -123.639395) (xy 27.715968 -123.647218) (xy 27.686 -123.647708) (xy 27.654424 -123.647177)
			(xy 27.59187 -123.638493) (xy 27.531106 -123.621289) (xy 27.473284 -123.595894) (xy 27.419504 -123.562788)
			(xy 27.370787 -123.522601) (xy 27.328059 -123.476098) (xy 27.292131 -123.42416) (xy 27.263687 -123.367775)
			(xy 27.25293 -123.338082) (xy 27.249643 -123.329663) (xy 27.238203 -123.315688) (xy 27.222633 -123.306536)
			(xy 27.213814 -123.304554) (xy 27.207718 -123.303538) (xy 27.184096 -123.310904) (xy 27.178 -123.317)
			(xy 21.230082 -123.317) (xy 21.220013 -123.316573) (xy 21.201414 -123.308854) (xy 21.194014 -123.302014)
			(xy 19.547586 -121.65584) (xy 19.540216 -121.649096) (xy 19.521754 -121.641502) (xy 19.511772 -121.641108)
			(xy 17.958308 -121.641108) (xy 17.952647 -121.641276) (xy 17.941617 -121.643838) (xy 17.936464 -121.646188)
			(xy 17.894503 -121.665801) (xy 17.808206 -121.699471) (xy 17.719643 -121.726628) (xy 17.629306 -121.747124)
			(xy 17.537695 -121.760843) (xy 17.445317 -121.767711) (xy 17.399 -121.768108) (xy 16.129 -121.768108)
			(xy 16.080099 -121.76764) (xy 15.982599 -121.759965) (xy 15.886002 -121.744662) (xy 15.790904 -121.721826)
			(xy 15.697891 -121.691597) (xy 15.607537 -121.654162) (xy 15.520399 -121.609752) (xy 15.437016 -121.558641)
			(xy 15.3579 -121.501144) (xy 15.283541 -121.437615) (xy 15.248636 -121.403364) (xy 15.128748 -121.283476)
			(xy 15.121636 -121.276364) (xy 15.018004 -121.172732) (xy 15.015153 -121.170026) (xy 15.008775 -121.165433)
			(xy 15.005304 -121.163588) (xy 14.999876 -121.161011) (xy 14.988196 -121.1582) (xy 14.98219 -121.158)
			(xy 12.29233 -121.158) (xy 12.282678 -121.159016) (xy 12.278402 -121.159902) (xy 12.270225 -121.162966)
			(xy 12.266422 -121.165112) (xy 12.226056 -121.192546) (xy 12.141756 -121.241748) (xy 12.09802 -121.26341)
			(xy 12.055822 -121.283294) (xy 11.969 -121.31743) (xy 11.879866 -121.344973) (xy 11.788922 -121.365768)
			(xy 11.696676 -121.379699) (xy 11.603646 -121.386688) (xy 11.557 -121.387108) (xy 3.838702 -121.387108)
			(xy 3.832694 -121.387281) (xy 3.821017 -121.390115) (xy 3.815588 -121.392696) (xy 3.812114 -121.394535)
			(xy 3.805734 -121.399128) (xy 3.802888 -121.40184) (xy 2.91084 -122.293888) (xy 2.908133 -122.296738)
			(xy 2.903539 -122.303116) (xy 2.901696 -122.306588) (xy 2.899118 -122.312016) (xy 2.896305 -122.323696)
			(xy 2.896108 -122.329702) (xy 2.896108 -122.682) (xy 14.095982 -122.682) (xy 14.100053 -122.626378)
			(xy 14.112179 -122.571941) (xy 14.132102 -122.51985) (xy 14.159398 -122.471215) (xy 14.193484 -122.427072)
			(xy 14.233633 -122.388363) (xy 14.278991 -122.355912) (xy 14.328591 -122.330411) (xy 14.381375 -122.312404)
			(xy 14.436218 -122.302274) (xy 14.491952 -122.300237) (xy 14.547389 -122.306337) (xy 14.601346 -122.320443)
			(xy 14.652675 -122.342255) (xy 14.700281 -122.371309) (xy 14.743149 -122.406984) (xy 14.780366 -122.448521)
			(xy 14.811139 -122.495034) (xy 14.834811 -122.545531) (xy 14.850879 -122.598938) (xy 14.858999 -122.654114)
			(xy 14.859508 -122.682) (xy 14.858999 -122.709886) (xy 14.850879 -122.765062) (xy 14.834811 -122.818469)
			(xy 14.811139 -122.868966) (xy 14.780366 -122.915479) (xy 14.743149 -122.957016) (xy 14.700281 -122.992691)
			(xy 14.652675 -123.021745) (xy 14.601346 -123.043557) (xy 14.547389 -123.057663) (xy 14.491952 -123.063763)
			(xy 14.436218 -123.061726) (xy 14.381375 -123.051596) (xy 14.328591 -123.033589) (xy 14.278991 -123.008088)
			(xy 14.233633 -122.975637) (xy 14.193484 -122.936928) (xy 14.159398 -122.892785) (xy 14.132102 -122.84415)
			(xy 14.112179 -122.792059) (xy 14.100053 -122.737622) (xy 14.095982 -122.682) (xy 2.896108 -122.682)
			(xy 2.896108 -124.841) (xy 4.189982 -124.841) (xy 4.194053 -124.785378) (xy 4.206179 -124.730941)
			(xy 4.226102 -124.67885) (xy 4.253398 -124.630215) (xy 4.287484 -124.586072) (xy 4.327633 -124.547363)
			(xy 4.372991 -124.514912) (xy 4.422591 -124.489411) (xy 4.475375 -124.471404) (xy 4.530218 -124.461274)
			(xy 4.585952 -124.459237) (xy 4.641389 -124.465337) (xy 4.695346 -124.479443) (xy 4.746675 -124.501255)
			(xy 4.794281 -124.530309) (xy 4.837149 -124.565984) (xy 4.874366 -124.607521) (xy 4.905139 -124.654034)
			(xy 4.928811 -124.704531) (xy 4.944879 -124.757938) (xy 4.952999 -124.813114) (xy 4.953508 -124.841)
			(xy 4.952999 -124.868886) (xy 4.944879 -124.924062) (xy 4.928811 -124.977469) (xy 4.905139 -125.027966)
			(xy 4.874366 -125.074479) (xy 4.837149 -125.116016) (xy 4.794281 -125.151691) (xy 4.746675 -125.180745)
			(xy 4.695346 -125.202557) (xy 4.641389 -125.216663) (xy 4.585952 -125.222763) (xy 4.530218 -125.220726)
			(xy 4.475375 -125.210596) (xy 4.422591 -125.192589) (xy 4.372991 -125.167088) (xy 4.327633 -125.134637)
			(xy 4.287484 -125.095928) (xy 4.253398 -125.051785) (xy 4.226102 -125.00315) (xy 4.206179 -124.951059)
			(xy 4.194053 -124.896622) (xy 4.189982 -124.841) (xy 2.896108 -124.841) (xy 2.896108 -126.365) (xy 4.825492 -126.365)
			(xy 4.82596 -126.33763) (xy 4.833778 -126.283451) (xy 4.849266 -126.230948) (xy 4.872108 -126.181201)
			(xy 4.901831 -126.135234) (xy 4.919472 -126.114302) (xy 4.919726 -126.114048) (xy 4.925302 -126.106954)
			(xy 4.931554 -126.090043) (xy 4.931918 -126.081028) (xy 4.931918 -126.013972) (xy 4.931571 -126.004954)
			(xy 4.925316 -125.988037) (xy 4.919726 -125.980952) (xy 4.919472 -125.980952) (xy 4.919472 -125.980698)
			(xy 4.901838 -125.959762) (xy 4.872125 -125.91379) (xy 4.849288 -125.864044) (xy 4.833796 -125.811544)
			(xy 4.825967 -125.757369) (xy 4.825492 -125.73) (xy 4.825978 -125.702749) (xy 4.833734 -125.648801)
			(xy 4.849089 -125.596506) (xy 4.871731 -125.546929) (xy 4.901197 -125.501079) (xy 4.936888 -125.459888)
			(xy 4.978079 -125.424197) (xy 5.023929 -125.394731) (xy 5.073506 -125.372089) (xy 5.125801 -125.356734)
			(xy 5.179749 -125.348978) (xy 5.234251 -125.348978) (xy 5.288199 -125.356734) (xy 5.340494 -125.372089)
			(xy 5.390071 -125.394731) (xy 5.435921 -125.424197) (xy 5.477112 -125.459888) (xy 5.512803 -125.501079)
			(xy 5.542269 -125.546929) (xy 5.564911 -125.596506) (xy 5.580266 -125.648801) (xy 5.588022 -125.702749)
			(xy 5.588508 -125.73) (xy 5.58804 -125.75737) (xy 5.580222 -125.811549) (xy 5.564734 -125.864052)
			(xy 5.541892 -125.913799) (xy 5.512169 -125.959766) (xy 5.494528 -125.980698) (xy 5.494274 -125.980952)
			(xy 5.488698 -125.988046) (xy 5.482446 -126.004957) (xy 5.482082 -126.013972) (xy 5.482082 -126.081028)
			(xy 5.482429 -126.090046) (xy 5.488684 -126.106963) (xy 5.494274 -126.114048) (xy 5.494528 -126.114048)
			(xy 5.494528 -126.114302) (xy 5.512186 -126.135219) (xy 5.541894 -126.181196) (xy 5.564726 -126.230948)
			(xy 5.580213 -126.283452) (xy 5.588036 -126.33763) (xy 5.588508 -126.365) (xy 5.588022 -126.392251)
			(xy 5.580266 -126.446199) (xy 5.564911 -126.498494) (xy 5.542269 -126.548071) (xy 5.512803 -126.593921)
			(xy 5.477112 -126.635112) (xy 5.435921 -126.670803) (xy 5.390071 -126.700269) (xy 5.340494 -126.722911)
			(xy 5.288199 -126.738266) (xy 5.234251 -126.746022) (xy 5.179749 -126.746022) (xy 5.125801 -126.738266)
			(xy 5.073506 -126.722911) (xy 5.023929 -126.700269) (xy 4.978079 -126.670803) (xy 4.936888 -126.635112)
			(xy 4.901197 -126.593921) (xy 4.871731 -126.548071) (xy 4.849089 -126.498494) (xy 4.833734 -126.446199)
			(xy 4.825978 -126.392251) (xy 4.825492 -126.365) (xy 2.896108 -126.365) (xy 2.896108 -127.087884)
			(xy 2.89641 -127.095548) (xy 2.901073 -127.110153) (xy 2.905252 -127.116586) (xy 2.920238 -127.13843)
			(xy 2.924508 -127.144215) (xy 2.935594 -127.153363) (xy 2.942082 -127.156464) (xy 2.942336 -127.156464)
			(xy 2.967898 -127.167781) (xy 3.01568 -127.196796) (xy 3.058716 -127.232473) (xy 3.096087 -127.274048)
			(xy 3.12699 -127.320631) (xy 3.150766 -127.371225) (xy 3.166905 -127.424746) (xy 3.175062 -127.480049)
			(xy 3.175062 -127.535951) (xy 3.166905 -127.591254) (xy 3.150766 -127.644775) (xy 3.12699 -127.695369)
			(xy 3.096087 -127.741952) (xy 3.058716 -127.783527) (xy 3.01568 -127.819204) (xy 2.967898 -127.848219)
			(xy 2.942336 -127.859536) (xy 2.942082 -127.859536) (xy 2.935552 -127.862571) (xy 2.924446 -127.871728)
			(xy 2.920238 -127.87757) (xy 2.905252 -127.899414) (xy 2.901126 -127.90587) (xy 2.89648 -127.920463)
			(xy 2.896108 -127.928116) (xy 2.896108 -128.246632) (xy 2.896584 -128.2569) (xy 2.904641 -128.275789)
			(xy 2.919454 -128.290011) (xy 2.928874 -128.29413) (xy 2.954099 -128.304178) (xy 3.001651 -128.330385)
			(xy 3.045009 -128.363068) (xy 3.083296 -128.401567) (xy 3.115739 -128.445105) (xy 3.141682 -128.492802)
			(xy 3.160603 -128.543695) (xy 3.172118 -128.596756) (xy 3.175995 -128.650913) (xy 3.172157 -128.705074)
			(xy 3.160679 -128.758143) (xy 3.141795 -128.809049) (xy 3.115886 -128.856765) (xy 3.083474 -128.900325)
			(xy 3.045215 -128.938852) (xy 3.001881 -128.971566) (xy 2.954347 -128.997807) (xy 2.929128 -129.00787)
			(xy 2.92862 -129.00787) (xy 2.928366 -129.008124) (xy 2.921421 -129.011084) (xy 2.909535 -129.020379)
			(xy 2.904998 -129.026412) (xy 2.90068 -129.033016) (xy 2.896108 -129.04724) (xy 2.896108 -129.373884)
			(xy 2.89641 -129.381548) (xy 2.901073 -129.396153) (xy 2.905252 -129.402586) (xy 2.920238 -129.42443)
			(xy 2.924508 -129.430215) (xy 2.935594 -129.439363) (xy 2.942082 -129.442464) (xy 2.942336 -129.442464)
			(xy 2.967898 -129.453781) (xy 3.01568 -129.482796) (xy 3.058716 -129.518473) (xy 3.096087 -129.560048)
			(xy 3.12699 -129.606631) (xy 3.150766 -129.657225) (xy 3.166905 -129.710746) (xy 3.175062 -129.766049)
			(xy 3.175062 -129.821951) (xy 3.166905 -129.877254) (xy 3.150766 -129.930775) (xy 3.12699 -129.981369)
			(xy 3.096087 -130.027952) (xy 3.058716 -130.069527) (xy 3.01568 -130.105204) (xy 2.967898 -130.134219)
			(xy 2.942336 -130.145536) (xy 2.942082 -130.145536) (xy 2.935552 -130.148571) (xy 2.924446 -130.157728)
			(xy 2.920238 -130.16357) (xy 2.905252 -130.185414) (xy 2.901126 -130.19187) (xy 2.89648 -130.206463)
			(xy 2.896108 -130.214116) (xy 2.896108 -130.470906) (xy 4.73759 -130.470906) (xy 4.73759 -130.41097)
			(xy 4.745413 -130.351548) (xy 4.760926 -130.293655) (xy 4.783862 -130.238282) (xy 4.813829 -130.186376)
			(xy 4.850316 -130.138826) (xy 4.892696 -130.096446) (xy 4.940246 -130.059959) (xy 4.992152 -130.029992)
			(xy 5.047525 -130.007056) (xy 5.105418 -129.991543) (xy 5.16484 -129.98372) (xy 5.224776 -129.98372)
			(xy 5.284198 -129.991543) (xy 5.342091 -130.007056) (xy 5.397464 -130.029992) (xy 5.44937 -130.059959)
			(xy 5.49692 -130.096446) (xy 5.5393 -130.138826) (xy 5.567058 -130.175) (xy 7.110982 -130.175) (xy 7.115053 -130.119378)
			(xy 7.127179 -130.064941) (xy 7.147102 -130.01285) (xy 7.174398 -129.964215) (xy 7.208484 -129.920072)
			(xy 7.248633 -129.881363) (xy 7.293991 -129.848912) (xy 7.343591 -129.823411) (xy 7.396375 -129.805404)
			(xy 7.451218 -129.795274) (xy 7.506952 -129.793237) (xy 7.562389 -129.799337) (xy 7.616346 -129.813443)
			(xy 7.667675 -129.835255) (xy 7.715281 -129.864309) (xy 7.758149 -129.899984) (xy 7.795366 -129.941521)
			(xy 7.826139 -129.988034) (xy 7.849811 -130.038531) (xy 7.865879 -130.091938) (xy 7.873999 -130.147114)
			(xy 7.874508 -130.175) (xy 9.142982 -130.175) (xy 9.147053 -130.119378) (xy 9.159179 -130.064941)
			(xy 9.179102 -130.01285) (xy 9.206398 -129.964215) (xy 9.240484 -129.920072) (xy 9.280633 -129.881363)
			(xy 9.325991 -129.848912) (xy 9.375591 -129.823411) (xy 9.428375 -129.805404) (xy 9.483218 -129.795274)
			(xy 9.538952 -129.793237) (xy 9.594389 -129.799337) (xy 9.648346 -129.813443) (xy 9.699675 -129.835255)
			(xy 9.747281 -129.864309) (xy 9.790149 -129.899984) (xy 9.827366 -129.941521) (xy 9.858139 -129.988034)
			(xy 9.881811 -130.038531) (xy 9.897879 -130.091938) (xy 9.905999 -130.147114) (xy 9.906508 -130.175)
			(xy 9.905999 -130.202886) (xy 9.897879 -130.258062) (xy 9.881811 -130.311469) (xy 9.858139 -130.361966)
			(xy 9.827366 -130.408479) (xy 9.808979 -130.429) (xy 14.076932 -130.429) (xy 14.081003 -130.373378)
			(xy 14.093129 -130.318941) (xy 14.113052 -130.26685) (xy 14.140348 -130.218215) (xy 14.174434 -130.174072)
			(xy 14.214583 -130.135363) (xy 14.259941 -130.102912) (xy 14.309541 -130.077411) (xy 14.362325 -130.059404)
			(xy 14.417168 -130.049274) (xy 14.472902 -130.047237) (xy 14.528339 -130.053337) (xy 14.582296 -130.067443)
			(xy 14.633625 -130.089255) (xy 14.681231 -130.118309) (xy 14.724099 -130.153984) (xy 14.761316 -130.195521)
			(xy 14.792089 -130.242034) (xy 14.815761 -130.292531) (xy 14.831829 -130.345938) (xy 14.839949 -130.401114)
			(xy 14.840458 -130.429) (xy 14.839949 -130.456886) (xy 14.831829 -130.512062) (xy 14.815761 -130.565469)
			(xy 14.792089 -130.615966) (xy 14.761316 -130.662479) (xy 14.724099 -130.704016) (xy 14.681231 -130.739691)
			(xy 14.633625 -130.768745) (xy 14.582296 -130.790557) (xy 14.528339 -130.804663) (xy 14.472902 -130.810763)
			(xy 14.417168 -130.808726) (xy 14.362325 -130.798596) (xy 14.309541 -130.780589) (xy 14.259941 -130.755088)
			(xy 14.214583 -130.722637) (xy 14.174434 -130.683928) (xy 14.140348 -130.639785) (xy 14.113052 -130.59115)
			(xy 14.093129 -130.539059) (xy 14.081003 -130.484622) (xy 14.076932 -130.429) (xy 9.808979 -130.429)
			(xy 9.790149 -130.450016) (xy 9.747281 -130.485691) (xy 9.699675 -130.514745) (xy 9.648346 -130.536557)
			(xy 9.594389 -130.550663) (xy 9.538952 -130.556763) (xy 9.483218 -130.554726) (xy 9.428375 -130.544596)
			(xy 9.375591 -130.526589) (xy 9.325991 -130.501088) (xy 9.280633 -130.468637) (xy 9.240484 -130.429928)
			(xy 9.206398 -130.385785) (xy 9.179102 -130.33715) (xy 9.159179 -130.285059) (xy 9.147053 -130.230622)
			(xy 9.142982 -130.175) (xy 7.874508 -130.175) (xy 7.873999 -130.202886) (xy 7.865879 -130.258062)
			(xy 7.849811 -130.311469) (xy 7.826139 -130.361966) (xy 7.795366 -130.408479) (xy 7.758149 -130.450016)
			(xy 7.715281 -130.485691) (xy 7.667675 -130.514745) (xy 7.616346 -130.536557) (xy 7.562389 -130.550663)
			(xy 7.506952 -130.556763) (xy 7.451218 -130.554726) (xy 7.396375 -130.544596) (xy 7.343591 -130.526589)
			(xy 7.293991 -130.501088) (xy 7.248633 -130.468637) (xy 7.208484 -130.429928) (xy 7.174398 -130.385785)
			(xy 7.147102 -130.33715) (xy 7.127179 -130.285059) (xy 7.115053 -130.230622) (xy 7.110982 -130.175)
			(xy 5.567058 -130.175) (xy 5.575787 -130.186376) (xy 5.605754 -130.238282) (xy 5.62869 -130.293655)
			(xy 5.644203 -130.351548) (xy 5.652026 -130.41097) (xy 5.652516 -130.440938) (xy 5.652026 -130.470906)
			(xy 5.644203 -130.530328) (xy 5.62869 -130.588221) (xy 5.605754 -130.643594) (xy 5.575787 -130.6955)
			(xy 5.5393 -130.74305) (xy 5.49692 -130.78543) (xy 5.44937 -130.821917) (xy 5.397464 -130.851884)
			(xy 5.342091 -130.87482) (xy 5.284198 -130.890333) (xy 5.224776 -130.898156) (xy 5.16484 -130.898156)
			(xy 5.105418 -130.890333) (xy 5.047525 -130.87482) (xy 4.992152 -130.851884) (xy 4.940246 -130.821917)
			(xy 4.892696 -130.78543) (xy 4.850316 -130.74305) (xy 4.813829 -130.6955) (xy 4.783862 -130.643594)
			(xy 4.760926 -130.588221) (xy 4.745413 -130.530328) (xy 4.73759 -130.470906) (xy 2.896108 -130.470906)
			(xy 2.896108 -130.532632) (xy 2.896584 -130.5429) (xy 2.904641 -130.561789) (xy 2.919454 -130.576011)
			(xy 2.928874 -130.58013) (xy 2.954099 -130.590178) (xy 3.001651 -130.616385) (xy 3.045009 -130.649068)
			(xy 3.083296 -130.687567) (xy 3.115739 -130.731105) (xy 3.141682 -130.778802) (xy 3.160603 -130.829695)
			(xy 3.172118 -130.882756) (xy 3.175995 -130.936913) (xy 3.172157 -130.991074) (xy 3.160679 -131.044143)
			(xy 3.141795 -131.095049) (xy 3.115886 -131.142765) (xy 3.083474 -131.186325) (xy 3.045215 -131.224852)
			(xy 3.005942 -131.2545) (xy 12.127482 -131.2545) (xy 12.131553 -131.198878) (xy 12.143679 -131.144441)
			(xy 12.163602 -131.09235) (xy 12.190898 -131.043715) (xy 12.224984 -130.999572) (xy 12.265133 -130.960863)
			(xy 12.310491 -130.928412) (xy 12.360091 -130.902911) (xy 12.412875 -130.884904) (xy 12.467718 -130.874774)
			(xy 12.523452 -130.872737) (xy 12.578889 -130.878837) (xy 12.632846 -130.892943) (xy 12.684175 -130.914755)
			(xy 12.731781 -130.943809) (xy 12.774649 -130.979484) (xy 12.811866 -131.021021) (xy 12.842639 -131.067534)
			(xy 12.866311 -131.118031) (xy 12.882379 -131.171438) (xy 12.890499 -131.226614) (xy 12.891008 -131.2545)
			(xy 12.890499 -131.282386) (xy 12.882379 -131.337562) (xy 12.866311 -131.390969) (xy 12.842639 -131.441466)
			(xy 12.811866 -131.487979) (xy 12.774649 -131.529516) (xy 12.731781 -131.565191) (xy 12.684175 -131.594245)
			(xy 12.632846 -131.616057) (xy 12.578889 -131.630163) (xy 12.523452 -131.636263) (xy 12.467718 -131.634226)
			(xy 12.412875 -131.624096) (xy 12.360091 -131.606089) (xy 12.310491 -131.580588) (xy 12.265133 -131.548137)
			(xy 12.224984 -131.509428) (xy 12.190898 -131.465285) (xy 12.163602 -131.41665) (xy 12.143679 -131.364559)
			(xy 12.131553 -131.310122) (xy 12.127482 -131.2545) (xy 3.005942 -131.2545) (xy 3.001881 -131.257566)
			(xy 2.954347 -131.283807) (xy 2.929128 -131.29387) (xy 2.92862 -131.29387) (xy 2.928366 -131.294124)
			(xy 2.921421 -131.297084) (xy 2.909535 -131.306379) (xy 2.904998 -131.312412) (xy 2.90068 -131.319016)
			(xy 2.896108 -131.33324) (xy 2.896108 -131.675632) (xy 2.896584 -131.6859) (xy 2.902172 -131.699)
			(xy 14.001242 -131.699) (xy 14.001715 -131.669446) (xy 14.009312 -131.610829) (xy 14.024393 -131.553677)
			(xy 14.046707 -131.498943) (xy 14.075882 -131.447538) (xy 14.111433 -131.400316) (xy 14.152767 -131.358065)
			(xy 14.199198 -131.321487) (xy 14.249951 -131.291191) (xy 14.304183 -131.267683) (xy 14.332458 -131.259072)
			(xy 14.338808 -131.257294) (xy 14.34973 -131.250944) (xy 15.069312 -130.531362) (xy 15.08783 -130.513385)
			(xy 15.12877 -130.481959) (xy 15.173459 -130.456142) (xy 15.221134 -130.436374) (xy 15.27098 -130.422994)
			(xy 15.322145 -130.41623) (xy 15.34795 -130.415792) (xy 17.25295 -130.415792) (xy 17.276421 -130.416135)
			(xy 17.323029 -130.421743) (xy 17.345914 -130.426968) (xy 17.35201 -130.428492) (xy 17.519396 -130.428492)
			(xy 17.529418 -130.428077) (xy 17.547936 -130.420407) (xy 17.562109 -130.406233) (xy 17.569778 -130.387714)
			(xy 17.570196 -130.377692) (xy 17.570196 -130.099308) (xy 17.569774 -130.089287) (xy 17.562106 -130.070769)
			(xy 17.547934 -130.056596) (xy 17.529417 -130.048927) (xy 17.519396 -130.048508) (xy 17.35201 -130.048508)
			(xy 17.345914 -130.050032) (xy 17.323029 -130.055255) (xy 17.276421 -130.060855) (xy 17.25295 -130.061208)
			(xy 14.96695 -130.061208) (xy 14.941144 -130.060775) (xy 14.889977 -130.054019) (xy 14.84013 -130.04064)
			(xy 14.792455 -130.02087) (xy 14.747769 -129.995045) (xy 14.706837 -129.963608) (xy 14.688312 -129.945638)
			(xy 14.34973 -129.607056) (xy 14.338808 -129.600706) (xy 14.332458 -129.598928) (xy 14.304167 -129.590369)
			(xy 14.249941 -129.566844) (xy 14.199194 -129.536535) (xy 14.152769 -129.499948) (xy 14.111439 -129.45769)
			(xy 14.075891 -129.410465) (xy 14.046716 -129.359058) (xy 14.024399 -129.304323) (xy 14.009312 -129.247172)
			(xy 14.001705 -129.188555) (xy 14.001242 -129.159) (xy 14.001782 -129.129034) (xy 14.009604 -129.069616)
			(xy 14.025114 -129.011727) (xy 14.048047 -128.956357) (xy 14.078011 -128.904454) (xy 14.114493 -128.856906)
			(xy 14.156868 -128.814526) (xy 14.204412 -128.778039) (xy 14.256312 -128.748069) (xy 14.311679 -128.72513)
			(xy 14.369567 -128.709614) (xy 14.428984 -128.701785) (xy 14.45895 -128.701292) (xy 14.488507 -128.701684)
			(xy 14.547129 -128.709288) (xy 14.604284 -128.724377) (xy 14.659021 -128.7467) (xy 14.710428 -128.775884)
			(xy 14.757649 -128.811444) (xy 14.799899 -128.852787) (xy 14.836475 -128.899227) (xy 14.866766 -128.949989)
			(xy 14.89027 -129.004229) (xy 14.898878 -129.032508) (xy 14.900656 -129.038858) (xy 14.907006 -129.04978)
			(xy 15.115286 -129.25806) (xy 15.122745 -129.264782) (xy 15.141321 -129.272355) (xy 15.151354 -129.272792)
			(xy 17.25295 -129.272792) (xy 17.276421 -129.273135) (xy 17.323029 -129.278743) (xy 17.345914 -129.283968)
			(xy 17.35201 -129.285492) (xy 17.519396 -129.285492) (xy 17.529418 -129.285077) (xy 17.547936 -129.277407)
			(xy 17.562109 -129.263233) (xy 17.569778 -129.244714) (xy 17.570196 -129.234692) (xy 17.570196 -128.956308)
			(xy 17.569774 -128.946287) (xy 17.562106 -128.927769) (xy 17.547934 -128.913596) (xy 17.529417 -128.905927)
			(xy 17.519396 -128.905508) (xy 17.35201 -128.905508) (xy 17.345914 -128.907032) (xy 17.323029 -128.912255)
			(xy 17.276421 -128.917855) (xy 17.25295 -128.918208) (xy 16.49095 -128.918208) (xy 16.465144 -128.917775)
			(xy 16.413977 -128.911019) (xy 16.36413 -128.89764) (xy 16.316455 -128.87787) (xy 16.271769 -128.852045)
			(xy 16.230837 -128.820608) (xy 16.212312 -128.802638) (xy 15.089886 -127.680212) (xy 15.082437 -127.673443)
			(xy 15.063801 -127.665876) (xy 15.043688 -127.666018) (xy 15.03426 -127.669544) (xy 14.933168 -127.71247)
			(xy 14.916404 -127.738632) (xy 14.916658 -127.753872) (xy 14.916658 -127.762) (xy 14.916168 -127.791968)
			(xy 14.908345 -127.85139) (xy 14.892832 -127.909283) (xy 14.869896 -127.964656) (xy 14.839929 -128.016562)
			(xy 14.803442 -128.064112) (xy 14.761062 -128.106492) (xy 14.713512 -128.142979) (xy 14.661606 -128.172946)
			(xy 14.606233 -128.195882) (xy 14.54834 -128.211395) (xy 14.488918 -128.219218) (xy 14.428982 -128.219218)
			(xy 14.36956 -128.211395) (xy 14.311667 -128.195882) (xy 14.256294 -128.172946) (xy 14.204388 -128.142979)
			(xy 14.156838 -128.106492) (xy 14.114458 -128.064112) (xy 14.077971 -128.016562) (xy 14.048004 -127.964656)
			(xy 14.025068 -127.909283) (xy 14.009555 -127.85139) (xy 14.001732 -127.791968) (xy 14.001732 -127.732032)
			(xy 14.009555 -127.67261) (xy 14.025068 -127.614717) (xy 14.048004 -127.559344) (xy 14.077971 -127.507438)
			(xy 14.114458 -127.459888) (xy 14.156838 -127.417508) (xy 14.204388 -127.381021) (xy 14.256294 -127.351054)
			(xy 14.311667 -127.328118) (xy 14.36956 -127.312605) (xy 14.428982 -127.304782) (xy 14.45895 -127.304292)
			(xy 14.467078 -127.304292) (xy 14.482318 -127.304546) (xy 14.50848 -127.287782) (xy 14.551406 -127.18669)
			(xy 14.554967 -127.177268) (xy 14.555129 -127.157141) (xy 14.547528 -127.138505) (xy 14.540738 -127.131064)
			(xy 14.180312 -126.770638) (xy 14.162361 -126.752108) (xy 14.130981 -126.711155) (xy 14.105208 -126.666461)
			(xy 14.085484 -126.618787) (xy 14.072144 -126.568949) (xy 14.065417 -126.517796) (xy 14.064996 -126.492)
			(xy 14.065493 -126.463853) (xy 14.073502 -126.408131) (xy 14.089355 -126.354116) (xy 14.112732 -126.302905)
			(xy 14.143156 -126.25554) (xy 14.180008 -126.212985) (xy 14.22254 -126.176106) (xy 14.269885 -126.145652)
			(xy 14.321081 -126.122243) (xy 14.375087 -126.106355) (xy 14.430803 -126.098311) (xy 14.45895 -126.097792)
			(xy 14.484756 -126.098225) (xy 14.535923 -126.104981) (xy 14.58577 -126.11836) (xy 14.633445 -126.13813)
			(xy 14.678131 -126.163955) (xy 14.719063 -126.195392) (xy 14.737588 -126.213362) (xy 16.639286 -128.114806)
			(xy 16.646696 -128.121633) (xy 16.665288 -128.12936) (xy 16.675354 -128.129792) (xy 17.25295 -128.129792)
			(xy 17.276421 -128.130135) (xy 17.323029 -128.135743) (xy 17.345914 -128.140968) (xy 17.35201 -128.142492)
			(xy 17.519396 -128.142492) (xy 17.529418 -128.142077) (xy 17.547936 -128.134407) (xy 17.562109 -128.120233)
			(xy 17.569778 -128.101714) (xy 17.570196 -128.091692) (xy 17.570196 -127.813308) (xy 17.569774 -127.803287)
			(xy 17.562106 -127.784769) (xy 17.547934 -127.770596) (xy 17.529417 -127.762927) (xy 17.519396 -127.762508)
			(xy 17.35201 -127.762508) (xy 17.345914 -127.764032) (xy 17.323029 -127.769255) (xy 17.276421 -127.774855)
			(xy 17.25295 -127.775208) (xy 16.61795 -127.775208) (xy 16.592144 -127.774775) (xy 16.540977 -127.768019)
			(xy 16.49113 -127.75464) (xy 16.443455 -127.73487) (xy 16.398769 -127.709045) (xy 16.357837 -127.677608)
			(xy 16.339312 -127.659638) (xy 14.180312 -125.500638) (xy 14.162361 -125.482108) (xy 14.130981 -125.441155)
			(xy 14.105208 -125.396461) (xy 14.085484 -125.348787) (xy 14.072144 -125.298949) (xy 14.065417 -125.247796)
			(xy 14.064996 -125.222) (xy 14.065493 -125.193853) (xy 14.073502 -125.138131) (xy 14.089355 -125.084116)
			(xy 14.112732 -125.032905) (xy 14.143156 -124.98554) (xy 14.180008 -124.942985) (xy 14.22254 -124.906106)
			(xy 14.269885 -124.875652) (xy 14.321081 -124.852243) (xy 14.375087 -124.836355) (xy 14.430803 -124.828311)
			(xy 14.45895 -124.827792) (xy 14.484756 -124.828225) (xy 14.535923 -124.834981) (xy 14.58577 -124.84836)
			(xy 14.633445 -124.86813) (xy 14.678131 -124.893955) (xy 14.719063 -124.925392) (xy 14.737588 -124.943362)
			(xy 16.766286 -126.971806) (xy 16.773696 -126.978633) (xy 16.792288 -126.98636) (xy 16.802354 -126.986792)
			(xy 17.25295 -126.986792) (xy 17.276421 -126.987135) (xy 17.323029 -126.992743) (xy 17.345914 -126.997968)
			(xy 17.35201 -126.999492) (xy 17.519396 -126.999492) (xy 17.529418 -126.999077) (xy 17.547936 -126.991407)
			(xy 17.562109 -126.977233) (xy 17.569778 -126.958714) (xy 17.570196 -126.948692) (xy 17.570196 -126.670308)
			(xy 17.569774 -126.660287) (xy 17.562106 -126.641769) (xy 17.547934 -126.627596) (xy 17.529417 -126.619927)
			(xy 17.519396 -126.619508) (xy 17.35201 -126.619508) (xy 17.345914 -126.621032) (xy 17.323029 -126.626255)
			(xy 17.276421 -126.631855) (xy 17.25295 -126.632208) (xy 16.74495 -126.632208) (xy 16.719144 -126.631775)
			(xy 16.667977 -126.625019) (xy 16.61813 -126.61164) (xy 16.570455 -126.59187) (xy 16.525769 -126.566045)
			(xy 16.484837 -126.534608) (xy 16.466312 -126.516638) (xy 14.180312 -124.230638) (xy 14.162361 -124.212108)
			(xy 14.130981 -124.171155) (xy 14.105208 -124.126461) (xy 14.085484 -124.078787) (xy 14.072144 -124.028949)
			(xy 14.065417 -123.977796) (xy 14.064996 -123.952) (xy 14.065493 -123.923853) (xy 14.073502 -123.868131)
			(xy 14.089355 -123.814116) (xy 14.112732 -123.762905) (xy 14.143156 -123.71554) (xy 14.180008 -123.672985)
			(xy 14.22254 -123.636106) (xy 14.269885 -123.605652) (xy 14.321081 -123.582243) (xy 14.375087 -123.566355)
			(xy 14.430803 -123.558311) (xy 14.45895 -123.557792) (xy 14.484756 -123.558225) (xy 14.535923 -123.564981)
			(xy 14.58577 -123.57836) (xy 14.633445 -123.59813) (xy 14.678131 -123.623955) (xy 14.719063 -123.655392)
			(xy 14.737588 -123.673362) (xy 15.143274 -124.079) (xy 26.494992 -124.079) (xy 26.499063 -124.023378)
			(xy 26.511189 -123.968941) (xy 26.531112 -123.91685) (xy 26.558408 -123.868215) (xy 26.592494 -123.824072)
			(xy 26.632643 -123.785363) (xy 26.678001 -123.752912) (xy 26.727601 -123.727411) (xy 26.780385 -123.709404)
			(xy 26.835228 -123.699274) (xy 26.890962 -123.697237) (xy 26.946399 -123.703337) (xy 27.000356 -123.717443)
			(xy 27.051685 -123.739255) (xy 27.099291 -123.768309) (xy 27.142159 -123.803984) (xy 27.179376 -123.845521)
			(xy 27.210149 -123.892034) (xy 27.233821 -123.942531) (xy 27.249889 -123.995938) (xy 27.258009 -124.051114)
			(xy 27.258518 -124.079) (xy 27.258009 -124.106886) (xy 27.249889 -124.162062) (xy 27.233821 -124.215469)
			(xy 27.210149 -124.265966) (xy 27.179376 -124.312479) (xy 27.142159 -124.354016) (xy 27.099291 -124.389691)
			(xy 27.051685 -124.418745) (xy 27.000356 -124.440557) (xy 26.946399 -124.454663) (xy 26.890962 -124.460763)
			(xy 26.835228 -124.458726) (xy 26.780385 -124.448596) (xy 26.727601 -124.430589) (xy 26.678001 -124.405088)
			(xy 26.632643 -124.372637) (xy 26.592494 -124.333928) (xy 26.558408 -124.289785) (xy 26.531112 -124.24115)
			(xy 26.511189 -124.189059) (xy 26.499063 -124.134622) (xy 26.494992 -124.079) (xy 15.143274 -124.079)
			(xy 16.516302 -125.451866) (xy 23.719518 -125.451866) (xy 23.719518 -125.39193) (xy 23.727341 -125.332508)
			(xy 23.742854 -125.274615) (xy 23.76579 -125.219242) (xy 23.795757 -125.167336) (xy 23.832244 -125.119786)
			(xy 23.874624 -125.077406) (xy 23.922174 -125.040919) (xy 23.97408 -125.010952) (xy 24.029453 -124.988016)
			(xy 24.087346 -124.972503) (xy 24.146768 -124.96468) (xy 24.206704 -124.96468) (xy 24.266126 -124.972503)
			(xy 24.324019 -124.988016) (xy 24.379392 -125.010952) (xy 24.431298 -125.040919) (xy 24.478848 -125.077406)
			(xy 24.521228 -125.119786) (xy 24.557715 -125.167336) (xy 24.587682 -125.219242) (xy 24.610618 -125.274615)
			(xy 24.626131 -125.332508) (xy 24.633954 -125.39193) (xy 24.634444 -125.421898) (xy 24.633954 -125.451866)
			(xy 24.626131 -125.511288) (xy 24.610618 -125.569181) (xy 24.587682 -125.624554) (xy 24.557715 -125.67646)
			(xy 24.521228 -125.72401) (xy 24.478848 -125.76639) (xy 24.431298 -125.802877) (xy 24.379392 -125.832844)
			(xy 24.324019 -125.85578) (xy 24.266126 -125.871293) (xy 24.206704 -125.879116) (xy 24.146768 -125.879116)
			(xy 24.087346 -125.871293) (xy 24.029453 -125.85578) (xy 23.97408 -125.832844) (xy 23.922174 -125.802877)
			(xy 23.874624 -125.76639) (xy 23.832244 -125.72401) (xy 23.795757 -125.67646) (xy 23.76579 -125.624554)
			(xy 23.742854 -125.569181) (xy 23.727341 -125.511288) (xy 23.719518 -125.451866) (xy 16.516302 -125.451866)
			(xy 16.893286 -125.828806) (xy 16.900696 -125.835633) (xy 16.919288 -125.84336) (xy 16.929354 -125.843792)
			(xy 17.25295 -125.843792) (xy 17.276421 -125.844135) (xy 17.323029 -125.849743) (xy 17.345914 -125.854968)
			(xy 17.35201 -125.856492) (xy 17.739868 -125.856492) (xy 17.747888 -125.856201) (xy 17.763153 -125.851279)
			(xy 17.76984 -125.84684) (xy 17.794619 -125.829429) (xy 17.847708 -125.800289) (xy 17.904026 -125.778019)
			(xy 17.962687 -125.762968) (xy 18.02277 -125.755374) (xy 18.05305 -125.754892) (xy 18.084654 -125.755409)
			(xy 18.147323 -125.763651) (xy 18.20838 -125.780001) (xy 18.266782 -125.804179) (xy 18.321528 -125.835772)
			(xy 18.371684 -125.874238) (xy 18.416391 -125.918922) (xy 18.454885 -125.969057) (xy 18.486507 -126.023787)
			(xy 18.510716 -126.082175) (xy 18.527098 -126.143224) (xy 18.534382 -126.198376) (xy 26.47391 -126.198376)
			(xy 26.477981 -126.142754) (xy 26.490107 -126.088317) (xy 26.51003 -126.036226) (xy 26.537326 -125.987591)
			(xy 26.571412 -125.943448) (xy 26.611561 -125.904739) (xy 26.656919 -125.872288) (xy 26.706519 -125.846787)
			(xy 26.759303 -125.82878) (xy 26.814146 -125.81865) (xy 26.86988 -125.816613) (xy 26.925317 -125.822713)
			(xy 26.979274 -125.836819) (xy 26.995674 -125.843788) (xy 29.639242 -125.843788) (xy 29.639242 -125.783852)
			(xy 29.647065 -125.72443) (xy 29.662578 -125.666537) (xy 29.685514 -125.611164) (xy 29.715481 -125.559258)
			(xy 29.751968 -125.511708) (xy 29.794348 -125.469328) (xy 29.841898 -125.432841) (xy 29.893804 -125.402874)
			(xy 29.949177 -125.379938) (xy 30.00707 -125.364425) (xy 30.066492 -125.356602) (xy 30.126428 -125.356602)
			(xy 30.18585 -125.364425) (xy 30.243743 -125.379938) (xy 30.299116 -125.402874) (xy 30.351022 -125.432841)
			(xy 30.398572 -125.469328) (xy 30.417686 -125.488442) (xy 31.564562 -125.488442) (xy 31.564562 -125.428506)
			(xy 31.572385 -125.369084) (xy 31.587898 -125.311191) (xy 31.610834 -125.255818) (xy 31.640801 -125.203912)
			(xy 31.677288 -125.156362) (xy 31.719668 -125.113982) (xy 31.767218 -125.077495) (xy 31.819124 -125.047528)
			(xy 31.874497 -125.024592) (xy 31.93239 -125.009079) (xy 31.991812 -125.001256) (xy 32.051748 -125.001256)
			(xy 32.11117 -125.009079) (xy 32.169063 -125.024592) (xy 32.224436 -125.047528) (xy 32.276342 -125.077495)
			(xy 32.323892 -125.113982) (xy 32.366272 -125.156362) (xy 32.402759 -125.203912) (xy 32.432726 -125.255818)
			(xy 32.455662 -125.311191) (xy 32.471175 -125.369084) (xy 32.478998 -125.428506) (xy 32.479488 -125.458474)
			(xy 32.478998 -125.488442) (xy 32.471175 -125.547864) (xy 32.455662 -125.605757) (xy 32.432726 -125.66113)
			(xy 32.402759 -125.713036) (xy 32.366272 -125.760586) (xy 32.323892 -125.802966) (xy 32.276342 -125.839453)
			(xy 32.224436 -125.86942) (xy 32.169063 -125.892356) (xy 32.11117 -125.907869) (xy 32.051748 -125.915692)
			(xy 31.991812 -125.915692) (xy 31.93239 -125.907869) (xy 31.874497 -125.892356) (xy 31.819124 -125.86942)
			(xy 31.767218 -125.839453) (xy 31.719668 -125.802966) (xy 31.677288 -125.760586) (xy 31.640801 -125.713036)
			(xy 31.610834 -125.66113) (xy 31.587898 -125.605757) (xy 31.572385 -125.547864) (xy 31.564562 -125.488442)
			(xy 30.417686 -125.488442) (xy 30.440952 -125.511708) (xy 30.477439 -125.559258) (xy 30.507406 -125.611164)
			(xy 30.530342 -125.666537) (xy 30.545855 -125.72443) (xy 30.553678 -125.783852) (xy 30.554168 -125.81382)
			(xy 30.553678 -125.843788) (xy 30.545855 -125.90321) (xy 30.530342 -125.961103) (xy 30.507406 -126.016476)
			(xy 30.477439 -126.068382) (xy 30.440952 -126.115932) (xy 30.398572 -126.158312) (xy 30.351022 -126.194799)
			(xy 30.299116 -126.224766) (xy 30.243743 -126.247702) (xy 30.18585 -126.263215) (xy 30.126428 -126.271038)
			(xy 30.066492 -126.271038) (xy 30.00707 -126.263215) (xy 29.949177 -126.247702) (xy 29.893804 -126.224766)
			(xy 29.841898 -126.194799) (xy 29.794348 -126.158312) (xy 29.751968 -126.115932) (xy 29.715481 -126.068382)
			(xy 29.685514 -126.016476) (xy 29.662578 -125.961103) (xy 29.647065 -125.90321) (xy 29.639242 -125.843788)
			(xy 26.995674 -125.843788) (xy 27.030603 -125.858631) (xy 27.078209 -125.887685) (xy 27.121077 -125.92336)
			(xy 27.158294 -125.964897) (xy 27.189067 -126.01141) (xy 27.212739 -126.061907) (xy 27.228807 -126.115314)
			(xy 27.236927 -126.17049) (xy 27.237436 -126.198376) (xy 27.236927 -126.226262) (xy 27.228807 -126.281438)
			(xy 27.212739 -126.334845) (xy 27.189067 -126.385342) (xy 27.158294 -126.431855) (xy 27.121077 -126.473392)
			(xy 27.078209 -126.509067) (xy 27.030603 -126.538121) (xy 26.979274 -126.559933) (xy 26.925317 -126.574039)
			(xy 26.86988 -126.580139) (xy 26.814146 -126.578102) (xy 26.759303 -126.567972) (xy 26.706519 -126.549965)
			(xy 26.656919 -126.524464) (xy 26.611561 -126.492013) (xy 26.571412 -126.453304) (xy 26.537326 -126.409161)
			(xy 26.51003 -126.360526) (xy 26.490107 -126.308435) (xy 26.477981 -126.253998) (xy 26.47391 -126.198376)
			(xy 18.534382 -126.198376) (xy 18.535374 -126.205888) (xy 18.535904 -126.237492) (xy 18.535904 -126.976628)
			(xy 28.008562 -126.976628) (xy 28.008562 -126.916692) (xy 28.016385 -126.85727) (xy 28.031898 -126.799377)
			(xy 28.054834 -126.744004) (xy 28.084801 -126.692098) (xy 28.121288 -126.644548) (xy 28.163668 -126.602168)
			(xy 28.211218 -126.565681) (xy 28.263124 -126.535714) (xy 28.318497 -126.512778) (xy 28.37639 -126.497265)
			(xy 28.435812 -126.489442) (xy 28.495748 -126.489442) (xy 28.55517 -126.497265) (xy 28.613063 -126.512778)
			(xy 28.668436 -126.535714) (xy 28.720342 -126.565681) (xy 28.767892 -126.602168) (xy 28.770242 -126.604518)
			(xy 36.201078 -126.604518) (xy 36.201078 -126.544582) (xy 36.208901 -126.48516) (xy 36.224414 -126.427267)
			(xy 36.24735 -126.371894) (xy 36.277317 -126.319988) (xy 36.313804 -126.272438) (xy 36.356184 -126.230058)
			(xy 36.403734 -126.193571) (xy 36.45564 -126.163604) (xy 36.511013 -126.140668) (xy 36.568906 -126.125155)
			(xy 36.628328 -126.117332) (xy 36.688264 -126.117332) (xy 36.747686 -126.125155) (xy 36.805579 -126.140668)
			(xy 36.860952 -126.163604) (xy 36.912858 -126.193571) (xy 36.960408 -126.230058) (xy 37.002788 -126.272438)
			(xy 37.039275 -126.319988) (xy 37.069242 -126.371894) (xy 37.092178 -126.427267) (xy 37.107691 -126.48516)
			(xy 37.115514 -126.544582) (xy 37.116004 -126.57455) (xy 37.115514 -126.604518) (xy 37.107691 -126.66394)
			(xy 37.092178 -126.721833) (xy 37.069242 -126.777206) (xy 37.039275 -126.829112) (xy 37.002788 -126.876662)
			(xy 36.960408 -126.919042) (xy 36.912858 -126.955529) (xy 36.860952 -126.985496) (xy 36.805579 -127.008432)
			(xy 36.747686 -127.023945) (xy 36.688264 -127.031768) (xy 36.628328 -127.031768) (xy 36.568906 -127.023945)
			(xy 36.511013 -127.008432) (xy 36.45564 -126.985496) (xy 36.403734 -126.955529) (xy 36.356184 -126.919042)
			(xy 36.313804 -126.876662) (xy 36.277317 -126.829112) (xy 36.24735 -126.777206) (xy 36.224414 -126.721833)
			(xy 36.208901 -126.66394) (xy 36.201078 -126.604518) (xy 28.770242 -126.604518) (xy 28.810272 -126.644548)
			(xy 28.846759 -126.692098) (xy 28.876726 -126.744004) (xy 28.899662 -126.799377) (xy 28.915175 -126.85727)
			(xy 28.922998 -126.916692) (xy 28.923488 -126.94666) (xy 28.922998 -126.976628) (xy 28.915175 -127.03605)
			(xy 28.899662 -127.093943) (xy 28.876726 -127.149316) (xy 28.846759 -127.201222) (xy 28.810272 -127.248772)
			(xy 28.805044 -127.254) (xy 33.653982 -127.254) (xy 33.658053 -127.198378) (xy 33.670179 -127.143941)
			(xy 33.690102 -127.09185) (xy 33.717398 -127.043215) (xy 33.751484 -126.999072) (xy 33.791633 -126.960363)
			(xy 33.836991 -126.927912) (xy 33.886591 -126.902411) (xy 33.939375 -126.884404) (xy 33.994218 -126.874274)
			(xy 34.049952 -126.872237) (xy 34.105389 -126.878337) (xy 34.159346 -126.892443) (xy 34.210675 -126.914255)
			(xy 34.258281 -126.943309) (xy 34.301149 -126.978984) (xy 34.338366 -127.020521) (xy 34.369139 -127.067034)
			(xy 34.392811 -127.117531) (xy 34.408879 -127.170938) (xy 34.416999 -127.226114) (xy 34.417508 -127.254)
			(xy 34.416999 -127.281886) (xy 34.408879 -127.337062) (xy 34.392811 -127.390469) (xy 34.369139 -127.440966)
			(xy 34.338366 -127.487479) (xy 34.301149 -127.529016) (xy 34.258281 -127.564691) (xy 34.210675 -127.593745)
			(xy 34.159346 -127.615557) (xy 34.105389 -127.629663) (xy 34.049952 -127.635763) (xy 33.994218 -127.633726)
			(xy 33.939375 -127.623596) (xy 33.886591 -127.605589) (xy 33.836991 -127.580088) (xy 33.791633 -127.547637)
			(xy 33.751484 -127.508928) (xy 33.717398 -127.464785) (xy 33.690102 -127.41615) (xy 33.670179 -127.364059)
			(xy 33.658053 -127.309622) (xy 33.653982 -127.254) (xy 28.805044 -127.254) (xy 28.767892 -127.291152)
			(xy 28.720342 -127.327639) (xy 28.668436 -127.357606) (xy 28.613063 -127.380542) (xy 28.55517 -127.396055)
			(xy 28.495748 -127.403878) (xy 28.435812 -127.403878) (xy 28.37639 -127.396055) (xy 28.318497 -127.380542)
			(xy 28.263124 -127.357606) (xy 28.211218 -127.327639) (xy 28.163668 -127.291152) (xy 28.121288 -127.248772)
			(xy 28.084801 -127.201222) (xy 28.054834 -127.149316) (xy 28.031898 -127.093943) (xy 28.016385 -127.03605)
			(xy 28.008562 -126.976628) (xy 18.535904 -126.976628) (xy 18.535904 -127.520188) (xy 24.05429 -127.520188)
			(xy 24.05429 -127.460252) (xy 24.062113 -127.40083) (xy 24.077626 -127.342937) (xy 24.100562 -127.287564)
			(xy 24.130529 -127.235658) (xy 24.167016 -127.188108) (xy 24.209396 -127.145728) (xy 24.256946 -127.109241)
			(xy 24.308852 -127.079274) (xy 24.364225 -127.056338) (xy 24.422118 -127.040825) (xy 24.48154 -127.033002)
			(xy 24.541476 -127.033002) (xy 24.600898 -127.040825) (xy 24.658791 -127.056338) (xy 24.714164 -127.079274)
			(xy 24.76607 -127.109241) (xy 24.81362 -127.145728) (xy 24.856 -127.188108) (xy 24.892487 -127.235658)
			(xy 24.922454 -127.287564) (xy 24.94539 -127.342937) (xy 24.960903 -127.40083) (xy 24.968726 -127.460252)
			(xy 24.969216 -127.49022) (xy 24.968726 -127.520188) (xy 24.960903 -127.57961) (xy 24.94539 -127.637503)
			(xy 24.922454 -127.692876) (xy 24.892487 -127.744782) (xy 24.856 -127.792332) (xy 24.81362 -127.834712)
			(xy 24.76607 -127.871199) (xy 24.714164 -127.901166) (xy 24.658791 -127.924102) (xy 24.600898 -127.939615)
			(xy 24.541476 -127.947438) (xy 24.48154 -127.947438) (xy 24.422118 -127.939615) (xy 24.364225 -127.924102)
			(xy 24.308852 -127.901166) (xy 24.256946 -127.871199) (xy 24.209396 -127.834712) (xy 24.167016 -127.792332)
			(xy 24.130529 -127.744782) (xy 24.100562 -127.692876) (xy 24.077626 -127.637503) (xy 24.062113 -127.57961)
			(xy 24.05429 -127.520188) (xy 18.535904 -127.520188) (xy 18.535904 -128.143) (xy 19.556982 -128.143)
			(xy 19.561053 -128.087378) (xy 19.573179 -128.032941) (xy 19.593102 -127.98085) (xy 19.620398 -127.932215)
			(xy 19.654484 -127.888072) (xy 19.694633 -127.849363) (xy 19.739991 -127.816912) (xy 19.789591 -127.791411)
			(xy 19.842375 -127.773404) (xy 19.897218 -127.763274) (xy 19.952952 -127.761237) (xy 20.008389 -127.767337)
			(xy 20.062346 -127.781443) (xy 20.113675 -127.803255) (xy 20.161281 -127.832309) (xy 20.204149 -127.867984)
			(xy 20.241366 -127.909521) (xy 20.272139 -127.956034) (xy 20.295811 -128.006531) (xy 20.311879 -128.059938)
			(xy 20.319999 -128.115114) (xy 20.320508 -128.143) (xy 21.588982 -128.143) (xy 21.593053 -128.087378)
			(xy 21.605179 -128.032941) (xy 21.625102 -127.98085) (xy 21.652398 -127.932215) (xy 21.686484 -127.888072)
			(xy 21.726633 -127.849363) (xy 21.771991 -127.816912) (xy 21.821591 -127.791411) (xy 21.874375 -127.773404)
			(xy 21.929218 -127.763274) (xy 21.984952 -127.761237) (xy 22.040389 -127.767337) (xy 22.094346 -127.781443)
			(xy 22.145675 -127.803255) (xy 22.193281 -127.832309) (xy 22.236149 -127.867984) (xy 22.273366 -127.909521)
			(xy 22.304139 -127.956034) (xy 22.327811 -128.006531) (xy 22.343879 -128.059938) (xy 22.351999 -128.115114)
			(xy 22.352508 -128.143) (xy 22.351999 -128.170886) (xy 22.343879 -128.226062) (xy 22.327811 -128.279469)
			(xy 22.304139 -128.329966) (xy 22.273366 -128.376479) (xy 22.236149 -128.418016) (xy 22.193281 -128.453691)
			(xy 22.145675 -128.482745) (xy 22.094346 -128.504557) (xy 22.040389 -128.518663) (xy 21.984952 -128.524763)
			(xy 21.929218 -128.522726) (xy 21.874375 -128.512596) (xy 21.821591 -128.494589) (xy 21.771991 -128.469088)
			(xy 21.726633 -128.436637) (xy 21.686484 -128.397928) (xy 21.652398 -128.353785) (xy 21.625102 -128.30515)
			(xy 21.605179 -128.253059) (xy 21.593053 -128.198622) (xy 21.588982 -128.143) (xy 20.320508 -128.143)
			(xy 20.319999 -128.170886) (xy 20.311879 -128.226062) (xy 20.295811 -128.279469) (xy 20.272139 -128.329966)
			(xy 20.241366 -128.376479) (xy 20.204149 -128.418016) (xy 20.161281 -128.453691) (xy 20.113675 -128.482745)
			(xy 20.062346 -128.504557) (xy 20.008389 -128.518663) (xy 19.952952 -128.524763) (xy 19.897218 -128.522726)
			(xy 19.842375 -128.512596) (xy 19.789591 -128.494589) (xy 19.739991 -128.469088) (xy 19.694633 -128.436637)
			(xy 19.654484 -128.397928) (xy 19.620398 -128.353785) (xy 19.593102 -128.30515) (xy 19.573179 -128.253059)
			(xy 19.561053 -128.198622) (xy 19.556982 -128.143) (xy 18.535904 -128.143) (xy 18.535904 -128.739388)
			(xy 24.444942 -128.739388) (xy 24.444942 -128.679452) (xy 24.452765 -128.62003) (xy 24.468278 -128.562137)
			(xy 24.491214 -128.506764) (xy 24.521181 -128.454858) (xy 24.557668 -128.407308) (xy 24.600048 -128.364928)
			(xy 24.647598 -128.328441) (xy 24.699504 -128.298474) (xy 24.754877 -128.275538) (xy 24.81277 -128.260025)
			(xy 24.872192 -128.252202) (xy 24.932128 -128.252202) (xy 24.99155 -128.260025) (xy 25.049443 -128.275538)
			(xy 25.104816 -128.298474) (xy 25.156722 -128.328441) (xy 25.204272 -128.364928) (xy 25.246652 -128.407308)
			(xy 25.283139 -128.454858) (xy 25.313106 -128.506764) (xy 25.332658 -128.553968) (xy 27.736782 -128.553968)
			(xy 27.736782 -128.494032) (xy 27.744605 -128.43461) (xy 27.760118 -128.376717) (xy 27.783054 -128.321344)
			(xy 27.813021 -128.269438) (xy 27.849508 -128.221888) (xy 27.891888 -128.179508) (xy 27.939438 -128.143021)
			(xy 27.991344 -128.113054) (xy 28.046717 -128.090118) (xy 28.10461 -128.074605) (xy 28.164032 -128.066782)
			(xy 28.223968 -128.066782) (xy 28.28339 -128.074605) (xy 28.341283 -128.090118) (xy 28.396656 -128.113054)
			(xy 28.448526 -128.143) (xy 30.097982 -128.143) (xy 30.102053 -128.087378) (xy 30.114179 -128.032941)
			(xy 30.134102 -127.98085) (xy 30.161398 -127.932215) (xy 30.195484 -127.888072) (xy 30.235633 -127.849363)
			(xy 30.280991 -127.816912) (xy 30.330591 -127.791411) (xy 30.383375 -127.773404) (xy 30.438218 -127.763274)
			(xy 30.493952 -127.761237) (xy 30.549389 -127.767337) (xy 30.603346 -127.781443) (xy 30.654675 -127.803255)
			(xy 30.702281 -127.832309) (xy 30.745149 -127.867984) (xy 30.782366 -127.909521) (xy 30.813139 -127.956034)
			(xy 30.836811 -128.006531) (xy 30.852879 -128.059938) (xy 30.860999 -128.115114) (xy 30.861508 -128.143)
			(xy 32.129982 -128.143) (xy 32.134053 -128.087378) (xy 32.146179 -128.032941) (xy 32.166102 -127.98085)
			(xy 32.193398 -127.932215) (xy 32.227484 -127.888072) (xy 32.267633 -127.849363) (xy 32.312991 -127.816912)
			(xy 32.362591 -127.791411) (xy 32.415375 -127.773404) (xy 32.470218 -127.763274) (xy 32.525952 -127.761237)
			(xy 32.581389 -127.767337) (xy 32.635346 -127.781443) (xy 32.686675 -127.803255) (xy 32.734281 -127.832309)
			(xy 32.777149 -127.867984) (xy 32.814366 -127.909521) (xy 32.845139 -127.956034) (xy 32.868811 -128.006531)
			(xy 32.884879 -128.059938) (xy 32.891495 -128.104896) (xy 36.421804 -128.104896) (xy 36.421804 -128.04496)
			(xy 36.429627 -127.985538) (xy 36.44514 -127.927645) (xy 36.468076 -127.872272) (xy 36.498043 -127.820366)
			(xy 36.53453 -127.772816) (xy 36.57691 -127.730436) (xy 36.62446 -127.693949) (xy 36.676366 -127.663982)
			(xy 36.731739 -127.641046) (xy 36.789632 -127.625533) (xy 36.849054 -127.61771) (xy 36.90899 -127.61771)
			(xy 36.968412 -127.625533) (xy 37.026305 -127.641046) (xy 37.081678 -127.663982) (xy 37.133584 -127.693949)
			(xy 37.181134 -127.730436) (xy 37.223514 -127.772816) (xy 37.260001 -127.820366) (xy 37.289968 -127.872272)
			(xy 37.312904 -127.927645) (xy 37.328417 -127.985538) (xy 37.33624 -128.04496) (xy 37.33673 -128.074928)
			(xy 37.33624 -128.104896) (xy 37.328417 -128.164318) (xy 37.312904 -128.222211) (xy 37.289968 -128.277584)
			(xy 37.260001 -128.32949) (xy 37.223514 -128.37704) (xy 37.181134 -128.41942) (xy 37.133584 -128.455907)
			(xy 37.081678 -128.485874) (xy 37.026305 -128.50881) (xy 36.968412 -128.524323) (xy 36.90899 -128.532146)
			(xy 36.849054 -128.532146) (xy 36.789632 -128.524323) (xy 36.731739 -128.50881) (xy 36.676366 -128.485874)
			(xy 36.62446 -128.455907) (xy 36.57691 -128.41942) (xy 36.53453 -128.37704) (xy 36.498043 -128.32949)
			(xy 36.468076 -128.277584) (xy 36.44514 -128.222211) (xy 36.429627 -128.164318) (xy 36.421804 -128.104896)
			(xy 32.891495 -128.104896) (xy 32.892999 -128.115114) (xy 32.893508 -128.143) (xy 32.892999 -128.170886)
			(xy 32.884879 -128.226062) (xy 32.868811 -128.279469) (xy 32.845139 -128.329966) (xy 32.814366 -128.376479)
			(xy 32.777149 -128.418016) (xy 32.734281 -128.453691) (xy 32.686675 -128.482745) (xy 32.635346 -128.504557)
			(xy 32.581389 -128.518663) (xy 32.525952 -128.524763) (xy 32.470218 -128.522726) (xy 32.415375 -128.512596)
			(xy 32.362591 -128.494589) (xy 32.312991 -128.469088) (xy 32.267633 -128.436637) (xy 32.227484 -128.397928)
			(xy 32.193398 -128.353785) (xy 32.166102 -128.30515) (xy 32.146179 -128.253059) (xy 32.134053 -128.198622)
			(xy 32.129982 -128.143) (xy 30.861508 -128.143) (xy 30.860999 -128.170886) (xy 30.852879 -128.226062)
			(xy 30.836811 -128.279469) (xy 30.813139 -128.329966) (xy 30.782366 -128.376479) (xy 30.745149 -128.418016)
			(xy 30.702281 -128.453691) (xy 30.654675 -128.482745) (xy 30.603346 -128.504557) (xy 30.549389 -128.518663)
			(xy 30.493952 -128.524763) (xy 30.438218 -128.522726) (xy 30.383375 -128.512596) (xy 30.330591 -128.494589)
			(xy 30.280991 -128.469088) (xy 30.235633 -128.436637) (xy 30.195484 -128.397928) (xy 30.161398 -128.353785)
			(xy 30.134102 -128.30515) (xy 30.114179 -128.253059) (xy 30.102053 -128.198622) (xy 30.097982 -128.143)
			(xy 28.448526 -128.143) (xy 28.448562 -128.143021) (xy 28.496112 -128.179508) (xy 28.538492 -128.221888)
			(xy 28.574979 -128.269438) (xy 28.604946 -128.321344) (xy 28.627882 -128.376717) (xy 28.643395 -128.43461)
			(xy 28.651218 -128.494032) (xy 28.651708 -128.524) (xy 28.651218 -128.553968) (xy 28.643395 -128.61339)
			(xy 28.627882 -128.671283) (xy 28.604946 -128.726656) (xy 28.574979 -128.778562) (xy 28.538492 -128.826112)
			(xy 28.496112 -128.868492) (xy 28.448562 -128.904979) (xy 28.396656 -128.934946) (xy 28.396603 -128.934968)
			(xy 34.72991 -128.934968) (xy 34.72991 -128.875032) (xy 34.737733 -128.81561) (xy 34.753246 -128.757717)
			(xy 34.776182 -128.702344) (xy 34.806149 -128.650438) (xy 34.842636 -128.602888) (xy 34.885016 -128.560508)
			(xy 34.932566 -128.524021) (xy 34.984472 -128.494054) (xy 35.039845 -128.471118) (xy 35.097738 -128.455605)
			(xy 35.15716 -128.447782) (xy 35.217096 -128.447782) (xy 35.276518 -128.455605) (xy 35.334411 -128.471118)
			(xy 35.389784 -128.494054) (xy 35.44169 -128.524021) (xy 35.48924 -128.560508) (xy 35.53162 -128.602888)
			(xy 35.568107 -128.650438) (xy 35.598074 -128.702344) (xy 35.62101 -128.757717) (xy 35.636523 -128.81561)
			(xy 35.644346 -128.875032) (xy 35.644836 -128.905) (xy 35.644346 -128.934968) (xy 35.636523 -128.99439)
			(xy 35.62101 -129.052283) (xy 35.598074 -129.107656) (xy 35.568107 -129.159562) (xy 35.53162 -129.207112)
			(xy 35.48924 -129.249492) (xy 35.44169 -129.285979) (xy 35.389784 -129.315946) (xy 35.334411 -129.338882)
			(xy 35.276518 -129.354395) (xy 35.248132 -129.358132) (xy 36.203872 -129.358132) (xy 36.203872 -129.298196)
			(xy 36.211695 -129.238774) (xy 36.227208 -129.180881) (xy 36.250144 -129.125508) (xy 36.280111 -129.073602)
			(xy 36.316598 -129.026052) (xy 36.358978 -128.983672) (xy 36.406528 -128.947185) (xy 36.458434 -128.917218)
			(xy 36.513807 -128.894282) (xy 36.5717 -128.878769) (xy 36.631122 -128.870946) (xy 36.691058 -128.870946)
			(xy 36.75048 -128.878769) (xy 36.808373 -128.894282) (xy 36.863746 -128.917218) (xy 36.915652 -128.947185)
			(xy 36.963202 -128.983672) (xy 37.005582 -129.026052) (xy 37.042069 -129.073602) (xy 37.072036 -129.125508)
			(xy 37.094972 -129.180881) (xy 37.110485 -129.238774) (xy 37.118308 -129.298196) (xy 37.118798 -129.328164)
			(xy 37.118308 -129.358132) (xy 37.110485 -129.417554) (xy 37.094972 -129.475447) (xy 37.072036 -129.53082)
			(xy 37.042069 -129.582726) (xy 37.005582 -129.630276) (xy 36.963202 -129.672656) (xy 36.915652 -129.709143)
			(xy 36.863746 -129.73911) (xy 36.808373 -129.762046) (xy 36.75048 -129.777559) (xy 36.691058 -129.785382)
			(xy 36.631122 -129.785382) (xy 36.5717 -129.777559) (xy 36.513807 -129.762046) (xy 36.458434 -129.73911)
			(xy 36.406528 -129.709143) (xy 36.358978 -129.672656) (xy 36.316598 -129.630276) (xy 36.280111 -129.582726)
			(xy 36.250144 -129.53082) (xy 36.227208 -129.475447) (xy 36.211695 -129.417554) (xy 36.203872 -129.358132)
			(xy 35.248132 -129.358132) (xy 35.217096 -129.362218) (xy 35.15716 -129.362218) (xy 35.097738 -129.354395)
			(xy 35.039845 -129.338882) (xy 34.984472 -129.315946) (xy 34.932566 -129.285979) (xy 34.885016 -129.249492)
			(xy 34.842636 -129.207112) (xy 34.806149 -129.159562) (xy 34.776182 -129.107656) (xy 34.753246 -129.052283)
			(xy 34.737733 -128.99439) (xy 34.72991 -128.934968) (xy 28.396603 -128.934968) (xy 28.341283 -128.957882)
			(xy 28.28339 -128.973395) (xy 28.223968 -128.981218) (xy 28.164032 -128.981218) (xy 28.10461 -128.973395)
			(xy 28.046717 -128.957882) (xy 27.991344 -128.934946) (xy 27.939438 -128.904979) (xy 27.891888 -128.868492)
			(xy 27.849508 -128.826112) (xy 27.813021 -128.778562) (xy 27.783054 -128.726656) (xy 27.760118 -128.671283)
			(xy 27.744605 -128.61339) (xy 27.736782 -128.553968) (xy 25.332658 -128.553968) (xy 25.336042 -128.562137)
			(xy 25.351555 -128.62003) (xy 25.359378 -128.679452) (xy 25.359868 -128.70942) (xy 25.359378 -128.739388)
			(xy 25.351555 -128.79881) (xy 25.336042 -128.856703) (xy 25.313106 -128.912076) (xy 25.283139 -128.963982)
			(xy 25.246652 -129.011532) (xy 25.204272 -129.053912) (xy 25.156722 -129.090399) (xy 25.104816 -129.120366)
			(xy 25.049443 -129.143302) (xy 24.99155 -129.158815) (xy 24.932128 -129.166638) (xy 24.872192 -129.166638)
			(xy 24.81277 -129.158815) (xy 24.754877 -129.143302) (xy 24.699504 -129.120366) (xy 24.647598 -129.090399)
			(xy 24.600048 -129.053912) (xy 24.557668 -129.011532) (xy 24.521181 -128.963982) (xy 24.491214 -128.912076)
			(xy 24.468278 -128.856703) (xy 24.452765 -128.79881) (xy 24.444942 -128.739388) (xy 18.535904 -128.739388)
			(xy 18.535904 -130.175) (xy 19.556982 -130.175) (xy 19.561053 -130.119378) (xy 19.573179 -130.064941)
			(xy 19.593102 -130.01285) (xy 19.620398 -129.964215) (xy 19.654484 -129.920072) (xy 19.694633 -129.881363)
			(xy 19.739991 -129.848912) (xy 19.789591 -129.823411) (xy 19.842375 -129.805404) (xy 19.897218 -129.795274)
			(xy 19.952952 -129.793237) (xy 20.008389 -129.799337) (xy 20.062346 -129.813443) (xy 20.113675 -129.835255)
			(xy 20.161281 -129.864309) (xy 20.204149 -129.899984) (xy 20.241366 -129.941521) (xy 20.272139 -129.988034)
			(xy 20.295811 -130.038531) (xy 20.311879 -130.091938) (xy 20.319999 -130.147114) (xy 20.320508 -130.175)
			(xy 21.588982 -130.175) (xy 21.593053 -130.119378) (xy 21.605179 -130.064941) (xy 21.625102 -130.01285)
			(xy 21.652398 -129.964215) (xy 21.686484 -129.920072) (xy 21.726633 -129.881363) (xy 21.771991 -129.848912)
			(xy 21.821591 -129.823411) (xy 21.874375 -129.805404) (xy 21.929218 -129.795274) (xy 21.984952 -129.793237)
			(xy 22.040389 -129.799337) (xy 22.094346 -129.813443) (xy 22.145675 -129.835255) (xy 22.193281 -129.864309)
			(xy 22.236149 -129.899984) (xy 22.273366 -129.941521) (xy 22.304139 -129.988034) (xy 22.327811 -130.038531)
			(xy 22.343879 -130.091938) (xy 22.351999 -130.147114) (xy 22.352508 -130.175) (xy 24.744932 -130.175)
			(xy 24.749003 -130.119378) (xy 24.761129 -130.064941) (xy 24.781052 -130.01285) (xy 24.808348 -129.964215)
			(xy 24.842434 -129.920072) (xy 24.882583 -129.881363) (xy 24.927941 -129.848912) (xy 24.977541 -129.823411)
			(xy 25.030325 -129.805404) (xy 25.085168 -129.795274) (xy 25.140902 -129.793237) (xy 25.196339 -129.799337)
			(xy 25.250296 -129.813443) (xy 25.301625 -129.835255) (xy 25.349231 -129.864309) (xy 25.392099 -129.899984)
			(xy 25.429316 -129.941521) (xy 25.460089 -129.988034) (xy 25.483761 -130.038531) (xy 25.48661 -130.048)
			(xy 27.176982 -130.048) (xy 27.181053 -129.992378) (xy 27.193179 -129.937941) (xy 27.213102 -129.88585)
			(xy 27.240398 -129.837215) (xy 27.274484 -129.793072) (xy 27.314633 -129.754363) (xy 27.359991 -129.721912)
			(xy 27.409591 -129.696411) (xy 27.462375 -129.678404) (xy 27.517218 -129.668274) (xy 27.572952 -129.666237)
			(xy 27.628389 -129.672337) (xy 27.682346 -129.686443) (xy 27.733675 -129.708255) (xy 27.781281 -129.737309)
			(xy 27.824149 -129.772984) (xy 27.861366 -129.814521) (xy 27.892139 -129.861034) (xy 27.915811 -129.911531)
			(xy 27.931879 -129.964938) (xy 27.939999 -130.020114) (xy 27.940508 -130.048) (xy 27.939999 -130.075886)
			(xy 27.931879 -130.131062) (xy 27.91866 -130.175) (xy 30.097982 -130.175) (xy 30.102053 -130.119378)
			(xy 30.114179 -130.064941) (xy 30.134102 -130.01285) (xy 30.161398 -129.964215) (xy 30.195484 -129.920072)
			(xy 30.235633 -129.881363) (xy 30.280991 -129.848912) (xy 30.330591 -129.823411) (xy 30.383375 -129.805404)
			(xy 30.438218 -129.795274) (xy 30.493952 -129.793237) (xy 30.549389 -129.799337) (xy 30.603346 -129.813443)
			(xy 30.654675 -129.835255) (xy 30.702281 -129.864309) (xy 30.745149 -129.899984) (xy 30.782366 -129.941521)
			(xy 30.813139 -129.988034) (xy 30.836811 -130.038531) (xy 30.852879 -130.091938) (xy 30.860999 -130.147114)
			(xy 30.861508 -130.175) (xy 32.129982 -130.175) (xy 32.134053 -130.119378) (xy 32.146179 -130.064941)
			(xy 32.166102 -130.01285) (xy 32.193398 -129.964215) (xy 32.227484 -129.920072) (xy 32.267633 -129.881363)
			(xy 32.312991 -129.848912) (xy 32.362591 -129.823411) (xy 32.415375 -129.805404) (xy 32.470218 -129.795274)
			(xy 32.525952 -129.793237) (xy 32.581389 -129.799337) (xy 32.635346 -129.813443) (xy 32.686675 -129.835255)
			(xy 32.734281 -129.864309) (xy 32.777149 -129.899984) (xy 32.814366 -129.941521) (xy 32.845139 -129.988034)
			(xy 32.868811 -130.038531) (xy 32.884879 -130.091938) (xy 32.892999 -130.147114) (xy 32.893508 -130.175)
			(xy 32.892999 -130.202886) (xy 32.884879 -130.258062) (xy 32.868811 -130.311469) (xy 32.845139 -130.361966)
			(xy 32.814366 -130.408479) (xy 32.777149 -130.450016) (xy 32.734281 -130.485691) (xy 32.686675 -130.514745)
			(xy 32.635346 -130.536557) (xy 32.581389 -130.550663) (xy 32.525952 -130.556763) (xy 32.470218 -130.554726)
			(xy 32.415375 -130.544596) (xy 32.362591 -130.526589) (xy 32.312991 -130.501088) (xy 32.267633 -130.468637)
			(xy 32.227484 -130.429928) (xy 32.193398 -130.385785) (xy 32.166102 -130.33715) (xy 32.146179 -130.285059)
			(xy 32.134053 -130.230622) (xy 32.129982 -130.175) (xy 30.861508 -130.175) (xy 30.860999 -130.202886)
			(xy 30.852879 -130.258062) (xy 30.836811 -130.311469) (xy 30.813139 -130.361966) (xy 30.782366 -130.408479)
			(xy 30.745149 -130.450016) (xy 30.702281 -130.485691) (xy 30.654675 -130.514745) (xy 30.603346 -130.536557)
			(xy 30.549389 -130.550663) (xy 30.493952 -130.556763) (xy 30.438218 -130.554726) (xy 30.383375 -130.544596)
			(xy 30.330591 -130.526589) (xy 30.280991 -130.501088) (xy 30.235633 -130.468637) (xy 30.195484 -130.429928)
			(xy 30.161398 -130.385785) (xy 30.134102 -130.33715) (xy 30.114179 -130.285059) (xy 30.102053 -130.230622)
			(xy 30.097982 -130.175) (xy 27.91866 -130.175) (xy 27.915811 -130.184469) (xy 27.892139 -130.234966)
			(xy 27.861366 -130.281479) (xy 27.824149 -130.323016) (xy 27.781281 -130.358691) (xy 27.733675 -130.387745)
			(xy 27.682346 -130.409557) (xy 27.628389 -130.423663) (xy 27.572952 -130.429763) (xy 27.517218 -130.427726)
			(xy 27.462375 -130.417596) (xy 27.409591 -130.399589) (xy 27.359991 -130.374088) (xy 27.314633 -130.341637)
			(xy 27.274484 -130.302928) (xy 27.240398 -130.258785) (xy 27.213102 -130.21015) (xy 27.193179 -130.158059)
			(xy 27.181053 -130.103622) (xy 27.176982 -130.048) (xy 25.48661 -130.048) (xy 25.499829 -130.091938)
			(xy 25.507949 -130.147114) (xy 25.508458 -130.175) (xy 25.507949 -130.202886) (xy 25.499829 -130.258062)
			(xy 25.483761 -130.311469) (xy 25.460089 -130.361966) (xy 25.429316 -130.408479) (xy 25.392099 -130.450016)
			(xy 25.349231 -130.485691) (xy 25.301625 -130.514745) (xy 25.250296 -130.536557) (xy 25.196339 -130.550663)
			(xy 25.140902 -130.556763) (xy 25.085168 -130.554726) (xy 25.030325 -130.544596) (xy 24.977541 -130.526589)
			(xy 24.927941 -130.501088) (xy 24.882583 -130.468637) (xy 24.842434 -130.429928) (xy 24.808348 -130.385785)
			(xy 24.781052 -130.33715) (xy 24.761129 -130.285059) (xy 24.749003 -130.230622) (xy 24.744932 -130.175)
			(xy 22.352508 -130.175) (xy 22.351999 -130.202886) (xy 22.343879 -130.258062) (xy 22.327811 -130.311469)
			(xy 22.304139 -130.361966) (xy 22.273366 -130.408479) (xy 22.236149 -130.450016) (xy 22.193281 -130.485691)
			(xy 22.145675 -130.514745) (xy 22.094346 -130.536557) (xy 22.040389 -130.550663) (xy 21.984952 -130.556763)
			(xy 21.929218 -130.554726) (xy 21.874375 -130.544596) (xy 21.821591 -130.526589) (xy 21.771991 -130.501088)
			(xy 21.726633 -130.468637) (xy 21.686484 -130.429928) (xy 21.652398 -130.385785) (xy 21.625102 -130.33715)
			(xy 21.605179 -130.285059) (xy 21.593053 -130.230622) (xy 21.588982 -130.175) (xy 20.320508 -130.175)
			(xy 20.319999 -130.202886) (xy 20.311879 -130.258062) (xy 20.295811 -130.311469) (xy 20.272139 -130.361966)
			(xy 20.241366 -130.408479) (xy 20.204149 -130.450016) (xy 20.161281 -130.485691) (xy 20.113675 -130.514745)
			(xy 20.062346 -130.536557) (xy 20.008389 -130.550663) (xy 19.952952 -130.556763) (xy 19.897218 -130.554726)
			(xy 19.842375 -130.544596) (xy 19.789591 -130.526589) (xy 19.739991 -130.501088) (xy 19.694633 -130.468637)
			(xy 19.654484 -130.429928) (xy 19.620398 -130.385785) (xy 19.593102 -130.33715) (xy 19.573179 -130.285059)
			(xy 19.561053 -130.230622) (xy 19.556982 -130.175) (xy 18.535904 -130.175) (xy 18.535904 -130.466084)
			(xy 18.536336 -130.475797) (xy 18.543555 -130.493833) (xy 18.556963 -130.507889) (xy 18.565622 -130.512312)
			(xy 18.663666 -130.556762) (xy 18.692876 -130.552698) (xy 18.704306 -130.542792) (xy 18.725224 -130.525135)
			(xy 18.771201 -130.495426) (xy 18.820952 -130.472594) (xy 18.873456 -130.457107) (xy 18.927634 -130.449284)
			(xy 18.955004 -130.448812) (xy 18.982258 -130.449252) (xy 19.036211 -130.45701) (xy 19.08851 -130.472367)
			(xy 19.138092 -130.495012) (xy 19.183946 -130.524482) (xy 19.225139 -130.560178) (xy 19.260832 -130.601374)
			(xy 19.2903 -130.647229) (xy 19.312941 -130.696812) (xy 19.317684 -130.712968) (xy 38.588932 -130.712968)
			(xy 38.588932 -130.653032) (xy 38.596755 -130.59361) (xy 38.612268 -130.535717) (xy 38.635204 -130.480344)
			(xy 38.665171 -130.428438) (xy 38.701658 -130.380888) (xy 38.744038 -130.338508) (xy 38.791588 -130.302021)
			(xy 38.843494 -130.272054) (xy 38.898867 -130.249118) (xy 38.95676 -130.233605) (xy 39.016182 -130.225782)
			(xy 39.076118 -130.225782) (xy 39.13554 -130.233605) (xy 39.193433 -130.249118) (xy 39.248806 -130.272054)
			(xy 39.300712 -130.302021) (xy 39.348262 -130.338508) (xy 39.390642 -130.380888) (xy 39.427129 -130.428438)
			(xy 39.457096 -130.480344) (xy 39.480032 -130.535717) (xy 39.495545 -130.59361) (xy 39.503368 -130.653032)
			(xy 39.503858 -130.683) (xy 39.503368 -130.712968) (xy 39.495545 -130.77239) (xy 39.480032 -130.830283)
			(xy 39.457096 -130.885656) (xy 39.427129 -130.937562) (xy 39.390642 -130.985112) (xy 39.348262 -131.027492)
			(xy 39.300712 -131.063979) (xy 39.248806 -131.093946) (xy 39.193433 -131.116882) (xy 39.13554 -131.132395)
			(xy 39.076118 -131.140218) (xy 39.016182 -131.140218) (xy 38.95676 -131.132395) (xy 38.898867 -131.116882)
			(xy 38.843494 -131.093946) (xy 38.791588 -131.063979) (xy 38.744038 -131.027492) (xy 38.701658 -130.985112)
			(xy 38.665171 -130.937562) (xy 38.635204 -130.885656) (xy 38.612268 -130.830283) (xy 38.596755 -130.77239)
			(xy 38.588932 -130.712968) (xy 19.317684 -130.712968) (xy 19.328295 -130.749113) (xy 19.33605 -130.803066)
			(xy 19.336512 -130.83032) (xy 19.336512 -130.830574) (xy 19.335841 -130.862626) (xy 19.325118 -130.925826)
			(xy 19.315176 -130.956304) (xy 19.311874 -130.965702) (xy 19.31289 -130.985514) (xy 19.351498 -131.068064)
			(xy 19.365976 -131.081526) (xy 19.375374 -131.084828) (xy 19.40411 -131.096089) (xy 19.458489 -131.125281)
			(xy 19.508452 -131.161515) (xy 19.539338 -131.191) (xy 35.558982 -131.191) (xy 35.563053 -131.135378)
			(xy 35.575179 -131.080941) (xy 35.595102 -131.02885) (xy 35.622398 -130.980215) (xy 35.656484 -130.936072)
			(xy 35.696633 -130.897363) (xy 35.741991 -130.864912) (xy 35.791591 -130.839411) (xy 35.844375 -130.821404)
			(xy 35.899218 -130.811274) (xy 35.954952 -130.809237) (xy 36.010389 -130.815337) (xy 36.064346 -130.829443)
			(xy 36.115675 -130.851255) (xy 36.163281 -130.880309) (xy 36.206149 -130.915984) (xy 36.243366 -130.957521)
			(xy 36.274139 -131.004034) (xy 36.297811 -131.054531) (xy 36.313879 -131.107938) (xy 36.321999 -131.163114)
			(xy 36.322508 -131.191) (xy 36.321999 -131.218886) (xy 36.313879 -131.274062) (xy 36.297811 -131.327469)
			(xy 36.274139 -131.377966) (xy 36.243366 -131.424479) (xy 36.206149 -131.466016) (xy 36.163281 -131.501691)
			(xy 36.115675 -131.530745) (xy 36.064346 -131.552557) (xy 36.010389 -131.566663) (xy 35.954952 -131.572763)
			(xy 35.899218 -131.570726) (xy 35.844375 -131.560596) (xy 35.791591 -131.542589) (xy 35.741991 -131.517088)
			(xy 35.696633 -131.484637) (xy 35.656484 -131.445928) (xy 35.622398 -131.401785) (xy 35.595102 -131.35315)
			(xy 35.575179 -131.301059) (xy 35.563053 -131.246622) (xy 35.558982 -131.191) (xy 19.539338 -131.191)
			(xy 19.553095 -131.204133) (xy 19.591607 -131.252362) (xy 19.623291 -131.305328) (xy 19.64757 -131.362071)
			(xy 19.664007 -131.421561) (xy 19.672302 -131.48272) (xy 19.672808 -131.51358) (xy 19.672318 -131.543548)
			(xy 19.664495 -131.60297) (xy 19.648982 -131.660863) (xy 19.626046 -131.716236) (xy 19.596079 -131.768142)
			(xy 19.559592 -131.815692) (xy 19.517212 -131.858072) (xy 19.469662 -131.894559) (xy 19.417756 -131.924526)
			(xy 19.362383 -131.947462) (xy 19.30449 -131.962975) (xy 19.245068 -131.970798) (xy 19.185132 -131.970798)
			(xy 19.12571 -131.962975) (xy 19.067817 -131.947462) (xy 19.012444 -131.924526) (xy 18.960538 -131.894559)
			(xy 18.912988 -131.858072) (xy 18.870608 -131.815692) (xy 18.834121 -131.768142) (xy 18.804154 -131.716236)
			(xy 18.781218 -131.660863) (xy 18.765705 -131.60297) (xy 18.757882 -131.543548) (xy 18.757392 -131.51358)
			(xy 18.757392 -131.513326) (xy 18.757802 -131.485571) (xy 18.764547 -131.430471) (xy 18.777894 -131.376589)
			(xy 18.797646 -131.324711) (xy 18.810224 -131.299966) (xy 18.814796 -131.291076) (xy 18.816828 -131.271518)
			(xy 18.79092 -131.183888) (xy 18.778728 -131.168902) (xy 18.770092 -131.163822) (xy 18.769584 -131.163822)
			(xy 18.752238 -131.153858) (xy 18.719531 -131.130824) (xy 18.704306 -131.117848) (xy 18.69669 -131.111813)
			(xy 18.678354 -131.105432) (xy 18.65896 -131.106337) (xy 18.64995 -131.109974) (xy 18.565622 -131.148328)
			(xy 18.556986 -131.152789) (xy 18.543574 -131.166829) (xy 18.536342 -131.184848) (xy 18.535904 -131.194556)
			(xy 18.535904 -132.046468) (xy 23.996632 -132.046468) (xy 23.996632 -131.986532) (xy 24.004455 -131.92711)
			(xy 24.019968 -131.869217) (xy 24.042904 -131.813844) (xy 24.072871 -131.761938) (xy 24.109358 -131.714388)
			(xy 24.151738 -131.672008) (xy 24.199288 -131.635521) (xy 24.251194 -131.605554) (xy 24.306567 -131.582618)
			(xy 24.36446 -131.567105) (xy 24.423882 -131.559282) (xy 24.483818 -131.559282) (xy 24.54324 -131.567105)
			(xy 24.601133 -131.582618) (xy 24.656506 -131.605554) (xy 24.708412 -131.635521) (xy 24.755962 -131.672008)
			(xy 24.798342 -131.714388) (xy 24.834829 -131.761938) (xy 24.864796 -131.813844) (xy 24.887732 -131.869217)
			(xy 24.903245 -131.92711) (xy 24.911068 -131.986532) (xy 24.911558 -132.0165) (xy 24.911068 -132.046468)
			(xy 24.903245 -132.10589) (xy 24.887732 -132.163783) (xy 24.864796 -132.219156) (xy 24.834829 -132.271062)
			(xy 24.798342 -132.318612) (xy 24.755962 -132.360992) (xy 24.708412 -132.397479) (xy 24.656506 -132.427446)
			(xy 24.601133 -132.450382) (xy 24.54324 -132.465895) (xy 24.483818 -132.473718) (xy 24.423882 -132.473718)
			(xy 24.36446 -132.465895) (xy 24.306567 -132.450382) (xy 24.251194 -132.427446) (xy 24.199288 -132.397479)
			(xy 24.151738 -132.360992) (xy 24.109358 -132.318612) (xy 24.072871 -132.271062) (xy 24.042904 -132.219156)
			(xy 24.019968 -132.163783) (xy 24.004455 -132.10589) (xy 23.996632 -132.046468) (xy 18.535904 -132.046468)
			(xy 18.535904 -133.00227) (xy 19.683204 -133.00227) (xy 19.683204 -132.942334) (xy 19.691027 -132.882912)
			(xy 19.70654 -132.825019) (xy 19.729476 -132.769646) (xy 19.759443 -132.71774) (xy 19.79593 -132.67019)
			(xy 19.83831 -132.62781) (xy 19.88586 -132.591323) (xy 19.937766 -132.561356) (xy 19.993139 -132.53842)
			(xy 20.051032 -132.522907) (xy 20.110454 -132.515084) (xy 20.17039 -132.515084) (xy 20.229812 -132.522907)
			(xy 20.287705 -132.53842) (xy 20.343078 -132.561356) (xy 20.394984 -132.591323) (xy 20.442534 -132.62781)
			(xy 20.484914 -132.67019) (xy 20.521401 -132.71774) (xy 20.551368 -132.769646) (xy 20.572709 -132.821168)
			(xy 21.767782 -132.821168) (xy 21.767782 -132.761232) (xy 21.775605 -132.70181) (xy 21.791118 -132.643917)
			(xy 21.814054 -132.588544) (xy 21.844021 -132.536638) (xy 21.880508 -132.489088) (xy 21.922888 -132.446708)
			(xy 21.970438 -132.410221) (xy 22.022344 -132.380254) (xy 22.077717 -132.357318) (xy 22.13561 -132.341805)
			(xy 22.195032 -132.333982) (xy 22.254968 -132.333982) (xy 22.31439 -132.341805) (xy 22.372283 -132.357318)
			(xy 22.427656 -132.380254) (xy 22.479562 -132.410221) (xy 22.527112 -132.446708) (xy 22.569492 -132.489088)
			(xy 22.605979 -132.536638) (xy 22.635946 -132.588544) (xy 22.658882 -132.643917) (xy 22.674395 -132.70181)
			(xy 22.682218 -132.761232) (xy 22.682708 -132.7912) (xy 22.682218 -132.821168) (xy 22.674395 -132.88059)
			(xy 22.658882 -132.938483) (xy 22.635946 -132.993856) (xy 22.605979 -133.045762) (xy 22.569492 -133.093312)
			(xy 22.566804 -133.096) (xy 24.744932 -133.096) (xy 24.749003 -133.040378) (xy 24.761129 -132.985941)
			(xy 24.781052 -132.93385) (xy 24.808348 -132.885215) (xy 24.842434 -132.841072) (xy 24.882583 -132.802363)
			(xy 24.927941 -132.769912) (xy 24.977541 -132.744411) (xy 25.030325 -132.726404) (xy 25.085168 -132.716274)
			(xy 25.140902 -132.714237) (xy 25.196339 -132.720337) (xy 25.250296 -132.734443) (xy 25.301625 -132.756255)
			(xy 25.349231 -132.785309) (xy 25.392099 -132.820984) (xy 25.429316 -132.862521) (xy 25.460089 -132.909034)
			(xy 25.483761 -132.959531) (xy 25.499829 -133.012938) (xy 25.507949 -133.068114) (xy 25.508458 -133.096)
			(xy 25.507949 -133.123886) (xy 25.499829 -133.179062) (xy 25.483761 -133.232469) (xy 25.460089 -133.282966)
			(xy 25.429316 -133.329479) (xy 25.392099 -133.371016) (xy 25.349231 -133.406691) (xy 25.301625 -133.435745)
			(xy 25.250296 -133.457557) (xy 25.196339 -133.471663) (xy 25.140902 -133.477763) (xy 25.085168 -133.475726)
			(xy 25.030325 -133.465596) (xy 24.977541 -133.447589) (xy 24.927941 -133.422088) (xy 24.882583 -133.389637)
			(xy 24.842434 -133.350928) (xy 24.808348 -133.306785) (xy 24.781052 -133.25815) (xy 24.761129 -133.206059)
			(xy 24.749003 -133.151622) (xy 24.744932 -133.096) (xy 22.566804 -133.096) (xy 22.527112 -133.135692)
			(xy 22.479562 -133.172179) (xy 22.427656 -133.202146) (xy 22.372283 -133.225082) (xy 22.31439 -133.240595)
			(xy 22.254968 -133.248418) (xy 22.195032 -133.248418) (xy 22.13561 -133.240595) (xy 22.077717 -133.225082)
			(xy 22.022344 -133.202146) (xy 21.970438 -133.172179) (xy 21.922888 -133.135692) (xy 21.880508 -133.093312)
			(xy 21.844021 -133.045762) (xy 21.814054 -132.993856) (xy 21.791118 -132.938483) (xy 21.775605 -132.88059)
			(xy 21.767782 -132.821168) (xy 20.572709 -132.821168) (xy 20.574304 -132.825019) (xy 20.589817 -132.882912)
			(xy 20.59764 -132.942334) (xy 20.59813 -132.972302) (xy 20.59764 -133.00227) (xy 20.589817 -133.061692)
			(xy 20.574304 -133.119585) (xy 20.551368 -133.174958) (xy 20.521401 -133.226864) (xy 20.484914 -133.274414)
			(xy 20.442534 -133.316794) (xy 20.394984 -133.353281) (xy 20.343078 -133.383248) (xy 20.287705 -133.406184)
			(xy 20.229812 -133.421697) (xy 20.17039 -133.42952) (xy 20.110454 -133.42952) (xy 20.051032 -133.421697)
			(xy 19.993139 -133.406184) (xy 19.937766 -133.383248) (xy 19.88586 -133.353281) (xy 19.83831 -133.316794)
			(xy 19.79593 -133.274414) (xy 19.759443 -133.226864) (xy 19.729476 -133.174958) (xy 19.70654 -133.119585)
			(xy 19.691027 -133.061692) (xy 19.683204 -133.00227) (xy 18.535904 -133.00227) (xy 18.535904 -134.041134)
			(xy 18.536082 -134.048008) (xy 18.5397 -134.061271) (xy 18.543016 -134.067296) (xy 18.559145 -134.09538)
			(xy 18.584575 -134.154944) (xy 18.601807 -134.217374) (xy 18.610533 -134.281548) (xy 18.611088 -134.31393)
			(xy 18.611088 -134.493) (xy 29.081982 -134.493) (xy 29.086053 -134.437378) (xy 29.098179 -134.382941)
			(xy 29.118102 -134.33085) (xy 29.145398 -134.282215) (xy 29.179484 -134.238072) (xy 29.219633 -134.199363)
			(xy 29.264991 -134.166912) (xy 29.314591 -134.141411) (xy 29.367375 -134.123404) (xy 29.422218 -134.113274)
			(xy 29.477952 -134.111237) (xy 29.533389 -134.117337) (xy 29.587346 -134.131443) (xy 29.638675 -134.153255)
			(xy 29.686281 -134.182309) (xy 29.729149 -134.217984) (xy 29.766366 -134.259521) (xy 29.797139 -134.306034)
			(xy 29.820811 -134.356531) (xy 29.836879 -134.409938) (xy 29.844999 -134.465114) (xy 29.845508 -134.493)
			(xy 29.844999 -134.520886) (xy 29.836879 -134.576062) (xy 29.820811 -134.629469) (xy 29.797139 -134.679966)
			(xy 29.766366 -134.726479) (xy 29.729149 -134.768016) (xy 29.686281 -134.803691) (xy 29.638675 -134.832745)
			(xy 29.587346 -134.854557) (xy 29.533389 -134.868663) (xy 29.477952 -134.874763) (xy 29.422218 -134.872726)
			(xy 29.367375 -134.862596) (xy 29.314591 -134.844589) (xy 29.264991 -134.819088) (xy 29.219633 -134.786637)
			(xy 29.179484 -134.747928) (xy 29.145398 -134.703785) (xy 29.118102 -134.65515) (xy 29.098179 -134.603059)
			(xy 29.086053 -134.548622) (xy 29.081982 -134.493) (xy 18.611088 -134.493) (xy 18.611088 -135.209276)
			(xy 21.062424 -135.209276) (xy 21.062424 -135.14934) (xy 21.070247 -135.089918) (xy 21.08576 -135.032025)
			(xy 21.108696 -134.976652) (xy 21.138663 -134.924746) (xy 21.17515 -134.877196) (xy 21.21753 -134.834816)
			(xy 21.26508 -134.798329) (xy 21.316986 -134.768362) (xy 21.372359 -134.745426) (xy 21.430252 -134.729913)
			(xy 21.489674 -134.72209) (xy 21.54961 -134.72209) (xy 21.609032 -134.729913) (xy 21.666925 -134.745426)
			(xy 21.722298 -134.768362) (xy 21.774204 -134.798329) (xy 21.821754 -134.834816) (xy 21.864134 -134.877196)
			(xy 21.900621 -134.924746) (xy 21.930588 -134.976652) (xy 21.953524 -135.032025) (xy 21.969037 -135.089918)
			(xy 21.97686 -135.14934) (xy 21.97735 -135.179308) (xy 21.97686 -135.209276) (xy 21.969037 -135.268698)
			(xy 21.953524 -135.326591) (xy 21.930588 -135.381964) (xy 21.900621 -135.43387) (xy 21.864134 -135.48142)
			(xy 21.821754 -135.5238) (xy 21.774204 -135.560287) (xy 21.722298 -135.590254) (xy 21.666925 -135.61319)
			(xy 21.609032 -135.628703) (xy 21.553605 -135.636) (xy 25.545032 -135.636) (xy 25.549103 -135.580378)
			(xy 25.561229 -135.525941) (xy 25.581152 -135.47385) (xy 25.608448 -135.425215) (xy 25.642534 -135.381072)
			(xy 25.682683 -135.342363) (xy 25.728041 -135.309912) (xy 25.777641 -135.284411) (xy 25.830425 -135.266404)
			(xy 25.885268 -135.256274) (xy 25.941002 -135.254237) (xy 25.996439 -135.260337) (xy 26.050396 -135.274443)
			(xy 26.101725 -135.296255) (xy 26.149331 -135.325309) (xy 26.192199 -135.360984) (xy 26.229416 -135.402521)
			(xy 26.260189 -135.449034) (xy 26.283861 -135.499531) (xy 26.299929 -135.552938) (xy 26.308049 -135.608114)
			(xy 26.308558 -135.636) (xy 26.308049 -135.663886) (xy 26.299929 -135.719062) (xy 26.28671 -135.763)
			(xy 37.788342 -135.763) (xy 37.788882 -135.733034) (xy 37.796704 -135.673616) (xy 37.812214 -135.615727)
			(xy 37.835147 -135.560357) (xy 37.865111 -135.508454) (xy 37.901593 -135.460906) (xy 37.943968 -135.418526)
			(xy 37.991512 -135.382039) (xy 38.043412 -135.352069) (xy 38.098779 -135.32913) (xy 38.156667 -135.313614)
			(xy 38.216084 -135.305785) (xy 38.24605 -135.305292) (xy 38.260054 -135.305368) (xy 38.288014 -135.30702)
			(xy 38.30193 -135.308594) (xy 38.31352 -135.309434) (xy 38.335478 -135.301911) (xy 38.344094 -135.294116)
			(xy 38.67531 -134.9629) (xy 38.681406 -134.932674) (xy 38.67531 -134.91845) (xy 38.671123 -134.909375)
			(xy 38.657017 -134.895238) (xy 38.638561 -134.887608) (xy 38.628574 -134.887208) (xy 38.24605 -134.887208)
			(xy 38.217894 -134.886702) (xy 38.162156 -134.878682) (xy 38.108126 -134.862811) (xy 38.056905 -134.839414)
			(xy 38.009535 -134.808965) (xy 37.966979 -134.772085) (xy 37.930105 -134.729525) (xy 37.899662 -134.682151)
			(xy 37.876271 -134.630927) (xy 37.860407 -134.576895) (xy 37.852394 -134.521156) (xy 37.852394 -134.464844)
			(xy 37.860407 -134.409105) (xy 37.876271 -134.355073) (xy 37.899662 -134.303849) (xy 37.930105 -134.256475)
			(xy 37.966979 -134.213915) (xy 38.009535 -134.177035) (xy 38.056905 -134.146586) (xy 38.108126 -134.123189)
			(xy 38.162156 -134.107318) (xy 38.217894 -134.099298) (xy 38.24605 -134.098792) (xy 38.552882 -134.098792)
			(xy 38.56295 -134.098359) (xy 38.581548 -134.090644) (xy 38.58895 -134.083806) (xy 38.8747 -133.79831)
			(xy 38.882801 -133.789187) (xy 38.890236 -133.765989) (xy 38.888924 -133.75386) (xy 38.874954 -133.672326)
			(xy 38.872228 -133.660437) (xy 38.857664 -133.640926) (xy 38.847014 -133.634988) (xy 38.822238 -133.622594)
			(xy 38.775614 -133.592671) (xy 38.732955 -133.557325) (xy 38.694888 -133.517074) (xy 38.678104 -133.495034)
			(xy 38.6715 -133.486144) (xy 38.651688 -133.475222) (xy 38.562788 -133.469888) (xy 38.551678 -133.469702)
			(xy 38.530992 -133.477754) (xy 38.52291 -133.485382) (xy 38.522656 -133.485636) (xy 38.504575 -133.504047)
			(xy 38.464337 -133.536353) (xy 38.420111 -133.562937) (xy 38.372703 -133.583314) (xy 38.32298 -133.597111)
			(xy 38.271851 -133.604077) (xy 38.24605 -133.604508) (xy 38.218801 -133.604019) (xy 38.164859 -133.596257)
			(xy 38.11257 -133.580897) (xy 38.062999 -133.558253) (xy 38.017155 -133.528785) (xy 37.975971 -133.493094)
			(xy 37.940285 -133.451905) (xy 37.910823 -133.406057) (xy 37.888185 -133.356483) (xy 37.872833 -133.304192)
			(xy 37.865078 -133.250249) (xy 37.865078 -133.195751) (xy 37.872833 -133.141808) (xy 37.888185 -133.089517)
			(xy 37.910823 -133.039943) (xy 37.940285 -132.994095) (xy 37.975971 -132.952906) (xy 38.017155 -132.917215)
			(xy 38.062999 -132.887747) (xy 38.11257 -132.865103) (xy 38.164859 -132.849743) (xy 38.218801 -132.841981)
			(xy 38.24605 -132.841492) (xy 38.271851 -132.841937) (xy 38.322983 -132.848892) (xy 38.372709 -132.862681)
			(xy 38.42012 -132.883053) (xy 38.46435 -132.909634) (xy 38.504589 -132.941939) (xy 38.522656 -132.960364)
			(xy 38.52291 -132.960618) (xy 38.530995 -132.968237) (xy 38.55168 -132.976272) (xy 38.562788 -132.976112)
			(xy 38.651688 -132.970778) (xy 38.6715 -132.959856) (xy 38.678104 -132.950966) (xy 38.696669 -132.926691)
			(xy 38.739201 -132.882807) (xy 38.787196 -132.844976) (xy 38.8398 -132.813871) (xy 38.896077 -132.790047)
			(xy 38.955025 -132.773926) (xy 39.015594 -132.765797) (xy 39.04615 -132.765292) (xy 39.075639 -132.765778)
			(xy 39.13413 -132.773348) (xy 39.191164 -132.788369) (xy 39.245795 -132.810592) (xy 39.297119 -132.839648)
			(xy 39.320978 -132.856986) (xy 39.329868 -132.86359) (xy 39.351458 -132.868416) (xy 39.44874 -132.846572)
			(xy 39.46652 -132.833364) (xy 39.4716 -132.823458) (xy 39.485817 -132.797869) (xy 39.520627 -132.750808)
			(xy 39.540942 -132.729732) (xy 39.843456 -132.427218) (xy 39.850137 -132.419804) (xy 39.857737 -132.401372)
			(xy 39.857738 -132.381434) (xy 39.850141 -132.363001) (xy 39.843456 -132.35559) (xy 39.834566 -132.3467)
			(xy 39.810944 -132.339334) (xy 39.798752 -132.341366) (xy 39.782185 -132.344082) (xy 39.748737 -132.347003)
			(xy 39.73195 -132.347208) (xy 38.24605 -132.347208) (xy 38.217894 -132.346702) (xy 38.162156 -132.338682)
			(xy 38.108126 -132.322811) (xy 38.056905 -132.299414) (xy 38.009535 -132.268965) (xy 37.966979 -132.232085)
			(xy 37.930105 -132.189525) (xy 37.899662 -132.142151) (xy 37.876271 -132.090927) (xy 37.860407 -132.036895)
			(xy 37.852394 -131.981156) (xy 37.852394 -131.924844) (xy 37.860407 -131.869105) (xy 37.876271 -131.815073)
			(xy 37.899662 -131.763849) (xy 37.930105 -131.716475) (xy 37.966979 -131.673915) (xy 38.009535 -131.637035)
			(xy 38.056905 -131.606586) (xy 38.108126 -131.583189) (xy 38.162156 -131.567318) (xy 38.217894 -131.559298)
			(xy 38.24605 -131.558792) (xy 39.547546 -131.558792) (xy 39.557612 -131.55834) (xy 39.57621 -131.550638)
			(xy 39.583614 -131.543806) (xy 40.122856 -131.004818) (xy 40.129675 -130.997401) (xy 40.137408 -130.978815)
			(xy 40.137842 -130.96875) (xy 40.137842 -130.937) (xy 40.138289 -130.920274) (xy 40.146949 -130.887964)
			(xy 40.163678 -130.858996) (xy 40.187336 -130.835348) (xy 40.21631 -130.81863) (xy 40.248624 -130.809982)
			(xy 40.26535 -130.809492) (xy 40.39489 -130.809492) (xy 40.400986 -130.807968) (xy 40.423871 -130.802745)
			(xy 40.470479 -130.797145) (xy 40.49395 -130.796792) (xy 40.517421 -130.797135) (xy 40.564029 -130.802743)
			(xy 40.586914 -130.807968) (xy 40.59301 -130.809492) (xy 40.760396 -130.809492) (xy 40.770418 -130.809077)
			(xy 40.788936 -130.801407) (xy 40.803109 -130.787233) (xy 40.810778 -130.768714) (xy 40.811196 -130.758692)
			(xy 40.811196 -130.480308) (xy 40.810774 -130.470287) (xy 40.803106 -130.451769) (xy 40.788934 -130.437596)
			(xy 40.770417 -130.429927) (xy 40.760396 -130.429508) (xy 40.59301 -130.429508) (xy 40.586914 -130.431032)
			(xy 40.564029 -130.436255) (xy 40.517421 -130.441855) (xy 40.49395 -130.442208) (xy 40.470479 -130.441865)
			(xy 40.423871 -130.436257) (xy 40.400986 -130.431032) (xy 40.39489 -130.429508) (xy 40.26535 -130.429508)
			(xy 40.248631 -130.428967) (xy 40.21633 -130.420324) (xy 40.187367 -130.403612) (xy 40.163718 -130.379973)
			(xy 40.146996 -130.351017) (xy 40.138339 -130.318719) (xy 40.137842 -130.302) (xy 40.137842 -130.27025)
			(xy 40.137406 -130.260182) (xy 40.129694 -130.241583) (xy 40.122856 -130.234182) (xy 39.710614 -129.822194)
			(xy 39.703204 -129.815367) (xy 39.684612 -129.80764) (xy 39.674546 -129.807208) (xy 38.24605 -129.807208)
			(xy 38.217894 -129.806702) (xy 38.162156 -129.798682) (xy 38.108126 -129.782811) (xy 38.056905 -129.759414)
			(xy 38.009535 -129.728965) (xy 37.966979 -129.692085) (xy 37.930105 -129.649525) (xy 37.899662 -129.602151)
			(xy 37.876271 -129.550927) (xy 37.860407 -129.496895) (xy 37.852394 -129.441156) (xy 37.852394 -129.384844)
			(xy 37.860407 -129.329105) (xy 37.876271 -129.275073) (xy 37.899662 -129.223849) (xy 37.930105 -129.176475)
			(xy 37.966979 -129.133915) (xy 38.009535 -129.097035) (xy 38.056905 -129.066586) (xy 38.108126 -129.043189)
			(xy 38.162156 -129.027318) (xy 38.217894 -129.019298) (xy 38.24605 -129.018792) (xy 39.85895 -129.018792)
			(xy 39.875736 -129.019008) (xy 39.909183 -129.021934) (xy 39.925752 -129.024634) (xy 39.937944 -129.026666)
			(xy 39.961566 -129.0193) (xy 39.970456 -129.01041) (xy 39.977197 -129.003016) (xy 39.984811 -128.984533)
			(xy 39.984746 -128.964543) (xy 39.977013 -128.94611) (xy 39.970202 -128.938782) (xy 39.583614 -128.552194)
			(xy 39.576204 -128.545367) (xy 39.557612 -128.53764) (xy 39.547546 -128.537208) (xy 38.49243 -128.537208)
			(xy 38.485989 -128.537387) (xy 38.473516 -128.5406) (xy 38.467792 -128.543558) (xy 38.442308 -128.557148)
			(xy 38.388649 -128.578511) (xy 38.332728 -128.592956) (xy 38.275436 -128.600252) (xy 38.246558 -128.600708)
			(xy 38.24605 -128.600708) (xy 38.216084 -128.600215) (xy 38.156667 -128.592386) (xy 38.098779 -128.57687)
			(xy 38.043412 -128.553931) (xy 37.991512 -128.523961) (xy 37.943968 -128.487474) (xy 37.901593 -128.445094)
			(xy 37.865111 -128.397546) (xy 37.835147 -128.345643) (xy 37.812214 -128.290273) (xy 37.796704 -128.232384)
			(xy 37.788882 -128.172966) (xy 37.788882 -128.113034) (xy 37.796704 -128.053616) (xy 37.812214 -127.995727)
			(xy 37.835147 -127.940357) (xy 37.865111 -127.888454) (xy 37.901593 -127.840906) (xy 37.943968 -127.798526)
			(xy 37.991512 -127.762039) (xy 38.043412 -127.732069) (xy 38.098779 -127.70913) (xy 38.156667 -127.693614)
			(xy 38.216084 -127.685785) (xy 38.24605 -127.685292) (xy 38.246558 -127.685292) (xy 38.275436 -127.685726)
			(xy 38.332731 -127.693026) (xy 38.388651 -127.707477) (xy 38.442308 -127.72885) (xy 38.467792 -127.742442)
			(xy 38.473526 -127.745376) (xy 38.485992 -127.748598) (xy 38.49243 -127.748792) (xy 39.73195 -127.748792)
			(xy 39.748736 -127.749008) (xy 39.782183 -127.751934) (xy 39.798752 -127.754634) (xy 39.810944 -127.756666)
			(xy 39.834566 -127.7493) (xy 39.843456 -127.74041) (xy 39.850197 -127.733016) (xy 39.857811 -127.714533)
			(xy 39.857746 -127.694543) (xy 39.850013 -127.67611) (xy 39.843202 -127.668782) (xy 39.456614 -127.282194)
			(xy 39.449204 -127.275367) (xy 39.430612 -127.26764) (xy 39.420546 -127.267208) (xy 38.24605 -127.267208)
			(xy 38.217894 -127.266702) (xy 38.162156 -127.258682) (xy 38.108126 -127.242811) (xy 38.056905 -127.219414)
			(xy 38.009535 -127.188965) (xy 37.966979 -127.152085) (xy 37.930105 -127.109525) (xy 37.899662 -127.062151)
			(xy 37.876271 -127.010927) (xy 37.860407 -126.956895) (xy 37.852394 -126.901156) (xy 37.852394 -126.844844)
			(xy 37.860407 -126.789105) (xy 37.876271 -126.735073) (xy 37.899662 -126.683849) (xy 37.930105 -126.636475)
			(xy 37.966979 -126.593915) (xy 38.009535 -126.557035) (xy 38.056905 -126.526586) (xy 38.108126 -126.503189)
			(xy 38.162156 -126.487318) (xy 38.217894 -126.479298) (xy 38.24605 -126.478792) (xy 39.60495 -126.478792)
			(xy 39.621736 -126.479008) (xy 39.655183 -126.481934) (xy 39.671752 -126.484634) (xy 39.683944 -126.486666)
			(xy 39.707566 -126.4793) (xy 39.716456 -126.47041) (xy 39.723145 -126.463002) (xy 39.730744 -126.444567)
			(xy 39.730743 -126.424627) (xy 39.723142 -126.406193) (xy 39.716456 -126.398782) (xy 38.798246 -125.480826)
			(xy 38.790435 -125.473832) (xy 38.770942 -125.466179) (xy 38.750012 -125.466892) (xy 38.740334 -125.47092)
			(xy 38.639242 -125.51918) (xy 38.623748 -125.54712) (xy 38.625526 -125.563122) (xy 38.626491 -125.573063)
			(xy 38.627506 -125.593012) (xy 38.627558 -125.603) (xy 38.627045 -125.630254) (xy 38.619287 -125.684206)
			(xy 38.60393 -125.736505) (xy 38.581287 -125.786086) (xy 38.551817 -125.83194) (xy 38.516122 -125.873133)
			(xy 38.474927 -125.908827) (xy 38.429072 -125.938295) (xy 38.37949 -125.960936) (xy 38.32719 -125.976291)
			(xy 38.273237 -125.984046) (xy 38.21873 -125.984043) (xy 38.164778 -125.976284) (xy 38.112479 -125.960925)
			(xy 38.062899 -125.938279) (xy 38.017046 -125.908807) (xy 37.975855 -125.87311) (xy 37.940163 -125.831914)
			(xy 37.910697 -125.786057) (xy 37.888058 -125.736474) (xy 37.872706 -125.684173) (xy 37.864953 -125.63022)
			(xy 37.864958 -125.575713) (xy 37.87272 -125.521761) (xy 37.888081 -125.469464) (xy 37.910729 -125.419884)
			(xy 37.940203 -125.374033) (xy 37.975902 -125.332843) (xy 38.0171 -125.297153) (xy 38.062958 -125.267689)
			(xy 38.112542 -125.245052) (xy 38.164843 -125.229702) (xy 38.218796 -125.221952) (xy 38.24605 -125.221492)
			(xy 38.256038 -125.221543) (xy 38.275987 -125.222558) (xy 38.285928 -125.223524) (xy 38.30193 -125.225302)
			(xy 38.32987 -125.209808) (xy 38.37813 -125.108716) (xy 38.382275 -125.099058) (xy 38.383061 -125.078075)
			(xy 38.375325 -125.058555) (xy 38.368224 -125.050804) (xy 37.948362 -124.630688) (xy 37.930385 -124.61217)
			(xy 37.898959 -124.57123) (xy 37.873142 -124.526541) (xy 37.853374 -124.478866) (xy 37.839994 -124.42902)
			(xy 37.83323 -124.377855) (xy 37.832792 -124.35205) (xy 37.832792 -124.333) (xy 37.833294 -124.304842)
			(xy 37.841309 -124.249098) (xy 37.857175 -124.195062) (xy 37.88057 -124.143835) (xy 37.911017 -124.096458)
			(xy 37.947897 -124.053897) (xy 37.990458 -124.017017) (xy 38.037835 -123.98657) (xy 38.089062 -123.963175)
			(xy 38.143098 -123.947309) (xy 38.198842 -123.939294) (xy 38.227 -123.938792) (xy 38.256079 -123.939268)
			(xy 38.313606 -123.947805) (xy 38.369252 -123.96471) (xy 38.421807 -123.989614) (xy 38.470128 -124.021976)
			(xy 38.513165 -124.061092) (xy 38.549982 -124.106111) (xy 38.565328 -124.130816) (xy 38.56863 -124.13615)
			(xy 40.654732 -126.222506) (xy 40.662126 -126.229353) (xy 40.68073 -126.237069) (xy 40.6908 -126.237492)
			(xy 40.980868 -126.237492) (xy 40.988888 -126.237201) (xy 41.004153 -126.232279) (xy 41.01084 -126.22784)
			(xy 41.035619 -126.210429) (xy 41.088708 -126.181289) (xy 41.145026 -126.159019) (xy 41.203687 -126.143968)
			(xy 41.26377 -126.136374) (xy 41.29405 -126.135892) (xy 41.325654 -126.136409) (xy 41.388323 -126.144651)
			(xy 41.44938 -126.161001) (xy 41.507782 -126.185179) (xy 41.562528 -126.216772) (xy 41.612684 -126.255238)
			(xy 41.657391 -126.299922) (xy 41.695885 -126.350057) (xy 41.727507 -126.404787) (xy 41.751716 -126.463175)
			(xy 41.768098 -126.524224) (xy 41.776374 -126.586888) (xy 41.776904 -126.618492) (xy 41.776904 -128.143)
			(xy 42.797982 -128.143) (xy 42.802053 -128.087378) (xy 42.814179 -128.032941) (xy 42.834102 -127.98085)
			(xy 42.861398 -127.932215) (xy 42.895484 -127.888072) (xy 42.935633 -127.849363) (xy 42.980991 -127.816912)
			(xy 43.030591 -127.791411) (xy 43.083375 -127.773404) (xy 43.138218 -127.763274) (xy 43.193952 -127.761237)
			(xy 43.249389 -127.767337) (xy 43.303346 -127.781443) (xy 43.354675 -127.803255) (xy 43.402281 -127.832309)
			(xy 43.445149 -127.867984) (xy 43.482366 -127.909521) (xy 43.513139 -127.956034) (xy 43.536811 -128.006531)
			(xy 43.552879 -128.059938) (xy 43.560999 -128.115114) (xy 43.561508 -128.143) (xy 43.560999 -128.170886)
			(xy 43.552879 -128.226062) (xy 43.536811 -128.279469) (xy 43.513139 -128.329966) (xy 43.482366 -128.376479)
			(xy 43.445149 -128.418016) (xy 43.402281 -128.453691) (xy 43.354675 -128.482745) (xy 43.303346 -128.504557)
			(xy 43.249389 -128.518663) (xy 43.193952 -128.524763) (xy 43.138218 -128.522726) (xy 43.083375 -128.512596)
			(xy 43.030591 -128.494589) (xy 42.980991 -128.469088) (xy 42.935633 -128.436637) (xy 42.895484 -128.397928)
			(xy 42.861398 -128.353785) (xy 42.834102 -128.30515) (xy 42.814179 -128.253059) (xy 42.802053 -128.198622)
			(xy 42.797982 -128.143) (xy 41.776904 -128.143) (xy 41.776904 -130.556) (xy 42.543982 -130.556) (xy 42.548053 -130.500378)
			(xy 42.560179 -130.445941) (xy 42.580102 -130.39385) (xy 42.607398 -130.345215) (xy 42.641484 -130.301072)
			(xy 42.681633 -130.262363) (xy 42.726991 -130.229912) (xy 42.776591 -130.204411) (xy 42.829375 -130.186404)
			(xy 42.884218 -130.176274) (xy 42.939952 -130.174237) (xy 42.995389 -130.180337) (xy 43.049346 -130.194443)
			(xy 43.100675 -130.216255) (xy 43.148281 -130.245309) (xy 43.191149 -130.280984) (xy 43.228366 -130.322521)
			(xy 43.259139 -130.369034) (xy 43.282811 -130.419531) (xy 43.298879 -130.472938) (xy 43.306999 -130.528114)
			(xy 43.307508 -130.556) (xy 44.575982 -130.556) (xy 44.580053 -130.500378) (xy 44.592179 -130.445941)
			(xy 44.612102 -130.39385) (xy 44.639398 -130.345215) (xy 44.673484 -130.301072) (xy 44.713633 -130.262363)
			(xy 44.758991 -130.229912) (xy 44.808591 -130.204411) (xy 44.861375 -130.186404) (xy 44.916218 -130.176274)
			(xy 44.971952 -130.174237) (xy 45.027389 -130.180337) (xy 45.081346 -130.194443) (xy 45.132675 -130.216255)
			(xy 45.180281 -130.245309) (xy 45.223149 -130.280984) (xy 45.260366 -130.322521) (xy 45.291139 -130.369034)
			(xy 45.314811 -130.419531) (xy 45.330879 -130.472938) (xy 45.338999 -130.528114) (xy 45.339508 -130.556)
			(xy 45.338999 -130.583886) (xy 45.330879 -130.639062) (xy 45.314811 -130.692469) (xy 45.291139 -130.742966)
			(xy 45.260366 -130.789479) (xy 45.223149 -130.831016) (xy 45.180281 -130.866691) (xy 45.132675 -130.895745)
			(xy 45.081346 -130.917557) (xy 45.027389 -130.931663) (xy 44.971952 -130.937763) (xy 44.916218 -130.935726)
			(xy 44.861375 -130.925596) (xy 44.808591 -130.907589) (xy 44.758991 -130.882088) (xy 44.713633 -130.849637)
			(xy 44.673484 -130.810928) (xy 44.639398 -130.766785) (xy 44.612102 -130.71815) (xy 44.592179 -130.666059)
			(xy 44.580053 -130.611622) (xy 44.575982 -130.556) (xy 43.307508 -130.556) (xy 43.306999 -130.583886)
			(xy 43.298879 -130.639062) (xy 43.282811 -130.692469) (xy 43.259139 -130.742966) (xy 43.228366 -130.789479)
			(xy 43.191149 -130.831016) (xy 43.148281 -130.866691) (xy 43.100675 -130.895745) (xy 43.049346 -130.917557)
			(xy 42.995389 -130.931663) (xy 42.939952 -130.937763) (xy 42.884218 -130.935726) (xy 42.829375 -130.925596)
			(xy 42.776591 -130.907589) (xy 42.726991 -130.882088) (xy 42.681633 -130.849637) (xy 42.641484 -130.810928)
			(xy 42.607398 -130.766785) (xy 42.580102 -130.71815) (xy 42.560179 -130.666059) (xy 42.548053 -130.611622)
			(xy 42.543982 -130.556) (xy 41.776904 -130.556) (xy 41.776904 -132.588) (xy 42.543982 -132.588) (xy 42.548053 -132.532378)
			(xy 42.560179 -132.477941) (xy 42.580102 -132.42585) (xy 42.607398 -132.377215) (xy 42.641484 -132.333072)
			(xy 42.681633 -132.294363) (xy 42.726991 -132.261912) (xy 42.776591 -132.236411) (xy 42.829375 -132.218404)
			(xy 42.884218 -132.208274) (xy 42.939952 -132.206237) (xy 42.995389 -132.212337) (xy 43.049346 -132.226443)
			(xy 43.100675 -132.248255) (xy 43.148281 -132.277309) (xy 43.191149 -132.312984) (xy 43.228366 -132.354521)
			(xy 43.259139 -132.401034) (xy 43.282811 -132.451531) (xy 43.298879 -132.504938) (xy 43.306999 -132.560114)
			(xy 43.307508 -132.588) (xy 44.575982 -132.588) (xy 44.580053 -132.532378) (xy 44.592179 -132.477941)
			(xy 44.612102 -132.42585) (xy 44.639398 -132.377215) (xy 44.673484 -132.333072) (xy 44.713633 -132.294363)
			(xy 44.758991 -132.261912) (xy 44.808591 -132.236411) (xy 44.861375 -132.218404) (xy 44.916218 -132.208274)
			(xy 44.971952 -132.206237) (xy 45.027389 -132.212337) (xy 45.081346 -132.226443) (xy 45.132675 -132.248255)
			(xy 45.180281 -132.277309) (xy 45.223149 -132.312984) (xy 45.260366 -132.354521) (xy 45.291139 -132.401034)
			(xy 45.314811 -132.451531) (xy 45.330879 -132.504938) (xy 45.338999 -132.560114) (xy 45.339508 -132.588)
			(xy 45.338999 -132.615886) (xy 45.330879 -132.671062) (xy 45.314811 -132.724469) (xy 45.291139 -132.774966)
			(xy 45.260366 -132.821479) (xy 45.223149 -132.863016) (xy 45.180281 -132.898691) (xy 45.132675 -132.927745)
			(xy 45.081346 -132.949557) (xy 45.027389 -132.963663) (xy 44.971952 -132.969763) (xy 44.916218 -132.967726)
			(xy 44.861375 -132.957596) (xy 44.808591 -132.939589) (xy 44.758991 -132.914088) (xy 44.713633 -132.881637)
			(xy 44.673484 -132.842928) (xy 44.639398 -132.798785) (xy 44.612102 -132.75015) (xy 44.592179 -132.698059)
			(xy 44.580053 -132.643622) (xy 44.575982 -132.588) (xy 43.307508 -132.588) (xy 43.306999 -132.615886)
			(xy 43.298879 -132.671062) (xy 43.282811 -132.724469) (xy 43.259139 -132.774966) (xy 43.228366 -132.821479)
			(xy 43.191149 -132.863016) (xy 43.148281 -132.898691) (xy 43.100675 -132.927745) (xy 43.049346 -132.949557)
			(xy 42.995389 -132.963663) (xy 42.939952 -132.969763) (xy 42.884218 -132.967726) (xy 42.829375 -132.957596)
			(xy 42.776591 -132.939589) (xy 42.726991 -132.914088) (xy 42.681633 -132.881637) (xy 42.641484 -132.842928)
			(xy 42.607398 -132.798785) (xy 42.580102 -132.75015) (xy 42.560179 -132.698059) (xy 42.548053 -132.643622)
			(xy 42.543982 -132.588) (xy 41.776904 -132.588) (xy 41.776904 -134.525508) (xy 42.009042 -134.525508)
			(xy 42.009042 -134.465572) (xy 42.016865 -134.40615) (xy 42.032378 -134.348257) (xy 42.055314 -134.292884)
			(xy 42.085281 -134.240978) (xy 42.121768 -134.193428) (xy 42.164148 -134.151048) (xy 42.211698 -134.114561)
			(xy 42.263604 -134.084594) (xy 42.318977 -134.061658) (xy 42.37687 -134.046145) (xy 42.436292 -134.038322)
			(xy 42.496228 -134.038322) (xy 42.55565 -134.046145) (xy 42.613543 -134.061658) (xy 42.668916 -134.084594)
			(xy 42.720822 -134.114561) (xy 42.768372 -134.151048) (xy 42.810752 -134.193428) (xy 42.847239 -134.240978)
			(xy 42.877206 -134.292884) (xy 42.900142 -134.348257) (xy 42.915655 -134.40615) (xy 42.923478 -134.465572)
			(xy 42.923968 -134.49554) (xy 42.923478 -134.525508) (xy 42.915655 -134.58493) (xy 42.900142 -134.642823)
			(xy 42.877206 -134.698196) (xy 42.847239 -134.750102) (xy 42.810752 -134.797652) (xy 42.768372 -134.840032)
			(xy 42.720822 -134.876519) (xy 42.668916 -134.906486) (xy 42.613543 -134.929422) (xy 42.55565 -134.944935)
			(xy 42.496228 -134.952758) (xy 42.436292 -134.952758) (xy 42.37687 -134.944935) (xy 42.318977 -134.929422)
			(xy 42.263604 -134.906486) (xy 42.211698 -134.876519) (xy 42.164148 -134.840032) (xy 42.121768 -134.797652)
			(xy 42.085281 -134.750102) (xy 42.055314 -134.698196) (xy 42.032378 -134.642823) (xy 42.016865 -134.58493)
			(xy 42.009042 -134.525508) (xy 41.776904 -134.525508) (xy 41.776904 -135.833866) (xy 41.77732 -135.843937)
			(xy 41.785044 -135.862536) (xy 41.79189 -135.869934) (xy 41.831013 -135.90905) (xy 45.083982 -135.90905)
			(xy 45.088053 -135.853428) (xy 45.100179 -135.798991) (xy 45.120102 -135.7469) (xy 45.147398 -135.698265)
			(xy 45.181484 -135.654122) (xy 45.221633 -135.615413) (xy 45.266991 -135.582962) (xy 45.316591 -135.557461)
			(xy 45.369375 -135.539454) (xy 45.424218 -135.529324) (xy 45.479952 -135.527287) (xy 45.535389 -135.533387)
			(xy 45.589346 -135.547493) (xy 45.640675 -135.569305) (xy 45.688281 -135.598359) (xy 45.731149 -135.634034)
			(xy 45.768366 -135.675571) (xy 45.799139 -135.722084) (xy 45.822811 -135.772581) (xy 45.838879 -135.825988)
			(xy 45.846999 -135.881164) (xy 45.847508 -135.90905) (xy 45.846999 -135.936936) (xy 45.838879 -135.992112)
			(xy 45.822811 -136.045519) (xy 45.799139 -136.096016) (xy 45.768366 -136.142529) (xy 45.731149 -136.184066)
			(xy 45.688281 -136.219741) (xy 45.640675 -136.248795) (xy 45.589346 -136.270607) (xy 45.535389 -136.284713)
			(xy 45.479952 -136.290813) (xy 45.424218 -136.288776) (xy 45.369375 -136.278646) (xy 45.316591 -136.260639)
			(xy 45.266991 -136.235138) (xy 45.221633 -136.202687) (xy 45.181484 -136.163978) (xy 45.147398 -136.119835)
			(xy 45.120102 -136.0712) (xy 45.100179 -136.019109) (xy 45.088053 -135.964672) (xy 45.083982 -135.90905)
			(xy 41.831013 -135.90905) (xy 43.26763 -137.34542) (xy 43.289621 -137.368161) (xy 43.328124 -137.418356)
			(xy 43.359749 -137.473146) (xy 43.383955 -137.531593) (xy 43.400328 -137.592699) (xy 43.408588 -137.655419)
			(xy 43.409108 -137.68705) (xy 43.408612 -137.718677) (xy 43.400358 -137.78139) (xy 43.383986 -137.842488)
			(xy 43.359776 -137.900925) (xy 43.328141 -137.955699) (xy 43.289625 -138.005874) (xy 43.244886 -138.05059)
			(xy 43.194691 -138.08908) (xy 43.1399 -138.120686) (xy 43.081451 -138.144867) (xy 43.020344 -138.161207)
			(xy 42.957627 -138.169428) (xy 42.926 -138.169904) (xy 42.894375 -138.169421) (xy 42.83166 -138.161216)
			(xy 42.770553 -138.144893) (xy 42.7121 -138.120732) (xy 42.657302 -138.089146) (xy 42.607097 -138.050677)
			(xy 42.58437 -138.02868) (xy 40.95242 -136.39673) (xy 40.930496 -136.374025) (xy 40.892102 -136.323928)
			(xy 40.860557 -136.269259) (xy 40.836397 -136.210949) (xy 40.820034 -136.14999) (xy 40.811745 -136.08742)
			(xy 40.811196 -136.055862) (xy 40.811196 -135.052308) (xy 40.810774 -135.042287) (xy 40.803106 -135.023769)
			(xy 40.788934 -135.009596) (xy 40.770417 -135.001927) (xy 40.760396 -135.001508) (xy 40.6908 -135.001508)
			(xy 40.680731 -135.001932) (xy 40.662133 -135.009653) (xy 40.654732 -135.016494) (xy 38.647624 -137.023602)
			(xy 38.640004 -137.040874) (xy 38.63975 -137.050272) (xy 38.638162 -137.077599) (xy 38.628219 -137.131428)
			(xy 38.610925 -137.183365) (xy 38.586611 -137.232409) (xy 38.555746 -137.277617) (xy 38.518922 -137.31812)
			(xy 38.476849 -137.353139) (xy 38.430335 -137.381999) (xy 38.380275 -137.404147) (xy 38.327633 -137.419155)
			(xy 38.27342 -137.426736) (xy 38.24605 -137.427208) (xy 38.217918 -137.426799) (xy 38.162227 -137.418788)
			(xy 38.108242 -137.402936) (xy 38.057061 -137.379566) (xy 38.009725 -137.349152) (xy 37.967197 -137.312315)
			(xy 37.930342 -137.269801) (xy 37.89991 -137.222478) (xy 37.876519 -137.171306) (xy 37.860645 -137.117328)
			(xy 37.852612 -137.06164) (xy 37.852096 -137.033508) (xy 37.852096 -136.8679) (xy 37.852526 -136.842104)
			(xy 37.859245 -136.790952) (xy 37.872582 -136.741113) (xy 37.892309 -136.693442) (xy 37.918088 -136.648752)
			(xy 37.949478 -136.607808) (xy 37.967412 -136.589262) (xy 38.179756 -136.376664) (xy 38.185774 -136.370066)
			(xy 38.193258 -136.353867) (xy 38.194735 -136.336084) (xy 38.19271 -136.327388) (xy 38.169596 -136.242298)
			(xy 38.166906 -136.23373) (xy 38.156467 -136.219128) (xy 38.141637 -136.209016) (xy 38.13302 -136.206484)
			(xy 38.103845 -136.198486) (xy 38.047699 -136.17597) (xy 37.995009 -136.146252) (xy 37.946696 -136.10985)
			(xy 37.9036 -136.067399) (xy 37.866473 -136.019639) (xy 37.835964 -135.967403) (xy 37.812604 -135.911603)
			(xy 37.796801 -135.853211) (xy 37.78883 -135.793246) (xy 37.788342 -135.763) (xy 26.28671 -135.763)
			(xy 26.283861 -135.772469) (xy 26.260189 -135.822966) (xy 26.229416 -135.869479) (xy 26.192199 -135.911016)
			(xy 26.149331 -135.946691) (xy 26.101725 -135.975745) (xy 26.050396 -135.997557) (xy 25.996439 -136.011663)
			(xy 25.941002 -136.017763) (xy 25.885268 -136.015726) (xy 25.830425 -136.005596) (xy 25.777641 -135.987589)
			(xy 25.728041 -135.962088) (xy 25.682683 -135.929637) (xy 25.642534 -135.890928) (xy 25.608448 -135.846785)
			(xy 25.581152 -135.79815) (xy 25.561229 -135.746059) (xy 25.549103 -135.691622) (xy 25.545032 -135.636)
			(xy 21.553605 -135.636) (xy 21.54961 -135.636526) (xy 21.489674 -135.636526) (xy 21.430252 -135.628703)
			(xy 21.372359 -135.61319) (xy 21.316986 -135.590254) (xy 21.26508 -135.560287) (xy 21.21753 -135.5238)
			(xy 21.17515 -135.48142) (xy 21.138663 -135.43387) (xy 21.108696 -135.381964) (xy 21.08576 -135.326591)
			(xy 21.070247 -135.268698) (xy 21.062424 -135.209276) (xy 18.611088 -135.209276) (xy 18.611088 -135.68807)
			(xy 18.610574 -135.719703) (xy 18.602331 -135.782429) (xy 18.585967 -135.843542) (xy 18.561765 -135.901995)
			(xy 18.530138 -135.956788) (xy 18.491627 -136.006982) (xy 18.46961 -136.0297) (xy 17.74063 -136.75868)
			(xy 17.717925 -136.780604) (xy 17.667828 -136.818998) (xy 17.613159 -136.850543) (xy 17.554849 -136.874703)
			(xy 17.49389 -136.891066) (xy 17.43132 -136.899355) (xy 17.399762 -136.899904) (xy 17.399 -136.899904)
			(xy 17.36738 -136.899392) (xy 17.30468 -136.89114) (xy 17.243593 -136.874777) (xy 17.185163 -136.850584)
			(xy 17.13039 -136.818973) (xy 17.080209 -136.780485) (xy 17.03548 -136.735779) (xy 16.996966 -136.685619)
			(xy 16.965327 -136.630862) (xy 16.941103 -136.572444) (xy 16.924709 -136.511366) (xy 16.916425 -136.44867)
			(xy 16.915892 -136.41705) (xy 16.916395 -136.385417) (xy 16.924638 -136.322689) (xy 16.941001 -136.261575)
			(xy 16.965206 -136.203122) (xy 16.996836 -136.148329) (xy 17.035351 -136.098137) (xy 17.05737 -136.07542)
			(xy 17.136364 -135.996426) (xy 17.144169 -135.987958) (xy 17.151833 -135.966263) (xy 17.151096 -135.95477)
			(xy 17.140682 -135.863838) (xy 17.12849 -135.844534) (xy 17.11833 -135.838184) (xy 17.093861 -135.822504)
			(xy 17.048745 -135.785868) (xy 17.008632 -135.743813) (xy 16.974168 -135.697016) (xy 16.945909 -135.646231)
			(xy 16.92431 -135.592276) (xy 16.909718 -135.53602) (xy 16.902368 -135.478369) (xy 16.901922 -135.44931)
			(xy 16.902371 -135.41934) (xy 16.910193 -135.359913) (xy 16.925707 -135.302015) (xy 16.948645 -135.246637)
			(xy 16.978615 -135.194728) (xy 17.015105 -135.147175) (xy 17.05749 -135.104792) (xy 17.105045 -135.068304)
			(xy 17.156955 -135.038336) (xy 17.212334 -135.0154) (xy 17.270232 -134.999889) (xy 17.32966 -134.992069)
			(xy 17.35963 -134.991602) (xy 17.385172 -134.991957) (xy 17.43594 -134.99764) (xy 17.485758 -135.008944)
			(xy 17.509998 -135.017002) (xy 17.521743 -135.020354) (xy 17.545886 -135.0169) (xy 17.556226 -135.010398)
			(xy 17.623536 -134.962392) (xy 17.633048 -134.954782) (xy 17.644182 -134.933153) (xy 17.644872 -134.92099)
			(xy 17.644872 -134.671308) (xy 17.644473 -134.661284) (xy 17.636801 -134.642762) (xy 17.622622 -134.628588)
			(xy 17.604096 -134.620923) (xy 17.594072 -134.620508) (xy 17.35201 -134.620508) (xy 17.345914 -134.622032)
			(xy 17.323029 -134.627255) (xy 17.276421 -134.632855) (xy 17.25295 -134.633208) (xy 17.202404 -134.633208)
			(xy 17.192335 -134.633634) (xy 17.173737 -134.641354) (xy 17.166336 -134.648194) (xy 14.926056 -136.88822)
			(xy 14.919706 -136.899142) (xy 14.917928 -136.905492) (xy 14.909338 -136.933773) (xy 14.885818 -136.988)
			(xy 14.855514 -137.038748) (xy 14.818931 -137.085174) (xy 14.776678 -137.126506) (xy 14.729456 -137.162055)
			(xy 14.678051 -137.191232) (xy 14.623319 -137.21355) (xy 14.56617 -137.228638) (xy 14.507554 -137.236245)
			(xy 14.478 -137.236708) (xy 14.448032 -137.236218) (xy 14.38861 -137.228395) (xy 14.330717 -137.212882)
			(xy 14.275344 -137.189946) (xy 14.223438 -137.159979) (xy 14.175888 -137.123492) (xy 14.133508 -137.081112)
			(xy 14.097021 -137.033562) (xy 14.067054 -136.981656) (xy 14.044118 -136.926283) (xy 14.028605 -136.86839)
			(xy 14.020782 -136.808968) (xy 14.020292 -136.779) (xy 14.020729 -136.749445) (xy 14.028327 -136.690824)
			(xy 14.04341 -136.63367) (xy 14.065727 -136.578934) (xy 14.094905 -136.527527) (xy 14.13046 -136.480305)
			(xy 14.1718 -136.438054) (xy 14.218235 -136.401478) (xy 14.268994 -136.371185) (xy 14.32323 -136.34768)
			(xy 14.351508 -136.339072) (xy 14.357858 -136.337294) (xy 14.36878 -136.330944) (xy 16.739362 -133.960362)
			(xy 16.757902 -133.94241) (xy 16.798837 -133.910981) (xy 16.843521 -133.88516) (xy 16.891192 -133.865388)
			(xy 16.941034 -133.852003) (xy 16.992196 -133.845233) (xy 17.018 -133.844792) (xy 17.25295 -133.844792)
			(xy 17.276421 -133.845135) (xy 17.323029 -133.850743) (xy 17.345914 -133.855968) (xy 17.35201 -133.857492)
			(xy 17.519396 -133.857492) (xy 17.529418 -133.857077) (xy 17.547936 -133.849407) (xy 17.562109 -133.835233)
			(xy 17.569778 -133.816714) (xy 17.570196 -133.806692) (xy 17.570196 -133.528308) (xy 17.569774 -133.518287)
			(xy 17.562106 -133.499769) (xy 17.547934 -133.485596) (xy 17.529417 -133.477927) (xy 17.519396 -133.477508)
			(xy 17.35201 -133.477508) (xy 17.345914 -133.479032) (xy 17.323029 -133.484255) (xy 17.276421 -133.489855)
			(xy 17.25295 -133.490208) (xy 16.76273 -133.490208) (xy 16.752662 -133.490647) (xy 16.734064 -133.498358)
			(xy 16.726662 -133.505194) (xy 15.713964 -134.517638) (xy 15.695412 -134.535578) (xy 15.65448 -134.567008)
			(xy 15.609798 -134.59283) (xy 15.56213 -134.612604) (xy 15.51229 -134.625992) (xy 15.461129 -134.632766)
			(xy 15.435326 -134.633208) (xy 14.70533 -134.633208) (xy 14.698889 -134.633387) (xy 14.686416 -134.6366)
			(xy 14.680692 -134.639558) (xy 14.655208 -134.653148) (xy 14.601549 -134.674511) (xy 14.545628 -134.688956)
			(xy 14.488336 -134.696252) (xy 14.459458 -134.696708) (xy 14.45895 -134.696708) (xy 14.428982 -134.696218)
			(xy 14.36956 -134.688395) (xy 14.311667 -134.672882) (xy 14.256294 -134.649946) (xy 14.204388 -134.619979)
			(xy 14.156838 -134.583492) (xy 14.114458 -134.541112) (xy 14.077971 -134.493562) (xy 14.048004 -134.441656)
			(xy 14.025068 -134.386283) (xy 14.009555 -134.32839) (xy 14.001732 -134.268968) (xy 14.001732 -134.209032)
			(xy 14.009555 -134.14961) (xy 14.025068 -134.091717) (xy 14.048004 -134.036344) (xy 14.077971 -133.984438)
			(xy 14.114458 -133.936888) (xy 14.156838 -133.894508) (xy 14.204388 -133.858021) (xy 14.256294 -133.828054)
			(xy 14.311667 -133.805118) (xy 14.36956 -133.789605) (xy 14.428982 -133.781782) (xy 14.45895 -133.781292)
			(xy 14.459458 -133.781292) (xy 14.488336 -133.781726) (xy 14.545631 -133.789026) (xy 14.601551 -133.803477)
			(xy 14.655208 -133.82485) (xy 14.680692 -133.838442) (xy 14.686426 -133.841376) (xy 14.698892 -133.844598)
			(xy 14.70533 -133.844792) (xy 15.250922 -133.844792) (xy 15.260993 -133.84438) (xy 15.279591 -133.83665)
			(xy 15.28699 -133.829806) (xy 16.299688 -132.817362) (xy 16.318216 -132.799397) (xy 16.359154 -132.76797)
			(xy 16.403841 -132.742151) (xy 16.451514 -132.722381) (xy 16.501358 -132.708998) (xy 16.552522 -132.702231)
			(xy 16.578326 -132.701792) (xy 17.25295 -132.701792) (xy 17.276421 -132.702135) (xy 17.323029 -132.707743)
			(xy 17.345914 -132.712968) (xy 17.35201 -132.714492) (xy 17.519396 -132.714492) (xy 17.529418 -132.714077)
			(xy 17.547936 -132.706407) (xy 17.562109 -132.692233) (xy 17.569778 -132.673714) (xy 17.570196 -132.663692)
			(xy 17.570196 -132.385308) (xy 17.569774 -132.375287) (xy 17.562106 -132.356769) (xy 17.547934 -132.342596)
			(xy 17.529417 -132.334927) (xy 17.519396 -132.334508) (xy 17.35201 -132.334508) (xy 17.345914 -132.336032)
			(xy 17.323029 -132.341255) (xy 17.276421 -132.346855) (xy 17.25295 -132.347208) (xy 16.344138 -132.347208)
			(xy 16.334071 -132.347651) (xy 16.315473 -132.355359) (xy 16.30807 -132.362194) (xy 15.422372 -133.247638)
			(xy 15.403817 -133.265574) (xy 15.362885 -133.297004) (xy 15.318204 -133.322827) (xy 15.270536 -133.342602)
			(xy 15.220697 -133.355991) (xy 15.169537 -133.362765) (xy 15.143734 -133.363208) (xy 14.70533 -133.363208)
			(xy 14.698889 -133.363387) (xy 14.686416 -133.3666) (xy 14.680692 -133.369558) (xy 14.655208 -133.383148)
			(xy 14.601549 -133.404511) (xy 14.545628 -133.418956) (xy 14.488336 -133.426252) (xy 14.459458 -133.426708)
			(xy 14.45895 -133.426708) (xy 14.428982 -133.426218) (xy 14.36956 -133.418395) (xy 14.311667 -133.402882)
			(xy 14.256294 -133.379946) (xy 14.204388 -133.349979) (xy 14.156838 -133.313492) (xy 14.114458 -133.271112)
			(xy 14.077971 -133.223562) (xy 14.048004 -133.171656) (xy 14.025068 -133.116283) (xy 14.009555 -133.05839)
			(xy 14.001732 -132.998968) (xy 14.001732 -132.939032) (xy 14.009555 -132.87961) (xy 14.025068 -132.821717)
			(xy 14.048004 -132.766344) (xy 14.077971 -132.714438) (xy 14.114458 -132.666888) (xy 14.156838 -132.624508)
			(xy 14.204388 -132.588021) (xy 14.256294 -132.558054) (xy 14.311667 -132.535118) (xy 14.36956 -132.519605)
			(xy 14.428982 -132.511782) (xy 14.45895 -132.511292) (xy 14.459458 -132.511292) (xy 14.488336 -132.511726)
			(xy 14.545631 -132.519026) (xy 14.601551 -132.533477) (xy 14.655208 -132.55485) (xy 14.680692 -132.568442)
			(xy 14.686426 -132.571376) (xy 14.698892 -132.574598) (xy 14.70533 -132.574792) (xy 14.95933 -132.574792)
			(xy 14.969401 -132.574384) (xy 14.987999 -132.566652) (xy 14.995398 -132.559806) (xy 15.881096 -131.674362)
			(xy 15.899621 -131.656393) (xy 15.940559 -131.624966) (xy 15.985247 -131.599148) (xy 16.03292 -131.579379)
			(xy 16.082765 -131.565997) (xy 16.133929 -131.559231) (xy 16.159734 -131.558792) (xy 17.25295 -131.558792)
			(xy 17.276421 -131.559135) (xy 17.323029 -131.564743) (xy 17.345914 -131.569968) (xy 17.35201 -131.571492)
			(xy 17.519396 -131.571492) (xy 17.529418 -131.571077) (xy 17.547936 -131.563407) (xy 17.562109 -131.549233)
			(xy 17.569778 -131.530714) (xy 17.570196 -131.520692) (xy 17.570196 -131.242308) (xy 17.569774 -131.232287)
			(xy 17.562106 -131.213769) (xy 17.547934 -131.199596) (xy 17.529417 -131.191927) (xy 17.519396 -131.191508)
			(xy 17.35201 -131.191508) (xy 17.345914 -131.193032) (xy 17.323029 -131.198255) (xy 17.276421 -131.203855)
			(xy 17.25295 -131.204208) (xy 15.532354 -131.204208) (xy 15.522288 -131.20466) (xy 15.50369 -131.212362)
			(xy 15.496286 -131.219194) (xy 14.907006 -131.80822) (xy 14.900656 -131.819142) (xy 14.898878 -131.825492)
			(xy 14.890243 -131.853758) (xy 14.866727 -131.907982) (xy 14.836427 -131.958729) (xy 14.799849 -132.005154)
			(xy 14.7576 -132.046486) (xy 14.710384 -132.082037) (xy 14.658985 -132.111216) (xy 14.604258 -132.133537)
			(xy 14.547113 -132.148629) (xy 14.488502 -132.156242) (xy 14.45895 -132.156708) (xy 14.428981 -132.156265)
			(xy 14.369557 -132.148435) (xy 14.311663 -132.132917) (xy 14.25629 -132.109975) (xy 14.204384 -132.080003)
			(xy 14.156835 -132.043512) (xy 14.114455 -132.001127) (xy 14.077969 -131.953574) (xy 14.048003 -131.901665)
			(xy 14.025067 -131.846289) (xy 14.009555 -131.788394) (xy 14.001732 -131.728969) (xy 14.001242 -131.699)
			(xy 2.902172 -131.699) (xy 2.904641 -131.704789) (xy 2.919454 -131.719011) (xy 2.928874 -131.72313)
			(xy 2.954099 -131.733178) (xy 3.001651 -131.759385) (xy 3.045009 -131.792068) (xy 3.083296 -131.830567)
			(xy 3.115739 -131.874105) (xy 3.141682 -131.921802) (xy 3.160603 -131.972695) (xy 3.172118 -132.025756)
			(xy 3.175995 -132.079913) (xy 3.172157 -132.134074) (xy 3.160679 -132.187143) (xy 3.153313 -132.207)
			(xy 7.110982 -132.207) (xy 7.115053 -132.151378) (xy 7.127179 -132.096941) (xy 7.147102 -132.04485)
			(xy 7.174398 -131.996215) (xy 7.208484 -131.952072) (xy 7.248633 -131.913363) (xy 7.293991 -131.880912)
			(xy 7.343591 -131.855411) (xy 7.396375 -131.837404) (xy 7.451218 -131.827274) (xy 7.506952 -131.825237)
			(xy 7.562389 -131.831337) (xy 7.616346 -131.845443) (xy 7.667675 -131.867255) (xy 7.715281 -131.896309)
			(xy 7.758149 -131.931984) (xy 7.795366 -131.973521) (xy 7.826139 -132.020034) (xy 7.849811 -132.070531)
			(xy 7.865879 -132.123938) (xy 7.873999 -132.179114) (xy 7.874508 -132.207) (xy 9.142982 -132.207)
			(xy 9.147053 -132.151378) (xy 9.159179 -132.096941) (xy 9.179102 -132.04485) (xy 9.206398 -131.996215)
			(xy 9.240484 -131.952072) (xy 9.280633 -131.913363) (xy 9.325991 -131.880912) (xy 9.375591 -131.855411)
			(xy 9.428375 -131.837404) (xy 9.483218 -131.827274) (xy 9.538952 -131.825237) (xy 9.594389 -131.831337)
			(xy 9.648346 -131.845443) (xy 9.699675 -131.867255) (xy 9.747281 -131.896309) (xy 9.790149 -131.931984)
			(xy 9.827366 -131.973521) (xy 9.858139 -132.020034) (xy 9.881811 -132.070531) (xy 9.897879 -132.123938)
			(xy 9.905999 -132.179114) (xy 9.906508 -132.207) (xy 9.905999 -132.234886) (xy 9.897879 -132.290062)
			(xy 9.881811 -132.343469) (xy 9.858139 -132.393966) (xy 9.827366 -132.440479) (xy 9.790149 -132.482016)
			(xy 9.747281 -132.517691) (xy 9.699675 -132.546745) (xy 9.648346 -132.568557) (xy 9.594389 -132.582663)
			(xy 9.538952 -132.588763) (xy 9.483218 -132.586726) (xy 9.428375 -132.576596) (xy 9.375591 -132.558589)
			(xy 9.325991 -132.533088) (xy 9.280633 -132.500637) (xy 9.240484 -132.461928) (xy 9.206398 -132.417785)
			(xy 9.179102 -132.36915) (xy 9.159179 -132.317059) (xy 9.147053 -132.262622) (xy 9.142982 -132.207)
			(xy 7.874508 -132.207) (xy 7.873999 -132.234886) (xy 7.865879 -132.290062) (xy 7.849811 -132.343469)
			(xy 7.826139 -132.393966) (xy 7.795366 -132.440479) (xy 7.758149 -132.482016) (xy 7.715281 -132.517691)
			(xy 7.667675 -132.546745) (xy 7.616346 -132.568557) (xy 7.562389 -132.582663) (xy 7.506952 -132.588763)
			(xy 7.451218 -132.586726) (xy 7.396375 -132.576596) (xy 7.343591 -132.558589) (xy 7.293991 -132.533088)
			(xy 7.248633 -132.500637) (xy 7.208484 -132.461928) (xy 7.174398 -132.417785) (xy 7.147102 -132.36915)
			(xy 7.127179 -132.317059) (xy 7.115053 -132.262622) (xy 7.110982 -132.207) (xy 3.153313 -132.207)
			(xy 3.141795 -132.238049) (xy 3.115886 -132.285765) (xy 3.083474 -132.329325) (xy 3.045215 -132.367852)
			(xy 3.001881 -132.400566) (xy 2.954347 -132.426807) (xy 2.929128 -132.43687) (xy 2.92862 -132.43687)
			(xy 2.928366 -132.437124) (xy 2.921421 -132.440084) (xy 2.909535 -132.449379) (xy 2.904998 -132.455412)
			(xy 2.90068 -132.462016) (xy 2.896108 -132.47624) (xy 2.896108 -132.529326) (xy 2.89637 -132.53697)
			(xy 2.900899 -132.551571) (xy 2.904998 -132.558028) (xy 2.920238 -132.579872) (xy 2.924404 -132.585559)
			(xy 2.935225 -132.594588) (xy 2.941574 -132.597652) (xy 2.941828 -132.597652) (xy 2.967122 -132.60912)
			(xy 3.014378 -132.638294) (xy 3.056909 -132.674007) (xy 3.093817 -132.715504) (xy 3.124324 -132.761911)
			(xy 3.147786 -132.812248) (xy 3.163708 -132.865453) (xy 3.171754 -132.920403) (xy 3.171754 -132.975939)
			(xy 3.163708 -133.030889) (xy 3.147786 -133.084094) (xy 3.124324 -133.134431) (xy 3.093816 -133.180837)
			(xy 3.056908 -133.222334) (xy 3.014377 -133.258047) (xy 2.967121 -133.28722) (xy 2.941828 -133.298692)
			(xy 2.941574 -133.298692) (xy 2.935219 -133.301749) (xy 2.924387 -133.31077) (xy 2.920238 -133.316472)
			(xy 2.904998 -133.338316) (xy 2.900894 -133.344769) (xy 2.896376 -133.359374) (xy 2.896108 -133.367018)
			(xy 2.896108 -134.228582) (xy 6.548102 -134.228582) (xy 6.548102 -134.168646) (xy 6.555925 -134.109224)
			(xy 6.571438 -134.051331) (xy 6.594374 -133.995958) (xy 6.624341 -133.944052) (xy 6.660828 -133.896502)
			(xy 6.703208 -133.854122) (xy 6.750758 -133.817635) (xy 6.802664 -133.787668) (xy 6.858037 -133.764732)
			(xy 6.91593 -133.749219) (xy 6.975352 -133.741396) (xy 7.035288 -133.741396) (xy 7.09471 -133.749219)
			(xy 7.152603 -133.764732) (xy 7.207976 -133.787668) (xy 7.259882 -133.817635) (xy 7.307432 -133.854122)
			(xy 7.349812 -133.896502) (xy 7.386299 -133.944052) (xy 7.416266 -133.995958) (xy 7.439202 -134.051331)
			(xy 7.454715 -134.109224) (xy 7.462538 -134.168646) (xy 7.463028 -134.198614) (xy 7.462538 -134.228582)
			(xy 7.454715 -134.288004) (xy 7.439202 -134.345897) (xy 7.416266 -134.40127) (xy 7.386299 -134.453176)
			(xy 7.349812 -134.500726) (xy 7.307432 -134.543106) (xy 7.259882 -134.579593) (xy 7.207976 -134.60956)
			(xy 7.152603 -134.632496) (xy 7.09471 -134.648009) (xy 7.035288 -134.655832) (xy 6.975352 -134.655832)
			(xy 6.91593 -134.648009) (xy 6.858037 -134.632496) (xy 6.802664 -134.60956) (xy 6.750758 -134.579593)
			(xy 6.703208 -134.543106) (xy 6.660828 -134.500726) (xy 6.624341 -134.453176) (xy 6.594374 -134.40127)
			(xy 6.571438 -134.345897) (xy 6.555925 -134.288004) (xy 6.548102 -134.228582) (xy 2.896108 -134.228582)
			(xy 2.896108 -135.65505) (xy 8.630918 -135.65505) (xy 8.634989 -135.599428) (xy 8.647115 -135.544991)
			(xy 8.667038 -135.4929) (xy 8.694334 -135.444265) (xy 8.72842 -135.400122) (xy 8.768569 -135.361413)
			(xy 8.813927 -135.328962) (xy 8.863527 -135.303461) (xy 8.916311 -135.285454) (xy 8.971154 -135.275324)
			(xy 9.026888 -135.273287) (xy 9.082325 -135.279387) (xy 9.136282 -135.293493) (xy 9.187611 -135.315305)
			(xy 9.235217 -135.344359) (xy 9.278085 -135.380034) (xy 9.315302 -135.421571) (xy 9.346075 -135.468084)
			(xy 9.365256 -135.509) (xy 14.076932 -135.509) (xy 14.081003 -135.453378) (xy 14.093129 -135.398941)
			(xy 14.113052 -135.34685) (xy 14.140348 -135.298215) (xy 14.174434 -135.254072) (xy 14.214583 -135.215363)
			(xy 14.259941 -135.182912) (xy 14.309541 -135.157411) (xy 14.362325 -135.139404) (xy 14.417168 -135.129274)
			(xy 14.472902 -135.127237) (xy 14.528339 -135.133337) (xy 14.582296 -135.147443) (xy 14.633625 -135.169255)
			(xy 14.681231 -135.198309) (xy 14.724099 -135.233984) (xy 14.761316 -135.275521) (xy 14.792089 -135.322034)
			(xy 14.815761 -135.372531) (xy 14.831829 -135.425938) (xy 14.839949 -135.481114) (xy 14.840458 -135.509)
			(xy 14.839949 -135.536886) (xy 14.831829 -135.592062) (xy 14.815761 -135.645469) (xy 14.792089 -135.695966)
			(xy 14.761316 -135.742479) (xy 14.724099 -135.784016) (xy 14.681231 -135.819691) (xy 14.633625 -135.848745)
			(xy 14.582296 -135.870557) (xy 14.528339 -135.884663) (xy 14.472902 -135.890763) (xy 14.417168 -135.888726)
			(xy 14.362325 -135.878596) (xy 14.309541 -135.860589) (xy 14.259941 -135.835088) (xy 14.214583 -135.802637)
			(xy 14.174434 -135.763928) (xy 14.140348 -135.719785) (xy 14.113052 -135.67115) (xy 14.093129 -135.619059)
			(xy 14.081003 -135.564622) (xy 14.076932 -135.509) (xy 9.365256 -135.509) (xy 9.369747 -135.518581)
			(xy 9.385815 -135.571988) (xy 9.393935 -135.627164) (xy 9.394444 -135.65505) (xy 9.393935 -135.682936)
			(xy 9.385815 -135.738112) (xy 9.369747 -135.791519) (xy 9.346075 -135.842016) (xy 9.315302 -135.888529)
			(xy 9.278085 -135.930066) (xy 9.235217 -135.965741) (xy 9.187611 -135.994795) (xy 9.136282 -136.016607)
			(xy 9.082325 -136.030713) (xy 9.026888 -136.036813) (xy 8.971154 -136.034776) (xy 8.916311 -136.024646)
			(xy 8.863527 -136.006639) (xy 8.813927 -135.981138) (xy 8.768569 -135.948687) (xy 8.72842 -135.909978)
			(xy 8.694334 -135.865835) (xy 8.667038 -135.8172) (xy 8.647115 -135.765109) (xy 8.634989 -135.710672)
			(xy 8.630918 -135.65505) (xy 2.896108 -135.65505) (xy 2.896108 -137.541) (xy 18.032982 -137.541)
			(xy 18.037053 -137.485378) (xy 18.049179 -137.430941) (xy 18.069102 -137.37885) (xy 18.096398 -137.330215)
			(xy 18.130484 -137.286072) (xy 18.170633 -137.247363) (xy 18.215991 -137.214912) (xy 18.265591 -137.189411)
			(xy 18.318375 -137.171404) (xy 18.373218 -137.161274) (xy 18.428952 -137.159237) (xy 18.484389 -137.165337)
			(xy 18.538346 -137.179443) (xy 18.589675 -137.201255) (xy 18.637281 -137.230309) (xy 18.680149 -137.265984)
			(xy 18.717366 -137.307521) (xy 18.748139 -137.354034) (xy 18.771811 -137.404531) (xy 18.787879 -137.457938)
			(xy 18.795999 -137.513114) (xy 18.796508 -137.541) (xy 18.795999 -137.568886) (xy 18.787879 -137.624062)
			(xy 18.771811 -137.677469) (xy 18.748139 -137.727966) (xy 18.717366 -137.774479) (xy 18.680149 -137.816016)
			(xy 18.637281 -137.851691) (xy 18.589675 -137.880745) (xy 18.538346 -137.902557) (xy 18.484389 -137.916663)
			(xy 18.428952 -137.922763) (xy 18.373218 -137.920726) (xy 18.318375 -137.910596) (xy 18.265591 -137.892589)
			(xy 18.215991 -137.867088) (xy 18.170633 -137.834637) (xy 18.130484 -137.795928) (xy 18.096398 -137.751785)
			(xy 18.069102 -137.70315) (xy 18.049179 -137.651059) (xy 18.037053 -137.596622) (xy 18.032982 -137.541)
			(xy 2.896108 -137.541) (xy 2.896108 -138.303) (xy 18.768566 -138.303) (xy 18.772637 -138.247378)
			(xy 18.784763 -138.192941) (xy 18.804686 -138.14085) (xy 18.831982 -138.092215) (xy 18.866068 -138.048072)
			(xy 18.906217 -138.009363) (xy 18.951575 -137.976912) (xy 19.001175 -137.951411) (xy 19.053959 -137.933404)
			(xy 19.108802 -137.923274) (xy 19.164536 -137.921237) (xy 19.219973 -137.927337) (xy 19.27393 -137.941443)
			(xy 19.325259 -137.963255) (xy 19.372865 -137.992309) (xy 19.415733 -138.027984) (xy 19.45295 -138.069521)
			(xy 19.483723 -138.116034) (xy 19.507395 -138.166531) (xy 19.523463 -138.219938) (xy 19.531583 -138.275114)
			(xy 19.532092 -138.303) (xy 19.531583 -138.330886) (xy 19.523463 -138.386062) (xy 19.507395 -138.439469)
			(xy 19.483723 -138.489966) (xy 19.45295 -138.536479) (xy 19.415733 -138.578016) (xy 19.372865 -138.613691)
			(xy 19.325259 -138.642745) (xy 19.27393 -138.664557) (xy 19.219973 -138.678663) (xy 19.164536 -138.684763)
			(xy 19.108802 -138.682726) (xy 19.053959 -138.672596) (xy 19.001175 -138.654589) (xy 18.951575 -138.629088)
			(xy 18.906217 -138.596637) (xy 18.866068 -138.557928) (xy 18.831982 -138.513785) (xy 18.804686 -138.46515)
			(xy 18.784763 -138.413059) (xy 18.772637 -138.358622) (xy 18.768566 -138.303) (xy 2.896108 -138.303)
			(xy 2.896108 -141.4526) (xy 6.958582 -141.4526) (xy 6.962653 -141.396978) (xy 6.974779 -141.342541)
			(xy 6.994702 -141.29045) (xy 7.021998 -141.241815) (xy 7.056084 -141.197672) (xy 7.096233 -141.158963)
			(xy 7.141591 -141.126512) (xy 7.191191 -141.101011) (xy 7.243975 -141.083004) (xy 7.298818 -141.072874)
			(xy 7.354552 -141.070837) (xy 7.409989 -141.076937) (xy 7.463946 -141.091043) (xy 7.515275 -141.112855)
			(xy 7.562881 -141.141909) (xy 7.605749 -141.177584) (xy 7.642966 -141.219121) (xy 7.673739 -141.265634)
			(xy 7.697411 -141.316131) (xy 7.713479 -141.369538) (xy 7.721599 -141.424714) (xy 7.722108 -141.4526)
			(xy 7.721599 -141.480486) (xy 7.713479 -141.535662) (xy 7.697411 -141.589069) (xy 7.673739 -141.639566)
			(xy 7.642966 -141.686079) (xy 7.605749 -141.727616) (xy 7.562881 -141.763291) (xy 7.515275 -141.792345)
			(xy 7.463946 -141.814157) (xy 7.409989 -141.828263) (xy 7.354552 -141.834363) (xy 7.298818 -141.832326)
			(xy 7.243975 -141.822196) (xy 7.191191 -141.804189) (xy 7.141591 -141.778688) (xy 7.096233 -141.746237)
			(xy 7.056084 -141.707528) (xy 7.021998 -141.663385) (xy 6.994702 -141.61475) (xy 6.974779 -141.562659)
			(xy 6.962653 -141.508222) (xy 6.958582 -141.4526) (xy 2.896108 -141.4526) (xy 2.896108 -157.655514)
			(xy 6.214364 -157.655514) (xy 6.214364 -145.666714) (xy 6.214859 -145.570897) (xy 6.222778 -145.379427)
			(xy 6.238603 -145.188448) (xy 6.262307 -144.998286) (xy 6.293849 -144.809265) (xy 6.333175 -144.62171)
			(xy 6.380219 -144.43594) (xy 6.434899 -144.252273) (xy 6.497122 -144.071023) (xy 6.566782 -143.892498)
			(xy 6.643761 -143.717005) (xy 6.727926 -143.544843) (xy 6.819133 -143.376306) (xy 6.917228 -143.211682)
			(xy 7.022042 -143.051253) (xy 7.133396 -142.895292) (xy 7.251099 -142.744066) (xy 7.374952 -142.597833)
			(xy 7.504742 -142.456844) (xy 7.640248 -142.321338) (xy 7.781237 -142.191548) (xy 7.92747 -142.067695)
			(xy 8.078696 -141.949992) (xy 8.234657 -141.838638) (xy 8.395086 -141.733824) (xy 8.55971 -141.635729)
			(xy 8.728247 -141.544522) (xy 8.900409 -141.460357) (xy 9.075902 -141.383378) (xy 9.254427 -141.313718)
			(xy 9.435677 -141.251495) (xy 9.619344 -141.196815) (xy 9.805114 -141.149771) (xy 9.992669 -141.110445)
			(xy 10.18169 -141.078903) (xy 10.371852 -141.055199) (xy 10.562831 -141.039374) (xy 10.754301 -141.031455)
			(xy 10.945935 -141.031455) (xy 11.137405 -141.039374) (xy 11.328384 -141.055199) (xy 11.518546 -141.078903)
			(xy 11.707567 -141.110445) (xy 11.895122 -141.149771) (xy 12.080892 -141.196815) (xy 12.264559 -141.251495)
			(xy 12.445809 -141.313718) (xy 12.624334 -141.383378) (xy 12.799827 -141.460357) (xy 12.971989 -141.544522)
			(xy 13.13912 -141.634968) (xy 30.403782 -141.634968) (xy 30.403782 -141.575032) (xy 30.411605 -141.51561)
			(xy 30.427118 -141.457717) (xy 30.450054 -141.402344) (xy 30.480021 -141.350438) (xy 30.516508 -141.302888)
			(xy 30.558888 -141.260508) (xy 30.606438 -141.224021) (xy 30.658344 -141.194054) (xy 30.713717 -141.171118)
			(xy 30.77161 -141.155605) (xy 30.831032 -141.147782) (xy 30.890968 -141.147782) (xy 30.95039 -141.155605)
			(xy 31.008283 -141.171118) (xy 31.063656 -141.194054) (xy 31.115562 -141.224021) (xy 31.163112 -141.260508)
			(xy 31.205492 -141.302888) (xy 31.241979 -141.350438) (xy 31.271946 -141.402344) (xy 31.294882 -141.457717)
			(xy 31.310395 -141.51561) (xy 31.318218 -141.575032) (xy 31.318708 -141.605) (xy 31.318218 -141.634968)
			(xy 31.310395 -141.69439) (xy 31.294882 -141.752283) (xy 31.271946 -141.807656) (xy 31.241979 -141.859562)
			(xy 31.205492 -141.907112) (xy 31.163112 -141.949492) (xy 31.115562 -141.985979) (xy 31.063656 -142.015946)
			(xy 31.008283 -142.038882) (xy 30.95039 -142.054395) (xy 30.890968 -142.062218) (xy 30.831032 -142.062218)
			(xy 30.77161 -142.054395) (xy 30.713717 -142.038882) (xy 30.658344 -142.015946) (xy 30.606438 -141.985979)
			(xy 30.558888 -141.949492) (xy 30.516508 -141.907112) (xy 30.480021 -141.859562) (xy 30.450054 -141.807656)
			(xy 30.427118 -141.752283) (xy 30.411605 -141.69439) (xy 30.403782 -141.634968) (xy 13.13912 -141.634968)
			(xy 13.140526 -141.635729) (xy 13.30515 -141.733824) (xy 13.465579 -141.838638) (xy 13.62154 -141.949992)
			(xy 13.772766 -142.067695) (xy 13.918999 -142.191548) (xy 14.059988 -142.321338) (xy 14.195494 -142.456844)
			(xy 14.325284 -142.597833) (xy 14.449137 -142.744066) (xy 14.515063 -142.828768) (xy 18.211782 -142.828768)
			(xy 18.211782 -142.768832) (xy 18.219605 -142.70941) (xy 18.235118 -142.651517) (xy 18.258054 -142.596144)
			(xy 18.288021 -142.544238) (xy 18.324508 -142.496688) (xy 18.366888 -142.454308) (xy 18.414438 -142.417821)
			(xy 18.466344 -142.387854) (xy 18.521717 -142.364918) (xy 18.57961 -142.349405) (xy 18.639032 -142.341582)
			(xy 18.698968 -142.341582) (xy 18.75839 -142.349405) (xy 18.816283 -142.364918) (xy 18.871656 -142.387854)
			(xy 18.923562 -142.417821) (xy 18.971112 -142.454308) (xy 19.013492 -142.496688) (xy 19.049979 -142.544238)
			(xy 19.079946 -142.596144) (xy 19.102882 -142.651517) (xy 19.118395 -142.70941) (xy 19.126218 -142.768832)
			(xy 19.126492 -142.785592) (xy 21.207982 -142.785592) (xy 21.212053 -142.72997) (xy 21.224179 -142.675533)
			(xy 21.244102 -142.623442) (xy 21.271398 -142.574807) (xy 21.305484 -142.530664) (xy 21.345633 -142.491955)
			(xy 21.390991 -142.459504) (xy 21.440591 -142.434003) (xy 21.493375 -142.415996) (xy 21.548218 -142.405866)
			(xy 21.603952 -142.403829) (xy 21.659389 -142.409929) (xy 21.713346 -142.424035) (xy 21.764675 -142.445847)
			(xy 21.812281 -142.474901) (xy 21.855149 -142.510576) (xy 21.892366 -142.552113) (xy 21.923139 -142.598626)
			(xy 21.946811 -142.649123) (xy 21.962879 -142.70253) (xy 21.965234 -142.718532) (xy 22.575502 -142.718532)
			(xy 22.575502 -142.658596) (xy 22.583325 -142.599174) (xy 22.598838 -142.541281) (xy 22.621774 -142.485908)
			(xy 22.651741 -142.434002) (xy 22.688228 -142.386452) (xy 22.730608 -142.344072) (xy 22.778158 -142.307585)
			(xy 22.830064 -142.277618) (xy 22.885437 -142.254682) (xy 22.94333 -142.239169) (xy 23.002752 -142.231346)
			(xy 23.062688 -142.231346) (xy 23.12211 -142.239169) (xy 23.180003 -142.254682) (xy 23.235376 -142.277618)
			(xy 23.287282 -142.307585) (xy 23.334832 -142.344072) (xy 23.377212 -142.386452) (xy 23.413699 -142.434002)
			(xy 23.443666 -142.485908) (xy 23.466602 -142.541281) (xy 23.482115 -142.599174) (xy 23.489938 -142.658596)
			(xy 23.490428 -142.688564) (xy 23.489938 -142.718532) (xy 23.484822 -142.757394) (xy 25.071052 -142.757394)
			(xy 25.071052 -142.697458) (xy 25.078875 -142.638036) (xy 25.094388 -142.580143) (xy 25.117324 -142.52477)
			(xy 25.147291 -142.472864) (xy 25.183778 -142.425314) (xy 25.226158 -142.382934) (xy 25.273708 -142.346447)
			(xy 25.325614 -142.31648) (xy 25.380987 -142.293544) (xy 25.43888 -142.278031) (xy 25.498302 -142.270208)
			(xy 25.558238 -142.270208) (xy 25.61766 -142.278031) (xy 25.675553 -142.293544) (xy 25.730926 -142.31648)
			(xy 25.782832 -142.346447) (xy 25.830382 -142.382934) (xy 25.872762 -142.425314) (xy 25.909249 -142.472864)
			(xy 25.939216 -142.52477) (xy 25.962152 -142.580143) (xy 25.977665 -142.638036) (xy 25.985488 -142.697458)
			(xy 25.985978 -142.727426) (xy 25.985488 -142.757394) (xy 26.71494 -142.757394) (xy 26.71494 -142.697458)
			(xy 26.722763 -142.638036) (xy 26.738276 -142.580143) (xy 26.761212 -142.52477) (xy 26.791179 -142.472864)
			(xy 26.827666 -142.425314) (xy 26.870046 -142.382934) (xy 26.917596 -142.346447) (xy 26.969502 -142.31648)
			(xy 27.024875 -142.293544) (xy 27.082768 -142.278031) (xy 27.14219 -142.270208) (xy 27.202126 -142.270208)
			(xy 27.261548 -142.278031) (xy 27.319441 -142.293544) (xy 27.374814 -142.31648) (xy 27.42672 -142.346447)
			(xy 27.450195 -142.36446) (xy 33.525206 -142.36446) (xy 33.525641 -142.337207) (xy 33.533403 -142.283257)
			(xy 33.548764 -142.23096) (xy 33.571411 -142.181382) (xy 33.600882 -142.135531) (xy 33.636579 -142.094341)
			(xy 33.677774 -142.05865) (xy 33.723629 -142.029185) (xy 33.773211 -142.006545) (xy 33.82551 -141.991191)
			(xy 33.879461 -141.983437) (xy 33.906714 -141.982952) (xy 33.933952 -141.983464) (xy 33.987875 -141.991215)
			(xy 34.040146 -142.006557) (xy 34.089704 -142.029178) (xy 34.13554 -142.058618) (xy 34.176722 -142.094279)
			(xy 34.212414 -142.135436) (xy 34.241888 -142.18125) (xy 34.264545 -142.230791) (xy 34.279926 -142.283051)
			(xy 34.287716 -142.336968) (xy 34.288222 -142.364206) (xy 34.288222 -142.364714) (xy 34.28746 -142.386812)
			(xy 34.286952 -142.397734) (xy 34.294318 -142.4178) (xy 34.363914 -142.487142) (xy 34.383726 -142.494762)
			(xy 34.394648 -142.494254) (xy 34.395156 -142.494254) (xy 34.416746 -142.493492) (xy 34.417254 -142.493492)
			(xy 34.444493 -142.493995) (xy 34.498414 -142.501781) (xy 34.550678 -142.517158) (xy 34.600223 -142.539814)
			(xy 34.646042 -142.569287) (xy 34.687202 -142.604978) (xy 34.722865 -142.646162) (xy 34.752308 -142.692)
			(xy 34.774931 -142.74156) (xy 34.790273 -142.793835) (xy 34.798023 -142.84776) (xy 34.798508 -142.875)
			(xy 34.798022 -142.902251) (xy 34.790266 -142.956199) (xy 34.774911 -143.008494) (xy 34.752269 -143.058071)
			(xy 34.722803 -143.103921) (xy 34.687112 -143.145112) (xy 34.645921 -143.180803) (xy 34.600071 -143.210269)
			(xy 34.550494 -143.232911) (xy 34.498199 -143.248266) (xy 34.444251 -143.256022) (xy 34.417 -143.256508)
			(xy 34.38976 -143.256023) (xy 34.335835 -143.248273) (xy 34.28356 -143.232931) (xy 34.234 -143.210308)
			(xy 34.188162 -143.180866) (xy 34.146978 -143.145202) (xy 34.111287 -143.104042) (xy 34.081814 -143.058223)
			(xy 34.059158 -143.008678) (xy 34.043781 -142.956414) (xy 34.035995 -142.902493) (xy 34.035492 -142.875254)
			(xy 34.035492 -142.874746) (xy 34.036254 -142.852648) (xy 34.036762 -142.841726) (xy 34.029396 -142.82166)
			(xy 33.9598 -142.752318) (xy 33.939988 -142.744698) (xy 33.929066 -142.745206) (xy 33.928558 -142.745206)
			(xy 33.906968 -142.745968) (xy 33.90646 -142.745968) (xy 33.879219 -142.745491) (xy 33.825296 -142.737706)
			(xy 33.773029 -142.722329) (xy 33.723481 -142.699672) (xy 33.677661 -142.670197) (xy 33.6365 -142.634502)
			(xy 33.600835 -142.593315) (xy 33.571394 -142.547473) (xy 33.548773 -142.497909) (xy 33.533434 -142.44563)
			(xy 33.525689 -142.391701) (xy 33.525206 -142.36446) (xy 27.450195 -142.36446) (xy 27.47427 -142.382934)
			(xy 27.51665 -142.425314) (xy 27.553137 -142.472864) (xy 27.583104 -142.52477) (xy 27.60604 -142.580143)
			(xy 27.621553 -142.638036) (xy 27.629376 -142.697458) (xy 27.629866 -142.727426) (xy 27.629376 -142.757394)
			(xy 27.621553 -142.816816) (xy 27.60604 -142.874709) (xy 27.605919 -142.875) (xy 31.367982 -142.875)
			(xy 31.372053 -142.819378) (xy 31.384179 -142.764941) (xy 31.404102 -142.71285) (xy 31.431398 -142.664215)
			(xy 31.465484 -142.620072) (xy 31.505633 -142.581363) (xy 31.550991 -142.548912) (xy 31.600591 -142.523411)
			(xy 31.653375 -142.505404) (xy 31.708218 -142.495274) (xy 31.763952 -142.493237) (xy 31.819389 -142.499337)
			(xy 31.873346 -142.513443) (xy 31.924675 -142.535255) (xy 31.972281 -142.564309) (xy 32.015149 -142.599984)
			(xy 32.052366 -142.641521) (xy 32.083139 -142.688034) (xy 32.106811 -142.738531) (xy 32.122879 -142.791938)
			(xy 32.130999 -142.847114) (xy 32.131508 -142.875) (xy 32.130999 -142.902886) (xy 32.122879 -142.958062)
			(xy 32.106811 -143.011469) (xy 32.083139 -143.061966) (xy 32.052366 -143.108479) (xy 32.015149 -143.150016)
			(xy 31.972281 -143.185691) (xy 31.924675 -143.214745) (xy 31.873346 -143.236557) (xy 31.819389 -143.250663)
			(xy 31.763952 -143.256763) (xy 31.708218 -143.254726) (xy 31.653375 -143.244596) (xy 31.600591 -143.226589)
			(xy 31.550991 -143.201088) (xy 31.505633 -143.168637) (xy 31.465484 -143.129928) (xy 31.431398 -143.085785)
			(xy 31.404102 -143.03715) (xy 31.384179 -142.985059) (xy 31.372053 -142.930622) (xy 31.367982 -142.875)
			(xy 27.605919 -142.875) (xy 27.583104 -142.930082) (xy 27.553137 -142.981988) (xy 27.51665 -143.029538)
			(xy 27.47427 -143.071918) (xy 27.42672 -143.108405) (xy 27.374814 -143.138372) (xy 27.319441 -143.161308)
			(xy 27.261548 -143.176821) (xy 27.202126 -143.184644) (xy 27.14219 -143.184644) (xy 27.082768 -143.176821)
			(xy 27.024875 -143.161308) (xy 26.969502 -143.138372) (xy 26.917596 -143.108405) (xy 26.870046 -143.071918)
			(xy 26.827666 -143.029538) (xy 26.791179 -142.981988) (xy 26.761212 -142.930082) (xy 26.738276 -142.874709)
			(xy 26.722763 -142.816816) (xy 26.71494 -142.757394) (xy 25.985488 -142.757394) (xy 25.977665 -142.816816)
			(xy 25.962152 -142.874709) (xy 25.939216 -142.930082) (xy 25.909249 -142.981988) (xy 25.872762 -143.029538)
			(xy 25.830382 -143.071918) (xy 25.782832 -143.108405) (xy 25.730926 -143.138372) (xy 25.675553 -143.161308)
			(xy 25.61766 -143.176821) (xy 25.558238 -143.184644) (xy 25.498302 -143.184644) (xy 25.43888 -143.176821)
			(xy 25.380987 -143.161308) (xy 25.325614 -143.138372) (xy 25.273708 -143.108405) (xy 25.226158 -143.071918)
			(xy 25.183778 -143.029538) (xy 25.147291 -142.981988) (xy 25.117324 -142.930082) (xy 25.094388 -142.874709)
			(xy 25.078875 -142.816816) (xy 25.071052 -142.757394) (xy 23.484822 -142.757394) (xy 23.482115 -142.777954)
			(xy 23.466602 -142.835847) (xy 23.443666 -142.89122) (xy 23.413699 -142.943126) (xy 23.377212 -142.990676)
			(xy 23.334832 -143.033056) (xy 23.287282 -143.069543) (xy 23.235376 -143.09951) (xy 23.180003 -143.122446)
			(xy 23.12211 -143.137959) (xy 23.062688 -143.145782) (xy 23.002752 -143.145782) (xy 22.94333 -143.137959)
			(xy 22.885437 -143.122446) (xy 22.830064 -143.09951) (xy 22.778158 -143.069543) (xy 22.730608 -143.033056)
			(xy 22.688228 -142.990676) (xy 22.651741 -142.943126) (xy 22.621774 -142.89122) (xy 22.598838 -142.835847)
			(xy 22.583325 -142.777954) (xy 22.575502 -142.718532) (xy 21.965234 -142.718532) (xy 21.970999 -142.757706)
			(xy 21.971508 -142.785592) (xy 21.970999 -142.813478) (xy 21.962879 -142.868654) (xy 21.946811 -142.922061)
			(xy 21.923139 -142.972558) (xy 21.892366 -143.019071) (xy 21.855149 -143.060608) (xy 21.812281 -143.096283)
			(xy 21.764675 -143.125337) (xy 21.713346 -143.147149) (xy 21.659389 -143.161255) (xy 21.603952 -143.167355)
			(xy 21.548218 -143.165318) (xy 21.493375 -143.155188) (xy 21.440591 -143.137181) (xy 21.390991 -143.11168)
			(xy 21.345633 -143.079229) (xy 21.305484 -143.04052) (xy 21.271398 -142.996377) (xy 21.244102 -142.947742)
			(xy 21.224179 -142.895651) (xy 21.212053 -142.841214) (xy 21.207982 -142.785592) (xy 19.126492 -142.785592)
			(xy 19.126708 -142.7988) (xy 19.126218 -142.828768) (xy 19.118395 -142.88819) (xy 19.102882 -142.946083)
			(xy 19.079946 -143.001456) (xy 19.049979 -143.053362) (xy 19.013492 -143.100912) (xy 18.971112 -143.143292)
			(xy 18.923562 -143.179779) (xy 18.871656 -143.209746) (xy 18.816283 -143.232682) (xy 18.75839 -143.248195)
			(xy 18.698968 -143.256018) (xy 18.639032 -143.256018) (xy 18.57961 -143.248195) (xy 18.521717 -143.232682)
			(xy 18.466344 -143.209746) (xy 18.414438 -143.179779) (xy 18.366888 -143.143292) (xy 18.324508 -143.100912)
			(xy 18.288021 -143.053362) (xy 18.258054 -143.001456) (xy 18.235118 -142.946083) (xy 18.219605 -142.88819)
			(xy 18.211782 -142.828768) (xy 14.515063 -142.828768) (xy 14.56684 -142.895292) (xy 14.678194 -143.051253)
			(xy 14.783008 -143.211682) (xy 14.881103 -143.376306) (xy 14.97231 -143.544843) (xy 15.056475 -143.717005)
			(xy 15.133454 -143.892498) (xy 15.203114 -144.071023) (xy 15.265337 -144.252273) (xy 15.320017 -144.43594)
			(xy 15.360254 -144.59483) (xy 24.180782 -144.59483) (xy 24.180782 -144.534894) (xy 24.188605 -144.475472)
			(xy 24.204118 -144.417579) (xy 24.227054 -144.362206) (xy 24.257021 -144.3103) (xy 24.293508 -144.26275)
			(xy 24.335888 -144.22037) (xy 24.383438 -144.183883) (xy 24.435344 -144.153916) (xy 24.490717 -144.13098)
			(xy 24.54861 -144.115467) (xy 24.608032 -144.107644) (xy 24.667968 -144.107644) (xy 24.72739 -144.115467)
			(xy 24.785283 -144.13098) (xy 24.840656 -144.153916) (xy 24.892562 -144.183883) (xy 24.940112 -144.22037)
			(xy 24.982492 -144.26275) (xy 25.018979 -144.3103) (xy 25.048946 -144.362206) (xy 25.071882 -144.417579)
			(xy 25.087395 -144.475472) (xy 25.095218 -144.534894) (xy 25.095708 -144.564862) (xy 25.095218 -144.59483)
			(xy 25.087395 -144.654252) (xy 25.071882 -144.712145) (xy 25.048946 -144.767518) (xy 25.018979 -144.819424)
			(xy 24.982492 -144.866974) (xy 24.940112 -144.909354) (xy 24.892562 -144.945841) (xy 24.840656 -144.975808)
			(xy 24.785283 -144.998744) (xy 24.72739 -145.014257) (xy 24.667968 -145.02208) (xy 24.608032 -145.02208)
			(xy 24.54861 -145.014257) (xy 24.490717 -144.998744) (xy 24.435344 -144.975808) (xy 24.383438 -144.945841)
			(xy 24.335888 -144.909354) (xy 24.293508 -144.866974) (xy 24.257021 -144.819424) (xy 24.227054 -144.767518)
			(xy 24.204118 -144.712145) (xy 24.188605 -144.654252) (xy 24.180782 -144.59483) (xy 15.360254 -144.59483)
			(xy 15.367061 -144.62171) (xy 15.406387 -144.809265) (xy 15.437929 -144.998286) (xy 15.461633 -145.188448)
			(xy 15.477458 -145.379427) (xy 15.485377 -145.570897) (xy 15.485872 -145.666714) (xy 15.485872 -145.771866)
			(xy 28.952934 -145.771866) (xy 28.952934 -145.71193) (xy 28.960757 -145.652508) (xy 28.97627 -145.594615)
			(xy 28.999206 -145.539242) (xy 29.029173 -145.487336) (xy 29.06566 -145.439786) (xy 29.10804 -145.397406)
			(xy 29.15559 -145.360919) (xy 29.207496 -145.330952) (xy 29.262869 -145.308016) (xy 29.320762 -145.292503)
			(xy 29.380184 -145.28468) (xy 29.44012 -145.28468) (xy 29.499542 -145.292503) (xy 29.557435 -145.308016)
			(xy 29.612808 -145.330952) (xy 29.664714 -145.360919) (xy 29.712264 -145.397406) (xy 29.754644 -145.439786)
			(xy 29.791131 -145.487336) (xy 29.821098 -145.539242) (xy 29.844034 -145.594615) (xy 29.859547 -145.652508)
			(xy 29.86737 -145.71193) (xy 29.86786 -145.741898) (xy 29.86737 -145.771866) (xy 29.859547 -145.831288)
			(xy 29.844034 -145.889181) (xy 29.821098 -145.944554) (xy 29.791131 -145.99646) (xy 29.754644 -146.04401)
			(xy 29.712264 -146.08639) (xy 29.664714 -146.122877) (xy 29.612808 -146.152844) (xy 29.557435 -146.17578)
			(xy 29.499542 -146.191293) (xy 29.44012 -146.199116) (xy 29.380184 -146.199116) (xy 29.320762 -146.191293)
			(xy 29.262869 -146.17578) (xy 29.207496 -146.152844) (xy 29.15559 -146.122877) (xy 29.10804 -146.08639)
			(xy 29.06566 -146.04401) (xy 29.029173 -145.99646) (xy 28.999206 -145.944554) (xy 28.97627 -145.889181)
			(xy 28.960757 -145.831288) (xy 28.952934 -145.771866) (xy 15.485872 -145.771866) (xy 15.485872 -147.730968)
			(xy 30.022782 -147.730968) (xy 30.022782 -147.671032) (xy 30.030605 -147.61161) (xy 30.046118 -147.553717)
			(xy 30.069054 -147.498344) (xy 30.099021 -147.446438) (xy 30.135508 -147.398888) (xy 30.177888 -147.356508)
			(xy 30.225438 -147.320021) (xy 30.277344 -147.290054) (xy 30.332717 -147.267118) (xy 30.39061 -147.251605)
			(xy 30.450032 -147.243782) (xy 30.509968 -147.243782) (xy 30.56939 -147.251605) (xy 30.627283 -147.267118)
			(xy 30.682656 -147.290054) (xy 30.734562 -147.320021) (xy 30.782112 -147.356508) (xy 30.824492 -147.398888)
			(xy 30.860979 -147.446438) (xy 30.890946 -147.498344) (xy 30.913882 -147.553717) (xy 30.929395 -147.61161)
			(xy 30.937218 -147.671032) (xy 30.937708 -147.701) (xy 30.937218 -147.730968) (xy 30.929395 -147.79039)
			(xy 30.913882 -147.848283) (xy 30.890946 -147.903656) (xy 30.860979 -147.955562) (xy 30.824492 -148.003112)
			(xy 30.782112 -148.045492) (xy 30.734562 -148.081979) (xy 30.682656 -148.111946) (xy 30.627283 -148.134882)
			(xy 30.56939 -148.150395) (xy 30.509968 -148.158218) (xy 30.450032 -148.158218) (xy 30.39061 -148.150395)
			(xy 30.332717 -148.134882) (xy 30.277344 -148.111946) (xy 30.225438 -148.081979) (xy 30.177888 -148.045492)
			(xy 30.135508 -148.003112) (xy 30.099021 -147.955562) (xy 30.069054 -147.903656) (xy 30.046118 -147.848283)
			(xy 30.030605 -147.79039) (xy 30.022782 -147.730968) (xy 15.485872 -147.730968) (xy 15.485872 -150.143968)
			(xy 28.498782 -150.143968) (xy 28.498782 -150.084032) (xy 28.506605 -150.02461) (xy 28.522118 -149.966717)
			(xy 28.545054 -149.911344) (xy 28.575021 -149.859438) (xy 28.611508 -149.811888) (xy 28.653888 -149.769508)
			(xy 28.701438 -149.733021) (xy 28.753344 -149.703054) (xy 28.808717 -149.680118) (xy 28.86661 -149.664605)
			(xy 28.926032 -149.656782) (xy 28.985968 -149.656782) (xy 29.04539 -149.664605) (xy 29.103283 -149.680118)
			(xy 29.158656 -149.703054) (xy 29.210562 -149.733021) (xy 29.258112 -149.769508) (xy 29.300492 -149.811888)
			(xy 29.336979 -149.859438) (xy 29.366946 -149.911344) (xy 29.389882 -149.966717) (xy 29.405395 -150.02461)
			(xy 29.413218 -150.084032) (xy 29.413708 -150.114) (xy 29.413218 -150.143968) (xy 29.405395 -150.20339)
			(xy 29.389882 -150.261283) (xy 29.366946 -150.316656) (xy 29.336979 -150.368562) (xy 29.300492 -150.416112)
			(xy 29.258112 -150.458492) (xy 29.210562 -150.494979) (xy 29.158656 -150.524946) (xy 29.103283 -150.547882)
			(xy 29.04539 -150.563395) (xy 28.985968 -150.571218) (xy 28.926032 -150.571218) (xy 28.86661 -150.563395)
			(xy 28.808717 -150.547882) (xy 28.753344 -150.524946) (xy 28.701438 -150.494979) (xy 28.653888 -150.458492)
			(xy 28.611508 -150.416112) (xy 28.575021 -150.368562) (xy 28.545054 -150.316656) (xy 28.522118 -150.261283)
			(xy 28.506605 -150.20339) (xy 28.498782 -150.143968) (xy 15.485872 -150.143968) (xy 15.485872 -155.34005)
			(xy 18.63166 -155.34005) (xy 18.635731 -155.284428) (xy 18.647857 -155.229991) (xy 18.66778 -155.1779)
			(xy 18.695076 -155.129265) (xy 18.729162 -155.085122) (xy 18.769311 -155.046413) (xy 18.814669 -155.013962)
			(xy 18.864269 -154.988461) (xy 18.917053 -154.970454) (xy 18.971896 -154.960324) (xy 19.02763 -154.958287)
			(xy 19.083067 -154.964387) (xy 19.137024 -154.978493) (xy 19.188353 -155.000305) (xy 19.235959 -155.029359)
			(xy 19.278827 -155.065034) (xy 19.316044 -155.106571) (xy 19.346817 -155.153084) (xy 19.370489 -155.203581)
			(xy 19.386557 -155.256988) (xy 19.394677 -155.312164) (xy 19.395186 -155.34005) (xy 19.394677 -155.367936)
			(xy 19.386557 -155.423112) (xy 19.370489 -155.476519) (xy 19.346817 -155.527016) (xy 19.316044 -155.573529)
			(xy 19.278827 -155.615066) (xy 19.235959 -155.650741) (xy 19.188353 -155.679795) (xy 19.137024 -155.701607)
			(xy 19.083067 -155.715713) (xy 19.02763 -155.721813) (xy 18.971896 -155.719776) (xy 18.917053 -155.709646)
			(xy 18.864269 -155.691639) (xy 18.814669 -155.666138) (xy 18.769311 -155.633687) (xy 18.729162 -155.594978)
			(xy 18.695076 -155.550835) (xy 18.66778 -155.5022) (xy 18.647857 -155.450109) (xy 18.635731 -155.395672)
			(xy 18.63166 -155.34005) (xy 15.485872 -155.34005) (xy 15.485872 -156.747968) (xy 24.632902 -156.747968)
			(xy 24.632902 -156.688032) (xy 24.640725 -156.62861) (xy 24.656238 -156.570717) (xy 24.679174 -156.515344)
			(xy 24.709141 -156.463438) (xy 24.745628 -156.415888) (xy 24.788008 -156.373508) (xy 24.835558 -156.337021)
			(xy 24.887464 -156.307054) (xy 24.942837 -156.284118) (xy 25.00073 -156.268605) (xy 25.060152 -156.260782)
			(xy 25.120088 -156.260782) (xy 25.17951 -156.268605) (xy 25.237403 -156.284118) (xy 25.292776 -156.307054)
			(xy 25.344682 -156.337021) (xy 25.392232 -156.373508) (xy 25.434612 -156.415888) (xy 25.471099 -156.463438)
			(xy 25.501066 -156.515344) (xy 25.524002 -156.570717) (xy 25.539515 -156.62861) (xy 25.547338 -156.688032)
			(xy 25.547828 -156.718) (xy 25.547338 -156.747968) (xy 25.539515 -156.80739) (xy 25.524002 -156.865283)
			(xy 25.501066 -156.920656) (xy 25.471099 -156.972562) (xy 25.434612 -157.020112) (xy 25.392232 -157.062492)
			(xy 25.344682 -157.098979) (xy 25.292776 -157.128946) (xy 25.237403 -157.151882) (xy 25.17951 -157.167395)
			(xy 25.120088 -157.175218) (xy 25.060152 -157.175218) (xy 25.00073 -157.167395) (xy 24.942837 -157.151882)
			(xy 24.887464 -157.128946) (xy 24.835558 -157.098979) (xy 24.788008 -157.062492) (xy 24.745628 -157.020112)
			(xy 24.709141 -156.972562) (xy 24.679174 -156.920656) (xy 24.656238 -156.865283) (xy 24.640725 -156.80739)
			(xy 24.632902 -156.747968) (xy 15.485872 -156.747968) (xy 15.485872 -157.655514) (xy 15.485377 -157.751331)
			(xy 15.477458 -157.942801) (xy 15.461633 -158.13378) (xy 15.437929 -158.323942) (xy 15.406387 -158.512963)
			(xy 15.398334 -158.551368) (xy 20.700982 -158.551368) (xy 20.700982 -158.491432) (xy 20.708805 -158.43201)
			(xy 20.724318 -158.374117) (xy 20.747254 -158.318744) (xy 20.777221 -158.266838) (xy 20.813708 -158.219288)
			(xy 20.856088 -158.176908) (xy 20.903638 -158.140421) (xy 20.955544 -158.110454) (xy 21.010917 -158.087518)
			(xy 21.06881 -158.072005) (xy 21.128232 -158.064182) (xy 21.188168 -158.064182) (xy 21.24759 -158.072005)
			(xy 21.305483 -158.087518) (xy 21.360856 -158.110454) (xy 21.412762 -158.140421) (xy 21.460312 -158.176908)
			(xy 21.502692 -158.219288) (xy 21.539179 -158.266838) (xy 21.569146 -158.318744) (xy 21.592082 -158.374117)
			(xy 21.607595 -158.43201) (xy 21.615418 -158.491432) (xy 21.615908 -158.5214) (xy 21.615418 -158.551368)
			(xy 21.607595 -158.61079) (xy 21.598879 -158.643316) (xy 25.71418 -158.643316) (xy 25.71418 -158.58338)
			(xy 25.722003 -158.523958) (xy 25.737516 -158.466065) (xy 25.760452 -158.410692) (xy 25.790419 -158.358786)
			(xy 25.826906 -158.311236) (xy 25.869286 -158.268856) (xy 25.916836 -158.232369) (xy 25.968742 -158.202402)
			(xy 26.024115 -158.179466) (xy 26.082008 -158.163953) (xy 26.14143 -158.15613) (xy 26.201366 -158.15613)
			(xy 26.260788 -158.163953) (xy 26.318681 -158.179466) (xy 26.374054 -158.202402) (xy 26.42596 -158.232369)
			(xy 26.47351 -158.268856) (xy 26.51589 -158.311236) (xy 26.552377 -158.358786) (xy 26.582344 -158.410692)
			(xy 26.60528 -158.466065) (xy 26.620793 -158.523958) (xy 26.628616 -158.58338) (xy 26.629106 -158.613348)
			(xy 26.628616 -158.643316) (xy 26.620793 -158.702738) (xy 26.60528 -158.760631) (xy 26.582344 -158.816004)
			(xy 26.552377 -158.86791) (xy 26.51589 -158.91546) (xy 26.47351 -158.95784) (xy 26.42596 -158.994327)
			(xy 26.374054 -159.024294) (xy 26.318681 -159.04723) (xy 26.260788 -159.062743) (xy 26.201366 -159.070566)
			(xy 26.14143 -159.070566) (xy 26.082008 -159.062743) (xy 26.024115 -159.04723) (xy 25.968742 -159.024294)
			(xy 25.916836 -158.994327) (xy 25.869286 -158.95784) (xy 25.826906 -158.91546) (xy 25.790419 -158.86791)
			(xy 25.760452 -158.816004) (xy 25.737516 -158.760631) (xy 25.722003 -158.702738) (xy 25.71418 -158.643316)
			(xy 21.598879 -158.643316) (xy 21.592082 -158.668683) (xy 21.569146 -158.724056) (xy 21.539179 -158.775962)
			(xy 21.502692 -158.823512) (xy 21.460312 -158.865892) (xy 21.412762 -158.902379) (xy 21.360856 -158.932346)
			(xy 21.305483 -158.955282) (xy 21.24759 -158.970795) (xy 21.188168 -158.978618) (xy 21.128232 -158.978618)
			(xy 21.06881 -158.970795) (xy 21.010917 -158.955282) (xy 20.955544 -158.932346) (xy 20.903638 -158.902379)
			(xy 20.856088 -158.865892) (xy 20.813708 -158.823512) (xy 20.777221 -158.775962) (xy 20.747254 -158.724056)
			(xy 20.724318 -158.668683) (xy 20.708805 -158.61079) (xy 20.700982 -158.551368) (xy 15.398334 -158.551368)
			(xy 15.367061 -158.700518) (xy 15.320017 -158.886288) (xy 15.265337 -159.069955) (xy 15.203114 -159.251205)
			(xy 15.180444 -159.309304) (xy 27.127436 -159.309304) (xy 27.127436 -159.249368) (xy 27.135259 -159.189946)
			(xy 27.150772 -159.132053) (xy 27.173708 -159.07668) (xy 27.203675 -159.024774) (xy 27.240162 -158.977224)
			(xy 27.282542 -158.934844) (xy 27.330092 -158.898357) (xy 27.381998 -158.86839) (xy 27.437371 -158.845454)
			(xy 27.495264 -158.829941) (xy 27.554686 -158.822118) (xy 27.614622 -158.822118) (xy 27.674044 -158.829941)
			(xy 27.731937 -158.845454) (xy 27.78731 -158.86839) (xy 27.839216 -158.898357) (xy 27.886766 -158.934844)
			(xy 27.929146 -158.977224) (xy 27.965633 -159.024774) (xy 27.9956 -159.07668) (xy 28.018536 -159.132053)
			(xy 28.034049 -159.189946) (xy 28.041872 -159.249368) (xy 28.042362 -159.279336) (xy 28.041872 -159.309304)
			(xy 28.034049 -159.368726) (xy 28.018536 -159.426619) (xy 27.9956 -159.481992) (xy 27.965633 -159.533898)
			(xy 27.929146 -159.581448) (xy 27.886766 -159.623828) (xy 27.839216 -159.660315) (xy 27.78731 -159.690282)
			(xy 27.731937 -159.713218) (xy 27.674044 -159.728731) (xy 27.614622 -159.736554) (xy 27.554686 -159.736554)
			(xy 27.495264 -159.728731) (xy 27.437371 -159.713218) (xy 27.381998 -159.690282) (xy 27.330092 -159.660315)
			(xy 27.282542 -159.623828) (xy 27.240162 -159.581448) (xy 27.203675 -159.533898) (xy 27.173708 -159.481992)
			(xy 27.150772 -159.426619) (xy 27.135259 -159.368726) (xy 27.127436 -159.309304) (xy 15.180444 -159.309304)
			(xy 15.133454 -159.42973) (xy 15.056475 -159.605223) (xy 14.97231 -159.777385) (xy 14.881103 -159.945922)
			(xy 14.783008 -160.110546) (xy 14.678194 -160.270975) (xy 14.56684 -160.426936) (xy 14.449137 -160.578162)
			(xy 14.325284 -160.724395) (xy 14.195494 -160.865384) (xy 14.059988 -161.00089) (xy 14.019089 -161.03854)
			(xy 19.54657 -161.03854) (xy 19.547056 -161.011289) (xy 19.554812 -160.957341) (xy 19.570167 -160.905046)
			(xy 19.592809 -160.855469) (xy 19.622275 -160.809619) (xy 19.657966 -160.768428) (xy 19.699157 -160.732737)
			(xy 19.745007 -160.703271) (xy 19.794584 -160.680629) (xy 19.846879 -160.665274) (xy 19.900827 -160.657518)
			(xy 19.955329 -160.657518) (xy 20.009277 -160.665274) (xy 20.061572 -160.680629) (xy 20.111149 -160.703271)
			(xy 20.156999 -160.732737) (xy 20.19819 -160.768428) (xy 20.233881 -160.809619) (xy 20.263347 -160.855469)
			(xy 20.285989 -160.905046) (xy 20.301344 -160.957341) (xy 20.3091 -161.011289) (xy 20.309586 -161.03854)
			(xy 20.309093 -161.065536) (xy 20.3015 -161.118992) (xy 20.286443 -161.170842) (xy 20.264223 -161.220051)
			(xy 20.249166 -161.243768) (xy 21.767782 -161.243768) (xy 21.767782 -161.183832) (xy 21.775605 -161.12441)
			(xy 21.791118 -161.066517) (xy 21.814054 -161.011144) (xy 21.844021 -160.959238) (xy 21.880508 -160.911688)
			(xy 21.922888 -160.869308) (xy 21.970438 -160.832821) (xy 22.022344 -160.802854) (xy 22.077717 -160.779918)
			(xy 22.13561 -160.764405) (xy 22.195032 -160.756582) (xy 22.254968 -160.756582) (xy 22.31439 -160.764405)
			(xy 22.372283 -160.779918) (xy 22.427656 -160.802854) (xy 22.479562 -160.832821) (xy 22.527112 -160.869308)
			(xy 22.569492 -160.911688) (xy 22.605979 -160.959238) (xy 22.635946 -161.011144) (xy 22.658882 -161.066517)
			(xy 22.674395 -161.12441) (xy 22.682218 -161.183832) (xy 22.682708 -161.2138) (xy 22.682218 -161.243768)
			(xy 22.674395 -161.30319) (xy 22.666428 -161.332922) (xy 24.701736 -161.332922) (xy 24.701736 -161.272986)
			(xy 24.709559 -161.213564) (xy 24.725072 -161.155671) (xy 24.748008 -161.100298) (xy 24.777975 -161.048392)
			(xy 24.814462 -161.000842) (xy 24.856842 -160.958462) (xy 24.904392 -160.921975) (xy 24.956298 -160.892008)
			(xy 25.011671 -160.869072) (xy 25.069564 -160.853559) (xy 25.128986 -160.845736) (xy 25.188922 -160.845736)
			(xy 25.248344 -160.853559) (xy 25.306237 -160.869072) (xy 25.36161 -160.892008) (xy 25.413516 -160.921975)
			(xy 25.461066 -160.958462) (xy 25.503446 -161.000842) (xy 25.539933 -161.048392) (xy 25.5699 -161.100298)
			(xy 25.592836 -161.155671) (xy 25.5948 -161.163) (xy 26.541982 -161.163) (xy 26.546053 -161.107378)
			(xy 26.558179 -161.052941) (xy 26.578102 -161.00085) (xy 26.605398 -160.952215) (xy 26.639484 -160.908072)
			(xy 26.679633 -160.869363) (xy 26.724991 -160.836912) (xy 26.774591 -160.811411) (xy 26.827375 -160.793404)
			(xy 26.882218 -160.783274) (xy 26.937952 -160.781237) (xy 26.993389 -160.787337) (xy 27.047346 -160.801443)
			(xy 27.098675 -160.823255) (xy 27.146281 -160.852309) (xy 27.189149 -160.887984) (xy 27.226366 -160.929521)
			(xy 27.257139 -160.976034) (xy 27.280811 -161.026531) (xy 27.296879 -161.079938) (xy 27.304999 -161.135114)
			(xy 27.305508 -161.163) (xy 27.304999 -161.190886) (xy 27.304693 -161.192968) (xy 32.943782 -161.192968)
			(xy 32.943782 -161.133032) (xy 32.951605 -161.07361) (xy 32.967118 -161.015717) (xy 32.990054 -160.960344)
			(xy 33.020021 -160.908438) (xy 33.056508 -160.860888) (xy 33.098888 -160.818508) (xy 33.146438 -160.782021)
			(xy 33.198344 -160.752054) (xy 33.253717 -160.729118) (xy 33.31161 -160.713605) (xy 33.371032 -160.705782)
			(xy 33.430968 -160.705782) (xy 33.49039 -160.713605) (xy 33.548283 -160.729118) (xy 33.603656 -160.752054)
			(xy 33.655562 -160.782021) (xy 33.703112 -160.818508) (xy 33.745492 -160.860888) (xy 33.781979 -160.908438)
			(xy 33.811946 -160.960344) (xy 33.834882 -161.015717) (xy 33.850395 -161.07361) (xy 33.858218 -161.133032)
			(xy 33.858708 -161.163) (xy 33.858218 -161.192968) (xy 33.850395 -161.25239) (xy 33.834882 -161.310283)
			(xy 33.811946 -161.365656) (xy 33.781979 -161.417562) (xy 33.745492 -161.465112) (xy 33.703112 -161.507492)
			(xy 33.655562 -161.543979) (xy 33.603656 -161.573946) (xy 33.548283 -161.596882) (xy 33.49039 -161.612395)
			(xy 33.430968 -161.620218) (xy 33.371032 -161.620218) (xy 33.31161 -161.612395) (xy 33.253717 -161.596882)
			(xy 33.198344 -161.573946) (xy 33.146438 -161.543979) (xy 33.098888 -161.507492) (xy 33.056508 -161.465112)
			(xy 33.020021 -161.417562) (xy 32.990054 -161.365656) (xy 32.967118 -161.310283) (xy 32.951605 -161.25239)
			(xy 32.943782 -161.192968) (xy 27.304693 -161.192968) (xy 27.296879 -161.246062) (xy 27.280811 -161.299469)
			(xy 27.257139 -161.349966) (xy 27.226366 -161.396479) (xy 27.189149 -161.438016) (xy 27.146281 -161.473691)
			(xy 27.098675 -161.502745) (xy 27.047346 -161.524557) (xy 26.993389 -161.538663) (xy 26.937952 -161.544763)
			(xy 26.882218 -161.542726) (xy 26.827375 -161.532596) (xy 26.774591 -161.514589) (xy 26.724991 -161.489088)
			(xy 26.679633 -161.456637) (xy 26.639484 -161.417928) (xy 26.605398 -161.373785) (xy 26.578102 -161.32515)
			(xy 26.558179 -161.273059) (xy 26.546053 -161.218622) (xy 26.541982 -161.163) (xy 25.5948 -161.163)
			(xy 25.608349 -161.213564) (xy 25.616172 -161.272986) (xy 25.616662 -161.302954) (xy 25.616172 -161.332922)
			(xy 25.608349 -161.392344) (xy 25.592836 -161.450237) (xy 25.5699 -161.50561) (xy 25.539933 -161.557516)
			(xy 25.503446 -161.605066) (xy 25.461066 -161.647446) (xy 25.413516 -161.683933) (xy 25.36161 -161.7139)
			(xy 25.306237 -161.736836) (xy 25.248344 -161.752349) (xy 25.188922 -161.760172) (xy 25.128986 -161.760172)
			(xy 25.069564 -161.752349) (xy 25.011671 -161.736836) (xy 24.956298 -161.7139) (xy 24.904392 -161.683933)
			(xy 24.856842 -161.647446) (xy 24.814462 -161.605066) (xy 24.777975 -161.557516) (xy 24.748008 -161.50561)
			(xy 24.725072 -161.450237) (xy 24.709559 -161.392344) (xy 24.701736 -161.332922) (xy 22.666428 -161.332922)
			(xy 22.658882 -161.361083) (xy 22.635946 -161.416456) (xy 22.605979 -161.468362) (xy 22.569492 -161.515912)
			(xy 22.527112 -161.558292) (xy 22.479562 -161.594779) (xy 22.427656 -161.624746) (xy 22.372283 -161.647682)
			(xy 22.31439 -161.663195) (xy 22.254968 -161.671018) (xy 22.195032 -161.671018) (xy 22.13561 -161.663195)
			(xy 22.077717 -161.647682) (xy 22.022344 -161.624746) (xy 21.970438 -161.594779) (xy 21.922888 -161.558292)
			(xy 21.880508 -161.515912) (xy 21.844021 -161.468362) (xy 21.814054 -161.416456) (xy 21.791118 -161.361083)
			(xy 21.775605 -161.30319) (xy 21.767782 -161.243768) (xy 20.249166 -161.243768) (xy 20.235285 -161.265633)
			(xy 20.200207 -161.306678) (xy 20.15969 -161.342365) (xy 20.137374 -161.357564) (xy 20.126349 -161.365258)
			(xy 20.108516 -161.385368) (xy 20.096546 -161.409434) (xy 20.091267 -161.435788) (xy 20.093045 -161.462608)
			(xy 20.101756 -161.488035) (xy 20.116798 -161.51031) (xy 20.137129 -161.52789) (xy 20.149058 -161.534094)
			(xy 20.173018 -161.546096) (xy 20.21761 -161.575817) (xy 20.257603 -161.611487) (xy 20.292211 -161.652403)
			(xy 20.320751 -161.697759) (xy 20.342663 -161.746664) (xy 20.357514 -161.798154) (xy 20.365013 -161.851216)
			(xy 20.365466 -161.87801) (xy 20.36498 -161.905261) (xy 20.362142 -161.925) (xy 33.907982 -161.925)
			(xy 33.912053 -161.869378) (xy 33.924179 -161.814941) (xy 33.944102 -161.76285) (xy 33.971398 -161.714215)
			(xy 34.005484 -161.670072) (xy 34.045633 -161.631363) (xy 34.090991 -161.598912) (xy 34.140591 -161.573411)
			(xy 34.193375 -161.555404) (xy 34.248218 -161.545274) (xy 34.303952 -161.543237) (xy 34.359389 -161.549337)
			(xy 34.413346 -161.563443) (xy 34.464675 -161.585255) (xy 34.512281 -161.614309) (xy 34.555149 -161.649984)
			(xy 34.592366 -161.691521) (xy 34.623139 -161.738034) (xy 34.646811 -161.788531) (xy 34.662879 -161.841938)
			(xy 34.670999 -161.897114) (xy 34.671508 -161.925) (xy 34.670999 -161.952886) (xy 34.662879 -162.008062)
			(xy 34.646811 -162.061469) (xy 34.623139 -162.111966) (xy 34.592366 -162.158479) (xy 34.555149 -162.200016)
			(xy 34.512281 -162.235691) (xy 34.464675 -162.264745) (xy 34.413346 -162.286557) (xy 34.359389 -162.300663)
			(xy 34.303952 -162.306763) (xy 34.248218 -162.304726) (xy 34.193375 -162.294596) (xy 34.140591 -162.276589)
			(xy 34.090991 -162.251088) (xy 34.045633 -162.218637) (xy 34.005484 -162.179928) (xy 33.971398 -162.135785)
			(xy 33.944102 -162.08715) (xy 33.924179 -162.035059) (xy 33.912053 -161.980622) (xy 33.907982 -161.925)
			(xy 20.362142 -161.925) (xy 20.357224 -161.959209) (xy 20.341869 -162.011504) (xy 20.319227 -162.061081)
			(xy 20.289761 -162.106931) (xy 20.25407 -162.148122) (xy 20.212879 -162.183813) (xy 20.167029 -162.213279)
			(xy 20.117452 -162.235921) (xy 20.065157 -162.251276) (xy 20.011209 -162.259032) (xy 19.956707 -162.259032)
			(xy 19.902759 -162.251276) (xy 19.850464 -162.235921) (xy 19.800887 -162.213279) (xy 19.755037 -162.183813)
			(xy 19.713846 -162.148122) (xy 19.678155 -162.106931) (xy 19.648689 -162.061081) (xy 19.626047 -162.011504)
			(xy 19.610692 -161.959209) (xy 19.602936 -161.905261) (xy 19.60245 -161.87801) (xy 19.602889 -161.851012)
			(xy 19.610489 -161.797553) (xy 19.625555 -161.7457) (xy 19.647783 -161.696491) (xy 19.67673 -161.65091)
			(xy 19.711817 -161.609867) (xy 19.752342 -161.574183) (xy 19.774662 -161.558986) (xy 19.785631 -161.55122)
			(xy 19.803455 -161.531122) (xy 19.815421 -161.507071) (xy 19.820702 -161.480732) (xy 19.818932 -161.453927)
			(xy 19.810234 -161.428511) (xy 19.795209 -161.406242) (xy 19.774897 -161.388662) (xy 19.762978 -161.382456)
			(xy 19.739006 -161.370476) (xy 19.694411 -161.340754) (xy 19.654417 -161.305082) (xy 19.619809 -161.264163)
			(xy 19.591269 -161.218803) (xy 19.56936 -161.169895) (xy 19.554513 -161.118401) (xy 19.54702 -161.065336)
			(xy 19.54657 -161.03854) (xy 14.019089 -161.03854) (xy 13.918999 -161.13068) (xy 13.772766 -161.254533)
			(xy 13.62154 -161.372236) (xy 13.465579 -161.48359) (xy 13.30515 -161.588404) (xy 13.140526 -161.686499)
			(xy 12.971989 -161.777706) (xy 12.799827 -161.861871) (xy 12.624334 -161.93885) (xy 12.445809 -162.00851)
			(xy 12.264559 -162.070733) (xy 12.080892 -162.125413) (xy 11.895122 -162.172457) (xy 11.707567 -162.211783)
			(xy 11.518546 -162.243325) (xy 11.328384 -162.267029) (xy 11.137405 -162.282854) (xy 10.945935 -162.290773)
			(xy 10.754301 -162.290773) (xy 10.562831 -162.282854) (xy 10.371852 -162.267029) (xy 10.18169 -162.243325)
			(xy 9.992669 -162.211783) (xy 9.805114 -162.172457) (xy 9.619344 -162.125413) (xy 9.435677 -162.070733)
			(xy 9.254427 -162.00851) (xy 9.075902 -161.93885) (xy 8.900409 -161.861871) (xy 8.728247 -161.777706)
			(xy 8.55971 -161.686499) (xy 8.395086 -161.588404) (xy 8.234657 -161.48359) (xy 8.078696 -161.372236)
			(xy 7.92747 -161.254533) (xy 7.781237 -161.13068) (xy 7.640248 -161.00089) (xy 7.504742 -160.865384)
			(xy 7.374952 -160.724395) (xy 7.251099 -160.578162) (xy 7.133396 -160.426936) (xy 7.022042 -160.270975)
			(xy 6.917228 -160.110546) (xy 6.819133 -159.945922) (xy 6.727926 -159.777385) (xy 6.643761 -159.605223)
			(xy 6.566782 -159.42973) (xy 6.497122 -159.251205) (xy 6.434899 -159.069955) (xy 6.380219 -158.886288)
			(xy 6.333175 -158.700518) (xy 6.293849 -158.512963) (xy 6.262307 -158.323942) (xy 6.238603 -158.13378)
			(xy 6.222778 -157.942801) (xy 6.214859 -157.751331) (xy 6.214364 -157.655514) (xy 2.896108 -157.655514)
			(xy 2.896108 -162.256978) (xy 2.896695 -162.267513) (xy 2.905224 -162.286788) (xy 2.912618 -162.294316)
			(xy 2.96799 -162.344862) (xy 2.975195 -162.351013) (xy 2.992815 -162.357935) (xy 3.00228 -162.358324)
			(xy 3.006852 -162.35807) (xy 3.048 -162.356292) (xy 3.077968 -162.356782) (xy 3.13739 -162.364605)
			(xy 3.195283 -162.380118) (xy 3.250656 -162.403054) (xy 3.302562 -162.433021) (xy 3.350112 -162.469508)
			(xy 3.392492 -162.511888) (xy 3.413425 -162.539168) (xy 21.970982 -162.539168) (xy 21.970982 -162.479232)
			(xy 21.978805 -162.41981) (xy 21.994318 -162.361917) (xy 22.017254 -162.306544) (xy 22.047221 -162.254638)
			(xy 22.083708 -162.207088) (xy 22.126088 -162.164708) (xy 22.173638 -162.128221) (xy 22.225544 -162.098254)
			(xy 22.280917 -162.075318) (xy 22.33881 -162.059805) (xy 22.398232 -162.051982) (xy 22.458168 -162.051982)
			(xy 22.51759 -162.059805) (xy 22.575483 -162.075318) (xy 22.630856 -162.098254) (xy 22.682762 -162.128221)
			(xy 22.730312 -162.164708) (xy 22.772692 -162.207088) (xy 22.809179 -162.254638) (xy 22.839146 -162.306544)
			(xy 22.862082 -162.361917) (xy 22.877595 -162.41981) (xy 22.885418 -162.479232) (xy 22.885908 -162.5092)
			(xy 22.885418 -162.539168) (xy 22.880268 -162.578284) (xy 29.534848 -162.578284) (xy 29.534848 -162.518348)
			(xy 29.542671 -162.458926) (xy 29.558184 -162.401033) (xy 29.58112 -162.34566) (xy 29.611087 -162.293754)
			(xy 29.647574 -162.246204) (xy 29.689954 -162.203824) (xy 29.737504 -162.167337) (xy 29.78941 -162.13737)
			(xy 29.844783 -162.114434) (xy 29.902676 -162.098921) (xy 29.962098 -162.091098) (xy 30.022034 -162.091098)
			(xy 30.081456 -162.098921) (xy 30.139349 -162.114434) (xy 30.194722 -162.13737) (xy 30.246628 -162.167337)
			(xy 30.294178 -162.203824) (xy 30.336558 -162.246204) (xy 30.373045 -162.293754) (xy 30.403012 -162.34566)
			(xy 30.425948 -162.401033) (xy 30.441461 -162.458926) (xy 30.449284 -162.518348) (xy 30.449774 -162.548316)
			(xy 30.449284 -162.578284) (xy 30.441461 -162.637706) (xy 30.425948 -162.695599) (xy 30.403012 -162.750972)
			(xy 30.373045 -162.802878) (xy 30.336558 -162.850428) (xy 30.294178 -162.892808) (xy 30.246628 -162.929295)
			(xy 30.194722 -162.959262) (xy 30.139349 -162.982198) (xy 30.086468 -162.996368) (xy 45.897782 -162.996368)
			(xy 45.897782 -162.936432) (xy 45.905605 -162.87701) (xy 45.921118 -162.819117) (xy 45.944054 -162.763744)
			(xy 45.974021 -162.711838) (xy 46.010508 -162.664288) (xy 46.052888 -162.621908) (xy 46.100438 -162.585421)
			(xy 46.152344 -162.555454) (xy 46.207717 -162.532518) (xy 46.26561 -162.517005) (xy 46.325032 -162.509182)
			(xy 46.384968 -162.509182) (xy 46.44439 -162.517005) (xy 46.502283 -162.532518) (xy 46.557656 -162.555454)
			(xy 46.609562 -162.585421) (xy 46.657112 -162.621908) (xy 46.699492 -162.664288) (xy 46.735979 -162.711838)
			(xy 46.765946 -162.763744) (xy 46.788882 -162.819117) (xy 46.804395 -162.87701) (xy 46.812218 -162.936432)
			(xy 46.812708 -162.9664) (xy 46.812218 -162.996368) (xy 46.804395 -163.05579) (xy 46.788882 -163.113683)
			(xy 46.765946 -163.169056) (xy 46.735979 -163.220962) (xy 46.699492 -163.268512) (xy 46.657112 -163.310892)
			(xy 46.609562 -163.347379) (xy 46.557656 -163.377346) (xy 46.502283 -163.400282) (xy 46.44439 -163.415795)
			(xy 46.384968 -163.423618) (xy 46.325032 -163.423618) (xy 46.26561 -163.415795) (xy 46.207717 -163.400282)
			(xy 46.152344 -163.377346) (xy 46.100438 -163.347379) (xy 46.052888 -163.310892) (xy 46.010508 -163.268512)
			(xy 45.974021 -163.220962) (xy 45.944054 -163.169056) (xy 45.921118 -163.113683) (xy 45.905605 -163.05579)
			(xy 45.897782 -162.996368) (xy 30.086468 -162.996368) (xy 30.081456 -162.997711) (xy 30.022034 -163.005534)
			(xy 29.962098 -163.005534) (xy 29.902676 -162.997711) (xy 29.844783 -162.982198) (xy 29.78941 -162.959262)
			(xy 29.737504 -162.929295) (xy 29.689954 -162.892808) (xy 29.647574 -162.850428) (xy 29.611087 -162.802878)
			(xy 29.58112 -162.750972) (xy 29.558184 -162.695599) (xy 29.542671 -162.637706) (xy 29.534848 -162.578284)
			(xy 22.880268 -162.578284) (xy 22.877595 -162.59859) (xy 22.862082 -162.656483) (xy 22.839146 -162.711856)
			(xy 22.809179 -162.763762) (xy 22.772692 -162.811312) (xy 22.730312 -162.853692) (xy 22.682762 -162.890179)
			(xy 22.630856 -162.920146) (xy 22.575483 -162.943082) (xy 22.51759 -162.958595) (xy 22.458168 -162.966418)
			(xy 22.398232 -162.966418) (xy 22.33881 -162.958595) (xy 22.280917 -162.943082) (xy 22.225544 -162.920146)
			(xy 22.173638 -162.890179) (xy 22.126088 -162.853692) (xy 22.083708 -162.811312) (xy 22.047221 -162.763762)
			(xy 22.017254 -162.711856) (xy 21.994318 -162.656483) (xy 21.978805 -162.59859) (xy 21.970982 -162.539168)
			(xy 3.413425 -162.539168) (xy 3.428979 -162.559438) (xy 3.458946 -162.611344) (xy 3.481882 -162.666717)
			(xy 3.497395 -162.72461) (xy 3.505218 -162.784032) (xy 3.505218 -162.843968) (xy 3.497395 -162.90339)
			(xy 3.481882 -162.961283) (xy 3.458946 -163.016656) (xy 3.428979 -163.068562) (xy 3.392492 -163.116112)
			(xy 3.350112 -163.158492) (xy 3.302562 -163.194979) (xy 3.250656 -163.224946) (xy 3.195283 -163.247882)
			(xy 3.13739 -163.263395) (xy 3.077968 -163.271218) (xy 3.048 -163.271708) (xy 3.006852 -163.26993)
			(xy 3.00228 -163.269676) (xy 2.992832 -163.27016) (xy 2.975234 -163.277055) (xy 2.96799 -163.283138)
			(xy 2.912618 -163.333684) (xy 2.905171 -163.341176) (xy 2.896633 -163.360472) (xy 2.896108 -163.371022)
			(xy 2.896108 -163.449) (xy 47.242982 -163.449) (xy 47.247053 -163.393378) (xy 47.259179 -163.338941)
			(xy 47.279102 -163.28685) (xy 47.306398 -163.238215) (xy 47.340484 -163.194072) (xy 47.380633 -163.155363)
			(xy 47.425991 -163.122912) (xy 47.475591 -163.097411) (xy 47.528375 -163.079404) (xy 47.583218 -163.069274)
			(xy 47.638952 -163.067237) (xy 47.694389 -163.073337) (xy 47.748346 -163.087443) (xy 47.799675 -163.109255)
			(xy 47.847281 -163.138309) (xy 47.890149 -163.173984) (xy 47.927366 -163.215521) (xy 47.958139 -163.262034)
			(xy 47.981811 -163.312531) (xy 47.997879 -163.365938) (xy 48.005999 -163.421114) (xy 48.006508 -163.449)
			(xy 48.005999 -163.476886) (xy 47.997879 -163.532062) (xy 47.981811 -163.585469) (xy 47.958139 -163.635966)
			(xy 47.927366 -163.682479) (xy 47.890149 -163.724016) (xy 47.847281 -163.759691) (xy 47.799675 -163.788745)
			(xy 47.748346 -163.810557) (xy 47.694389 -163.824663) (xy 47.638952 -163.830763) (xy 47.583218 -163.828726)
			(xy 47.528375 -163.818596) (xy 47.475591 -163.800589) (xy 47.425991 -163.775088) (xy 47.380633 -163.742637)
			(xy 47.340484 -163.703928) (xy 47.306398 -163.659785) (xy 47.279102 -163.61115) (xy 47.259179 -163.559059)
			(xy 47.247053 -163.504622) (xy 47.242982 -163.449) (xy 2.896108 -163.449) (xy 2.896108 -163.893246)
			(xy 2.896671 -163.904915) (xy 2.906992 -163.925844) (xy 2.91592 -163.933378) (xy 2.990342 -163.98367)
			(xy 2.997962 -163.98748) (xy 3.035046 -163.98748) (xy 3.043682 -163.984178) (xy 3.076048 -163.972845)
			(xy 3.14351 -163.960574) (xy 3.177794 -163.959794) (xy 3.178048 -163.959794) (xy 3.205301 -163.960257)
			(xy 3.259252 -163.968014) (xy 3.311549 -163.98337) (xy 3.36113 -164.006012) (xy 3.406983 -164.03548)
			(xy 3.448175 -164.071173) (xy 3.482903 -164.111251) (xy 11.175978 -164.111251) (xy 11.175978 -164.056749)
			(xy 11.183734 -164.002801) (xy 11.199089 -163.950506) (xy 11.221731 -163.900929) (xy 11.251197 -163.855079)
			(xy 11.286888 -163.813888) (xy 11.328079 -163.778197) (xy 11.373929 -163.748731) (xy 11.423506 -163.726089)
			(xy 11.475801 -163.710734) (xy 11.529749 -163.702978) (xy 11.584251 -163.702978) (xy 11.638199 -163.710734)
			(xy 11.690494 -163.726089) (xy 11.740071 -163.748731) (xy 11.785921 -163.778197) (xy 11.827112 -163.813888)
			(xy 11.862803 -163.855079) (xy 11.892269 -163.900929) (xy 11.914911 -163.950506) (xy 11.917042 -163.957762)
			(xy 16.26819 -163.957762) (xy 16.272261 -163.90214) (xy 16.284387 -163.847703) (xy 16.30431 -163.795612)
			(xy 16.331606 -163.746977) (xy 16.365692 -163.702834) (xy 16.405841 -163.664125) (xy 16.451199 -163.631674)
			(xy 16.500799 -163.606173) (xy 16.553583 -163.588166) (xy 16.608426 -163.578036) (xy 16.66416 -163.575999)
			(xy 16.719597 -163.582099) (xy 16.773554 -163.596205) (xy 16.824883 -163.618017) (xy 16.872489 -163.647071)
			(xy 16.915357 -163.682746) (xy 16.952574 -163.724283) (xy 16.983347 -163.770796) (xy 17.007019 -163.821293)
			(xy 17.023087 -163.8747) (xy 17.031207 -163.929876) (xy 17.031716 -163.957762) (xy 17.0316 -163.964108)
			(xy 35.585382 -163.964108) (xy 35.585382 -163.904172) (xy 35.593205 -163.84475) (xy 35.608718 -163.786857)
			(xy 35.631654 -163.731484) (xy 35.661621 -163.679578) (xy 35.698108 -163.632028) (xy 35.740488 -163.589648)
			(xy 35.788038 -163.553161) (xy 35.839944 -163.523194) (xy 35.895317 -163.500258) (xy 35.95321 -163.484745)
			(xy 36.012632 -163.476922) (xy 36.072568 -163.476922) (xy 36.13199 -163.484745) (xy 36.189883 -163.500258)
			(xy 36.245256 -163.523194) (xy 36.297162 -163.553161) (xy 36.344712 -163.589648) (xy 36.387092 -163.632028)
			(xy 36.423579 -163.679578) (xy 36.453546 -163.731484) (xy 36.476482 -163.786857) (xy 36.491995 -163.84475)
			(xy 36.499818 -163.904172) (xy 36.500308 -163.93414) (xy 36.499818 -163.964108) (xy 36.491995 -164.02353)
			(xy 36.476482 -164.081423) (xy 36.473522 -164.088568) (xy 37.718982 -164.088568) (xy 37.718982 -164.028632)
			(xy 37.726805 -163.96921) (xy 37.742318 -163.911317) (xy 37.765254 -163.855944) (xy 37.795221 -163.804038)
			(xy 37.831708 -163.756488) (xy 37.874088 -163.714108) (xy 37.921638 -163.677621) (xy 37.973544 -163.647654)
			(xy 38.028917 -163.624718) (xy 38.08681 -163.609205) (xy 38.146232 -163.601382) (xy 38.206168 -163.601382)
			(xy 38.26559 -163.609205) (xy 38.323483 -163.624718) (xy 38.378856 -163.647654) (xy 38.430762 -163.677621)
			(xy 38.478312 -163.714108) (xy 38.520692 -163.756488) (xy 38.557179 -163.804038) (xy 38.587146 -163.855944)
			(xy 38.610082 -163.911317) (xy 38.625595 -163.96921) (xy 38.633418 -164.028632) (xy 38.633908 -164.0586)
			(xy 38.633418 -164.088568) (xy 38.625595 -164.14799) (xy 38.610082 -164.205883) (xy 38.587146 -164.261256)
			(xy 38.557179 -164.313162) (xy 38.520692 -164.360712) (xy 38.478312 -164.403092) (xy 38.430762 -164.439579)
			(xy 38.378856 -164.469546) (xy 38.323483 -164.492482) (xy 38.26559 -164.507995) (xy 38.206168 -164.515818)
			(xy 38.146232 -164.515818) (xy 38.08681 -164.507995) (xy 38.028917 -164.492482) (xy 37.973544 -164.469546)
			(xy 37.921638 -164.439579) (xy 37.874088 -164.403092) (xy 37.831708 -164.360712) (xy 37.795221 -164.313162)
			(xy 37.765254 -164.261256) (xy 37.742318 -164.205883) (xy 37.726805 -164.14799) (xy 37.718982 -164.088568)
			(xy 36.473522 -164.088568) (xy 36.453546 -164.136796) (xy 36.423579 -164.188702) (xy 36.387092 -164.236252)
			(xy 36.344712 -164.278632) (xy 36.297162 -164.315119) (xy 36.245256 -164.345086) (xy 36.189883 -164.368022)
			(xy 36.13199 -164.383535) (xy 36.072568 -164.391358) (xy 36.012632 -164.391358) (xy 35.95321 -164.383535)
			(xy 35.895317 -164.368022) (xy 35.839944 -164.345086) (xy 35.788038 -164.315119) (xy 35.740488 -164.278632)
			(xy 35.698108 -164.236252) (xy 35.661621 -164.188702) (xy 35.631654 -164.136796) (xy 35.608718 -164.081423)
			(xy 35.593205 -164.02353) (xy 35.585382 -163.964108) (xy 17.0316 -163.964108) (xy 17.031207 -163.985648)
			(xy 17.023087 -164.040824) (xy 17.007019 -164.094231) (xy 16.983347 -164.144728) (xy 16.952574 -164.191241)
			(xy 16.915357 -164.232778) (xy 16.872489 -164.268453) (xy 16.824883 -164.297507) (xy 16.773554 -164.319319)
			(xy 16.719597 -164.333425) (xy 16.66416 -164.339525) (xy 16.608426 -164.337488) (xy 16.553583 -164.327358)
			(xy 16.500799 -164.309351) (xy 16.451199 -164.28385) (xy 16.405841 -164.251399) (xy 16.365692 -164.21269)
			(xy 16.331606 -164.168547) (xy 16.30431 -164.119912) (xy 16.284387 -164.067821) (xy 16.272261 -164.013384)
			(xy 16.26819 -163.957762) (xy 11.917042 -163.957762) (xy 11.930266 -164.002801) (xy 11.938022 -164.056749)
			(xy 11.938508 -164.084) (xy 11.938015 -164.112189) (xy 11.929713 -164.167953) (xy 11.913303 -164.22189)
			(xy 11.901678 -164.247576) (xy 11.896208 -164.260079) (xy 11.89138 -164.286928) (xy 11.893838 -164.314096)
			(xy 11.903408 -164.339641) (xy 11.919405 -164.361738) (xy 11.940686 -164.378805) (xy 11.965729 -164.389622)
			(xy 11.992743 -164.393417) (xy 12.006326 -164.392102) (xy 12.020866 -164.390328) (xy 12.050099 -164.388424)
			(xy 12.064746 -164.388292) (xy 12.094715 -164.388757) (xy 12.154141 -164.39658) (xy 12.212038 -164.412093)
			(xy 12.267414 -164.43503) (xy 12.319323 -164.464999) (xy 12.366876 -164.501487) (xy 12.409259 -164.543869)
			(xy 12.445748 -164.591422) (xy 12.475717 -164.64333) (xy 12.498655 -164.698706) (xy 12.514169 -164.756602)
			(xy 12.521993 -164.816028) (xy 12.521993 -164.875967) (xy 12.51417 -164.935393) (xy 12.498657 -164.993289)
			(xy 12.47572 -165.048665) (xy 12.445751 -165.100574) (xy 12.409262 -165.148127) (xy 12.36688 -165.19051)
			(xy 12.319327 -165.226998) (xy 12.267419 -165.256968) (xy 12.212043 -165.279906) (xy 12.154147 -165.295419)
			(xy 12.094721 -165.303243) (xy 12.034782 -165.303243) (xy 11.975356 -165.29542) (xy 11.91746 -165.279906)
			(xy 11.862084 -165.256969) (xy 11.810175 -165.227) (xy 11.762622 -165.190512) (xy 11.720239 -165.148129)
			(xy 11.683751 -165.100576) (xy 11.653782 -165.048668) (xy 11.630844 -164.993292) (xy 11.615331 -164.935395)
			(xy 11.607507 -164.875969) (xy 11.607038 -164.846) (xy 11.607527 -164.816067) (xy 11.615337 -164.756713)
			(xy 11.630821 -164.698885) (xy 11.653717 -164.643571) (xy 11.668252 -164.6174) (xy 11.674766 -164.605389)
			(xy 11.681733 -164.578977) (xy 11.681441 -164.551663) (xy 11.673912 -164.525405) (xy 11.659684 -164.502087)
			(xy 11.63978 -164.48338) (xy 11.615624 -164.470626) (xy 11.58895 -164.464739) (xy 11.575288 -164.465)
			(xy 11.557 -164.465508) (xy 11.529749 -164.465022) (xy 11.475801 -164.457266) (xy 11.423506 -164.441911)
			(xy 11.373929 -164.419269) (xy 11.328079 -164.389803) (xy 11.286888 -164.354112) (xy 11.251197 -164.312921)
			(xy 11.221731 -164.267071) (xy 11.199089 -164.217494) (xy 11.183734 -164.165199) (xy 11.175978 -164.111251)
			(xy 3.482903 -164.111251) (xy 3.483869 -164.112366) (xy 3.513337 -164.158219) (xy 3.53598 -164.207799)
			(xy 3.551336 -164.260096) (xy 3.559093 -164.314047) (xy 3.559093 -164.368553) (xy 3.551336 -164.422504)
			(xy 3.53598 -164.474801) (xy 3.513337 -164.524381) (xy 3.483869 -164.570234) (xy 3.448175 -164.611427)
			(xy 3.406983 -164.64712) (xy 3.36113 -164.676588) (xy 3.311549 -164.69923) (xy 3.297865 -164.703248)
			(xy 7.259302 -164.703248) (xy 7.259302 -164.643312) (xy 7.267125 -164.58389) (xy 7.282638 -164.525997)
			(xy 7.305574 -164.470624) (xy 7.335541 -164.418718) (xy 7.372028 -164.371168) (xy 7.414408 -164.328788)
			(xy 7.461958 -164.292301) (xy 7.513864 -164.262334) (xy 7.569237 -164.239398) (xy 7.62713 -164.223885)
			(xy 7.686552 -164.216062) (xy 7.746488 -164.216062) (xy 7.80591 -164.223885) (xy 7.863803 -164.239398)
			(xy 7.919176 -164.262334) (xy 7.971082 -164.292301) (xy 8.018632 -164.328788) (xy 8.061012 -164.371168)
			(xy 8.097499 -164.418718) (xy 8.127466 -164.470624) (xy 8.150402 -164.525997) (xy 8.165915 -164.58389)
			(xy 8.173738 -164.643312) (xy 8.174228 -164.67328) (xy 8.173738 -164.703248) (xy 8.165915 -164.76267)
			(xy 8.150402 -164.820563) (xy 8.127466 -164.875936) (xy 8.097499 -164.927842) (xy 8.061012 -164.975392)
			(xy 8.018632 -165.017772) (xy 7.971082 -165.054259) (xy 7.919176 -165.084226) (xy 7.863803 -165.107162)
			(xy 7.80591 -165.122675) (xy 7.746488 -165.130498) (xy 7.686552 -165.130498) (xy 7.62713 -165.122675)
			(xy 7.569237 -165.107162) (xy 7.513864 -165.084226) (xy 7.461958 -165.054259) (xy 7.414408 -165.017772)
			(xy 7.372028 -164.975392) (xy 7.335541 -164.927842) (xy 7.305574 -164.875936) (xy 7.282638 -164.820563)
			(xy 7.267125 -164.76267) (xy 7.259302 -164.703248) (xy 3.297865 -164.703248) (xy 3.259252 -164.714586)
			(xy 3.205301 -164.722343) (xy 3.178048 -164.72281) (xy 3.153699 -164.722405) (xy 3.105401 -164.716175)
			(xy 3.058285 -164.70386) (xy 3.035554 -164.695124) (xy 3.0353 -164.695124) (xy 3.024374 -164.691365)
			(xy 3.001357 -164.693096) (xy 2.991104 -164.698426) (xy 2.91592 -164.74948) (xy 2.9071 -164.757016)
			(xy 2.896798 -164.777777) (xy 2.896108 -164.789358) (xy 2.896108 -165.452298) (xy 2.896717 -165.463858)
			(xy 2.906892 -165.484626) (xy 2.915666 -165.492176) (xy 2.98069 -165.541706) (xy 2.985375 -165.545076)
			(xy 2.995892 -165.549821) (xy 3.001518 -165.551104) (xy 3.012948 -165.55339) (xy 3.024632 -165.550088)
			(xy 3.054391 -165.542377) (xy 3.115306 -165.534089) (xy 3.146044 -165.533578) (xy 3.146806 -165.533578)
			(xy 3.176775 -165.534047) (xy 3.236202 -165.54187) (xy 3.294098 -165.557383) (xy 3.349475 -165.58032)
			(xy 3.401384 -165.610289) (xy 3.448936 -165.646778) (xy 3.49132 -165.689161) (xy 3.527808 -165.736713)
			(xy 3.529456 -165.739568) (xy 15.562562 -165.739568) (xy 15.562562 -165.679632) (xy 15.570385 -165.62021)
			(xy 15.585898 -165.562317) (xy 15.608834 -165.506944) (xy 15.638801 -165.455038) (xy 15.675288 -165.407488)
			(xy 15.717668 -165.365108) (xy 15.765218 -165.328621) (xy 15.817124 -165.298654) (xy 15.872497 -165.275718)
			(xy 15.93039 -165.260205) (xy 15.989812 -165.252382) (xy 16.049748 -165.252382) (xy 16.10917 -165.260205)
			(xy 16.167063 -165.275718) (xy 16.222436 -165.298654) (xy 16.274342 -165.328621) (xy 16.321892 -165.365108)
			(xy 16.364272 -165.407488) (xy 16.400759 -165.455038) (xy 16.430726 -165.506944) (xy 16.453662 -165.562317)
			(xy 16.469175 -165.62021) (xy 16.471513 -165.637968) (xy 47.053482 -165.637968) (xy 47.053482 -165.578032)
			(xy 47.061305 -165.51861) (xy 47.076818 -165.460717) (xy 47.099754 -165.405344) (xy 47.129721 -165.353438)
			(xy 47.166208 -165.305888) (xy 47.208588 -165.263508) (xy 47.256138 -165.227021) (xy 47.308044 -165.197054)
			(xy 47.363417 -165.174118) (xy 47.42131 -165.158605) (xy 47.480732 -165.150782) (xy 47.540668 -165.150782)
			(xy 47.60009 -165.158605) (xy 47.657983 -165.174118) (xy 47.713356 -165.197054) (xy 47.765262 -165.227021)
			(xy 47.812812 -165.263508) (xy 47.855192 -165.305888) (xy 47.891679 -165.353438) (xy 47.921646 -165.405344)
			(xy 47.944582 -165.460717) (xy 47.960095 -165.51861) (xy 47.967918 -165.578032) (xy 47.968408 -165.608)
			(xy 47.967918 -165.637968) (xy 47.960095 -165.69739) (xy 47.944582 -165.755283) (xy 47.921646 -165.810656)
			(xy 47.891679 -165.862562) (xy 47.855192 -165.910112) (xy 47.812812 -165.952492) (xy 47.765262 -165.988979)
			(xy 47.713356 -166.018946) (xy 47.657983 -166.041882) (xy 47.60009 -166.057395) (xy 47.540668 -166.065218)
			(xy 47.480732 -166.065218) (xy 47.42131 -166.057395) (xy 47.363417 -166.041882) (xy 47.308044 -166.018946)
			(xy 47.256138 -165.988979) (xy 47.208588 -165.952492) (xy 47.166208 -165.910112) (xy 47.129721 -165.862562)
			(xy 47.099754 -165.810656) (xy 47.076818 -165.755283) (xy 47.061305 -165.69739) (xy 47.053482 -165.637968)
			(xy 16.471513 -165.637968) (xy 16.476998 -165.679632) (xy 16.477488 -165.7096) (xy 16.476998 -165.739568)
			(xy 16.469175 -165.79899) (xy 16.453662 -165.856883) (xy 16.430726 -165.912256) (xy 16.400759 -165.964162)
			(xy 16.364272 -166.011712) (xy 16.321892 -166.054092) (xy 16.274342 -166.090579) (xy 16.222436 -166.120546)
			(xy 16.167063 -166.143482) (xy 16.10917 -166.158995) (xy 16.049748 -166.166818) (xy 15.989812 -166.166818)
			(xy 15.93039 -166.158995) (xy 15.872497 -166.143482) (xy 15.817124 -166.120546) (xy 15.765218 -166.090579)
			(xy 15.717668 -166.054092) (xy 15.675288 -166.011712) (xy 15.638801 -165.964162) (xy 15.608834 -165.912256)
			(xy 15.585898 -165.856883) (xy 15.570385 -165.79899) (xy 15.562562 -165.739568) (xy 3.529456 -165.739568)
			(xy 3.557778 -165.788622) (xy 3.580716 -165.843998) (xy 3.596229 -165.901894) (xy 3.604053 -165.961321)
			(xy 3.604053 -166.021259) (xy 3.596229 -166.080686) (xy 3.580716 -166.138582) (xy 3.557778 -166.193958)
			(xy 3.527808 -166.245867) (xy 3.49132 -166.293419) (xy 3.448936 -166.335802) (xy 3.401384 -166.372291)
			(xy 3.349475 -166.40226) (xy 3.294098 -166.425197) (xy 3.236202 -166.44071) (xy 3.176775 -166.448533)
			(xy 3.146806 -166.448994) (xy 3.146044 -166.448994) (xy 3.115307 -166.448464) (xy 3.054392 -166.440187)
			(xy 3.024632 -166.432484) (xy 3.012948 -166.429182) (xy 3.001518 -166.431468) (xy 2.995891 -166.432748)
			(xy 2.985376 -166.437497) (xy 2.98069 -166.440866) (xy 2.915666 -166.490396) (xy 2.906884 -166.497939)
			(xy 2.896718 -166.518711) (xy 2.896108 -166.530274) (xy 2.896108 -167.669968) (xy 7.853662 -167.669968)
			(xy 7.853662 -167.610032) (xy 7.861485 -167.55061) (xy 7.876998 -167.492717) (xy 7.899934 -167.437344)
			(xy 7.929901 -167.385438) (xy 7.966388 -167.337888) (xy 8.008768 -167.295508) (xy 8.056318 -167.259021)
			(xy 8.108224 -167.229054) (xy 8.163597 -167.206118) (xy 8.22149 -167.190605) (xy 8.280912 -167.182782)
			(xy 8.340848 -167.182782) (xy 8.40027 -167.190605) (xy 8.458163 -167.206118) (xy 8.513536 -167.229054)
			(xy 8.565442 -167.259021) (xy 8.612992 -167.295508) (xy 8.655372 -167.337888) (xy 8.691859 -167.385438)
			(xy 8.721826 -167.437344) (xy 8.744762 -167.492717) (xy 8.760275 -167.55061) (xy 8.768098 -167.610032)
			(xy 8.768588 -167.64) (xy 8.768098 -167.669968) (xy 8.760275 -167.72939) (xy 8.744762 -167.787283)
			(xy 8.721826 -167.842656) (xy 8.691859 -167.894562) (xy 8.655372 -167.942112) (xy 8.612992 -167.984492)
			(xy 8.565442 -168.020979) (xy 8.513536 -168.050946) (xy 8.458163 -168.073882) (xy 8.40027 -168.089395)
			(xy 8.340848 -168.097218) (xy 8.280912 -168.097218) (xy 8.22149 -168.089395) (xy 8.163597 -168.073882)
			(xy 8.108224 -168.050946) (xy 8.056318 -168.020979) (xy 8.008768 -167.984492) (xy 7.966388 -167.942112)
			(xy 7.929901 -167.894562) (xy 7.899934 -167.842656) (xy 7.876998 -167.787283) (xy 7.861485 -167.72939)
			(xy 7.853662 -167.669968) (xy 2.896108 -167.669968) (xy 2.896108 -168.402) (xy 3.408932 -168.402)
			(xy 3.413003 -168.346378) (xy 3.425129 -168.291941) (xy 3.445052 -168.23985) (xy 3.472348 -168.191215)
			(xy 3.506434 -168.147072) (xy 3.546583 -168.108363) (xy 3.591941 -168.075912) (xy 3.641541 -168.050411)
			(xy 3.694325 -168.032404) (xy 3.749168 -168.022274) (xy 3.804902 -168.020237) (xy 3.860339 -168.026337)
			(xy 3.914296 -168.040443) (xy 3.965625 -168.062255) (xy 4.013231 -168.091309) (xy 4.056099 -168.126984)
			(xy 4.093316 -168.168521) (xy 4.124089 -168.215034) (xy 4.147761 -168.265531) (xy 4.163829 -168.318938)
			(xy 4.171949 -168.374114) (xy 4.172458 -168.402) (xy 4.171949 -168.429886) (xy 4.163829 -168.485062)
			(xy 4.147761 -168.538469) (xy 4.124089 -168.588966) (xy 4.093316 -168.635479) (xy 4.082216 -168.647868)
			(xy 5.898624 -168.647868) (xy 5.898624 -168.587932) (xy 5.906447 -168.52851) (xy 5.92196 -168.470617)
			(xy 5.944896 -168.415244) (xy 5.974863 -168.363338) (xy 6.01135 -168.315788) (xy 6.05373 -168.273408)
			(xy 6.10128 -168.236921) (xy 6.153186 -168.206954) (xy 6.208559 -168.184018) (xy 6.266452 -168.168505)
			(xy 6.325874 -168.160682) (xy 6.38581 -168.160682) (xy 6.445232 -168.168505) (xy 6.503125 -168.184018)
			(xy 6.558498 -168.206954) (xy 6.610404 -168.236921) (xy 6.657954 -168.273408) (xy 6.700334 -168.315788)
			(xy 6.736821 -168.363338) (xy 6.766788 -168.415244) (xy 6.789724 -168.470617) (xy 6.805237 -168.52851)
			(xy 6.81306 -168.587932) (xy 6.81355 -168.6179) (xy 6.81306 -168.647868) (xy 6.805237 -168.70729)
			(xy 6.789724 -168.765183) (xy 6.766788 -168.820556) (xy 6.736821 -168.872462) (xy 6.700334 -168.920012)
			(xy 6.657954 -168.962392) (xy 6.610404 -168.998879) (xy 6.558498 -169.028846) (xy 6.503125 -169.051782)
			(xy 6.445232 -169.067295) (xy 6.38581 -169.075118) (xy 6.325874 -169.075118) (xy 6.266452 -169.067295)
			(xy 6.208559 -169.051782) (xy 6.153186 -169.028846) (xy 6.10128 -168.998879) (xy 6.05373 -168.962392)
			(xy 6.01135 -168.920012) (xy 5.974863 -168.872462) (xy 5.944896 -168.820556) (xy 5.92196 -168.765183)
			(xy 5.906447 -168.70729) (xy 5.898624 -168.647868) (xy 4.082216 -168.647868) (xy 4.056099 -168.677016)
			(xy 4.013231 -168.712691) (xy 3.965625 -168.741745) (xy 3.914296 -168.763557) (xy 3.860339 -168.777663)
			(xy 3.804902 -168.783763) (xy 3.749168 -168.781726) (xy 3.694325 -168.771596) (xy 3.641541 -168.753589)
			(xy 3.591941 -168.728088) (xy 3.546583 -168.695637) (xy 3.506434 -168.656928) (xy 3.472348 -168.612785)
			(xy 3.445052 -168.56415) (xy 3.425129 -168.512059) (xy 3.413003 -168.457622) (xy 3.408932 -168.402)
			(xy 2.896108 -168.402) (xy 2.896108 -169.955968) (xy 3.333732 -169.955968) (xy 3.333732 -169.896032)
			(xy 3.341555 -169.83661) (xy 3.357068 -169.778717) (xy 3.380004 -169.723344) (xy 3.409971 -169.671438)
			(xy 3.446458 -169.623888) (xy 3.488838 -169.581508) (xy 3.536388 -169.545021) (xy 3.588294 -169.515054)
			(xy 3.643667 -169.492118) (xy 3.70156 -169.476605) (xy 3.760982 -169.468782) (xy 3.820918 -169.468782)
			(xy 3.88034 -169.476605) (xy 3.938233 -169.492118) (xy 3.993606 -169.515054) (xy 4.045512 -169.545021)
			(xy 4.093062 -169.581508) (xy 4.135442 -169.623888) (xy 4.171929 -169.671438) (xy 4.201896 -169.723344)
			(xy 4.224832 -169.778717) (xy 4.240345 -169.83661) (xy 4.248168 -169.896032) (xy 4.248658 -169.926)
			(xy 4.248168 -169.955968) (xy 4.240345 -170.01539) (xy 4.224832 -170.073283) (xy 4.201896 -170.128656)
			(xy 4.176948 -170.171868) (xy 5.898624 -170.171868) (xy 5.898624 -170.111932) (xy 5.906447 -170.05251)
			(xy 5.92196 -169.994617) (xy 5.944896 -169.939244) (xy 5.974863 -169.887338) (xy 6.01135 -169.839788)
			(xy 6.05373 -169.797408) (xy 6.10128 -169.760921) (xy 6.153186 -169.730954) (xy 6.208559 -169.708018)
			(xy 6.266452 -169.692505) (xy 6.325874 -169.684682) (xy 6.38581 -169.684682) (xy 6.445232 -169.692505)
			(xy 6.503125 -169.708018) (xy 6.558498 -169.730954) (xy 6.610404 -169.760921) (xy 6.657954 -169.797408)
			(xy 6.700334 -169.839788) (xy 6.736821 -169.887338) (xy 6.766788 -169.939244) (xy 6.789724 -169.994617)
			(xy 6.805237 -170.05251) (xy 6.81306 -170.111932) (xy 6.81355 -170.1419) (xy 6.81306 -170.171868)
			(xy 6.805237 -170.23129) (xy 6.789724 -170.289183) (xy 6.766788 -170.344556) (xy 6.736821 -170.396462)
			(xy 6.700334 -170.444012) (xy 6.657954 -170.486392) (xy 6.610404 -170.522879) (xy 6.558498 -170.552846)
			(xy 6.503125 -170.575782) (xy 6.445232 -170.591295) (xy 6.38581 -170.599118) (xy 6.325874 -170.599118)
			(xy 6.266452 -170.591295) (xy 6.208559 -170.575782) (xy 6.153186 -170.552846) (xy 6.10128 -170.522879)
			(xy 6.05373 -170.486392) (xy 6.01135 -170.444012) (xy 5.974863 -170.396462) (xy 5.944896 -170.344556)
			(xy 5.92196 -170.289183) (xy 5.906447 -170.23129) (xy 5.898624 -170.171868) (xy 4.176948 -170.171868)
			(xy 4.171929 -170.180562) (xy 4.135442 -170.228112) (xy 4.093062 -170.270492) (xy 4.045512 -170.306979)
			(xy 3.993606 -170.336946) (xy 3.938233 -170.359882) (xy 3.88034 -170.375395) (xy 3.820918 -170.383218)
			(xy 3.760982 -170.383218) (xy 3.70156 -170.375395) (xy 3.643667 -170.359882) (xy 3.588294 -170.336946)
			(xy 3.536388 -170.306979) (xy 3.488838 -170.270492) (xy 3.446458 -170.228112) (xy 3.409971 -170.180562)
			(xy 3.380004 -170.128656) (xy 3.357068 -170.073283) (xy 3.341555 -170.01539) (xy 3.333732 -169.955968)
			(xy 2.896108 -169.955968) (xy 2.896108 -171.935648) (xy 2.896802 -171.947516) (xy 2.90753 -171.968699)
			(xy 2.916682 -171.976288) (xy 2.925064 -171.982384) (xy 2.983992 -172.025056) (xy 2.988932 -172.02843)
			(xy 2.999965 -172.033047) (xy 3.005836 -172.0342) (xy 3.017774 -172.035978) (xy 3.029712 -172.031914)
			(xy 3.065022 -172.020906) (xy 3.138021 -172.009032) (xy 3.175 -172.008292) (xy 3.179826 -172.008292)
			(xy 3.209588 -172.009083) (xy 3.268537 -172.017424) (xy 3.325908 -172.033338) (xy 3.380731 -172.056556)
			(xy 3.432081 -172.086686) (xy 3.479091 -172.12322) (xy 3.520967 -172.16554) (xy 3.557003 -172.212933)
			(xy 3.58659 -172.264597) (xy 3.609229 -172.319662) (xy 3.624537 -172.377197) (xy 3.632256 -172.436232)
			(xy 3.632708 -172.466) (xy 3.632218 -172.495968) (xy 7.855694 -172.495968) (xy 7.855694 -172.436032)
			(xy 7.863517 -172.37661) (xy 7.87903 -172.318717) (xy 7.901966 -172.263344) (xy 7.931933 -172.211438)
			(xy 7.96842 -172.163888) (xy 8.0108 -172.121508) (xy 8.05835 -172.085021) (xy 8.110256 -172.055054)
			(xy 8.165629 -172.032118) (xy 8.223522 -172.016605) (xy 8.282944 -172.008782) (xy 8.34288 -172.008782)
			(xy 8.402302 -172.016605) (xy 8.460195 -172.032118) (xy 8.515568 -172.055054) (xy 8.567474 -172.085021)
			(xy 8.615024 -172.121508) (xy 8.657404 -172.163888) (xy 8.693891 -172.211438) (xy 8.723858 -172.263344)
			(xy 8.746794 -172.318717) (xy 8.762307 -172.37661) (xy 8.77013 -172.436032) (xy 8.77062 -172.466)
			(xy 8.77013 -172.495968) (xy 8.762307 -172.55539) (xy 8.746794 -172.613283) (xy 8.723858 -172.668656)
			(xy 8.693891 -172.720562) (xy 8.657404 -172.768112) (xy 8.615024 -172.810492) (xy 8.567474 -172.846979)
			(xy 8.515568 -172.876946) (xy 8.460195 -172.899882) (xy 8.402302 -172.915395) (xy 8.34288 -172.923218)
			(xy 8.282944 -172.923218) (xy 8.223522 -172.915395) (xy 8.165629 -172.899882) (xy 8.110256 -172.876946)
			(xy 8.05835 -172.846979) (xy 8.0108 -172.810492) (xy 7.96842 -172.768112) (xy 7.931933 -172.720562)
			(xy 7.901966 -172.668656) (xy 7.87903 -172.613283) (xy 7.863517 -172.55539) (xy 7.855694 -172.495968)
			(xy 3.632218 -172.495968) (xy 3.624395 -172.55539) (xy 3.608882 -172.613283) (xy 3.585946 -172.668656)
			(xy 3.555979 -172.720562) (xy 3.519492 -172.768112) (xy 3.477112 -172.810492) (xy 3.429562 -172.846979)
			(xy 3.377656 -172.876946) (xy 3.322283 -172.899882) (xy 3.26439 -172.915395) (xy 3.204968 -172.923218)
			(xy 3.175 -172.923708) (xy 3.174746 -172.923708) (xy 3.137825 -172.923009) (xy 3.064944 -172.911145)
			(xy 3.029712 -172.900086) (xy 3.023795 -172.898267) (xy 3.011463 -172.897236) (xy 3.005328 -172.898054)
			(xy 2.993898 -172.899832) (xy 2.925064 -172.949616) (xy 2.916682 -172.955712) (xy 2.907502 -172.963276)
			(xy 2.896785 -172.984475) (xy 2.896108 -172.996352) (xy 2.896108 -173.863508) (xy 9.823196 -173.863508)
			(xy 9.823196 -167.787828) (xy 9.823655 -167.758185) (xy 9.830909 -167.699344) (xy 9.837674 -167.67048)
			(xy 9.838944 -167.664384) (xy 9.838944 -166.755826) (xy 9.839499 -166.722225) (xy 9.848833 -166.655675)
			(xy 9.86731 -166.591063) (xy 9.894574 -166.52964) (xy 9.911842 -166.50081) (xy 9.915468 -166.494607)
			(xy 9.919467 -166.480813) (xy 9.919716 -166.473632) (xy 9.919716 -166.43858) (xy 9.945878 -166.43858)
			(xy 9.965182 -166.430198) (xy 9.972294 -166.422578) (xy 9.995166 -166.399408) (xy 10.046031 -166.358769)
			(xy 10.101891 -166.325327) (xy 10.161736 -166.299688) (xy 10.224482 -166.282317) (xy 10.288992 -166.273528)
			(xy 10.321544 -166.272972) (xy 11.369548 -166.272972) (xy 11.401107 -166.273539) (xy 11.463681 -166.281807)
			(xy 11.524645 -166.298158) (xy 11.582959 -166.322313) (xy 11.637628 -166.353859) (xy 11.687722 -166.392259)
			(xy 11.710416 -166.414196) (xy 11.76782 -166.4716) (xy 16.483582 -166.4716) (xy 16.487653 -166.415978)
			(xy 16.499779 -166.361541) (xy 16.519702 -166.30945) (xy 16.546998 -166.260815) (xy 16.581084 -166.216672)
			(xy 16.621233 -166.177963) (xy 16.666591 -166.145512) (xy 16.716191 -166.120011) (xy 16.768975 -166.102004)
			(xy 16.823818 -166.091874) (xy 16.879552 -166.089837) (xy 16.934989 -166.095937) (xy 16.988946 -166.110043)
			(xy 17.040275 -166.131855) (xy 17.087881 -166.160909) (xy 17.130749 -166.196584) (xy 17.167966 -166.238121)
			(xy 17.198739 -166.284634) (xy 17.222411 -166.335131) (xy 17.238479 -166.388538) (xy 17.246599 -166.443714)
			(xy 17.247108 -166.4716) (xy 17.246599 -166.499486) (xy 17.238479 -166.554662) (xy 17.222411 -166.608069)
			(xy 17.198739 -166.658566) (xy 17.167966 -166.705079) (xy 17.130749 -166.746616) (xy 17.087881 -166.782291)
			(xy 17.040275 -166.811345) (xy 16.988946 -166.833157) (xy 16.934989 -166.847263) (xy 16.879552 -166.853363)
			(xy 16.823818 -166.851326) (xy 16.768975 -166.841196) (xy 16.716191 -166.823189) (xy 16.666591 -166.797688)
			(xy 16.621233 -166.765237) (xy 16.581084 -166.726528) (xy 16.546998 -166.682385) (xy 16.519702 -166.63375)
			(xy 16.499779 -166.581659) (xy 16.487653 -166.527222) (xy 16.483582 -166.4716) (xy 11.76782 -166.4716)
			(xy 11.83259 -166.53637) (xy 11.854598 -166.559095) (xy 11.893101 -166.609293) (xy 11.924724 -166.664086)
			(xy 11.948927 -166.722537) (xy 11.965296 -166.783646) (xy 11.973551 -166.846368) (xy 11.973935 -166.869868)
			(xy 43.22494 -166.869868) (xy 43.22494 -166.809932) (xy 43.232763 -166.75051) (xy 43.248276 -166.692617)
			(xy 43.271212 -166.637244) (xy 43.301179 -166.585338) (xy 43.337666 -166.537788) (xy 43.380046 -166.495408)
			(xy 43.427596 -166.458921) (xy 43.479502 -166.428954) (xy 43.534875 -166.406018) (xy 43.592768 -166.390505)
			(xy 43.65219 -166.382682) (xy 43.712126 -166.382682) (xy 43.771548 -166.390505) (xy 43.829441 -166.406018)
			(xy 43.884814 -166.428954) (xy 43.93672 -166.458921) (xy 43.98427 -166.495408) (xy 44.02665 -166.537788)
			(xy 44.063137 -166.585338) (xy 44.093104 -166.637244) (xy 44.11604 -166.692617) (xy 44.131553 -166.75051)
			(xy 44.139376 -166.809932) (xy 44.139866 -166.8399) (xy 44.139376 -166.869868) (xy 44.131553 -166.92929)
			(xy 44.11604 -166.987183) (xy 44.093104 -167.042556) (xy 44.063137 -167.094462) (xy 44.02665 -167.142012)
			(xy 43.98427 -167.184392) (xy 43.93672 -167.220879) (xy 43.884814 -167.250846) (xy 43.829441 -167.273782)
			(xy 43.771548 -167.289295) (xy 43.712126 -167.297118) (xy 43.65219 -167.297118) (xy 43.592768 -167.289295)
			(xy 43.534875 -167.273782) (xy 43.479502 -167.250846) (xy 43.427596 -167.220879) (xy 43.380046 -167.184392)
			(xy 43.337666 -167.142012) (xy 43.301179 -167.094462) (xy 43.271212 -167.042556) (xy 43.248276 -166.987183)
			(xy 43.232763 -166.92929) (xy 43.22494 -166.869868) (xy 11.973935 -166.869868) (xy 11.974068 -166.878)
			(xy 11.973613 -166.909634) (xy 11.965354 -166.97236) (xy 11.948979 -167.033472) (xy 11.924766 -167.091923)
			(xy 11.893131 -167.146713) (xy 11.854614 -167.196905) (xy 11.809875 -167.24164) (xy 11.75968 -167.280153)
			(xy 11.704887 -167.311784) (xy 11.646434 -167.335992) (xy 11.585321 -167.352362) (xy 11.522594 -167.360615)
			(xy 11.49096 -167.361108) (xy 11.457595 -167.360542) (xy 11.391502 -167.351334) (xy 11.327306 -167.333115)
			(xy 11.266231 -167.30623) (xy 11.209438 -167.271192) (xy 11.183366 -167.250364) (xy 11.176378 -167.245051)
			(xy 11.159878 -167.239086) (xy 11.151108 -167.23868) (xy 10.85596 -167.23868) (xy 10.845952 -167.239155)
			(xy 10.827463 -167.246824) (xy 10.813313 -167.26098) (xy 10.805651 -167.279472) (xy 10.80516 -167.28948)
			(xy 10.80516 -167.669968) (xy 23.68091 -167.669968) (xy 23.68091 -167.610032) (xy 23.688733 -167.55061)
			(xy 23.704246 -167.492717) (xy 23.727182 -167.437344) (xy 23.757149 -167.385438) (xy 23.793636 -167.337888)
			(xy 23.836016 -167.295508) (xy 23.883566 -167.259021) (xy 23.935472 -167.229054) (xy 23.990845 -167.206118)
			(xy 24.048738 -167.190605) (xy 24.10816 -167.182782) (xy 24.168096 -167.182782) (xy 24.227518 -167.190605)
			(xy 24.285411 -167.206118) (xy 24.340784 -167.229054) (xy 24.39269 -167.259021) (xy 24.44024 -167.295508)
			(xy 24.48262 -167.337888) (xy 24.519107 -167.385438) (xy 24.549074 -167.437344) (xy 24.57201 -167.492717)
			(xy 24.587523 -167.55061) (xy 24.595346 -167.610032) (xy 24.595836 -167.64) (xy 24.595346 -167.669968)
			(xy 31.165528 -167.669968) (xy 31.165528 -167.610032) (xy 31.173351 -167.55061) (xy 31.188864 -167.492717)
			(xy 31.2118 -167.437344) (xy 31.241767 -167.385438) (xy 31.278254 -167.337888) (xy 31.320634 -167.295508)
			(xy 31.368184 -167.259021) (xy 31.42009 -167.229054) (xy 31.475463 -167.206118) (xy 31.533356 -167.190605)
			(xy 31.592778 -167.182782) (xy 31.652714 -167.182782) (xy 31.712136 -167.190605) (xy 31.770029 -167.206118)
			(xy 31.825402 -167.229054) (xy 31.877308 -167.259021) (xy 31.924858 -167.295508) (xy 31.967238 -167.337888)
			(xy 32.003725 -167.385438) (xy 32.021351 -167.415968) (xy 33.724832 -167.415968) (xy 33.724832 -167.356032)
			(xy 33.732655 -167.29661) (xy 33.748168 -167.238717) (xy 33.771104 -167.183344) (xy 33.801071 -167.131438)
			(xy 33.837558 -167.083888) (xy 33.879938 -167.041508) (xy 33.927488 -167.005021) (xy 33.979394 -166.975054)
			(xy 34.034767 -166.952118) (xy 34.09266 -166.936605) (xy 34.152082 -166.928782) (xy 34.212018 -166.928782)
			(xy 34.27144 -166.936605) (xy 34.329333 -166.952118) (xy 34.384706 -166.975054) (xy 34.436612 -167.005021)
			(xy 34.484162 -167.041508) (xy 34.526542 -167.083888) (xy 34.563029 -167.131438) (xy 34.592996 -167.183344)
			(xy 34.615932 -167.238717) (xy 34.631445 -167.29661) (xy 34.639268 -167.356032) (xy 34.639758 -167.386)
			(xy 34.639268 -167.415968) (xy 34.631445 -167.47539) (xy 34.621367 -167.513) (xy 47.128682 -167.513)
			(xy 47.132753 -167.457378) (xy 47.144879 -167.402941) (xy 47.164802 -167.35085) (xy 47.192098 -167.302215)
			(xy 47.226184 -167.258072) (xy 47.266333 -167.219363) (xy 47.311691 -167.186912) (xy 47.361291 -167.161411)
			(xy 47.414075 -167.143404) (xy 47.468918 -167.133274) (xy 47.524652 -167.131237) (xy 47.580089 -167.137337)
			(xy 47.634046 -167.151443) (xy 47.685375 -167.173255) (xy 47.732981 -167.202309) (xy 47.775849 -167.237984)
			(xy 47.813066 -167.279521) (xy 47.843839 -167.326034) (xy 47.867511 -167.376531) (xy 47.883579 -167.429938)
			(xy 47.891699 -167.485114) (xy 47.892208 -167.513) (xy 47.891699 -167.540886) (xy 47.883579 -167.596062)
			(xy 47.867511 -167.649469) (xy 47.843839 -167.699966) (xy 47.813066 -167.746479) (xy 47.775849 -167.788016)
			(xy 47.732981 -167.823691) (xy 47.685375 -167.852745) (xy 47.634046 -167.874557) (xy 47.580089 -167.888663)
			(xy 47.524652 -167.894763) (xy 47.468918 -167.892726) (xy 47.414075 -167.882596) (xy 47.361291 -167.864589)
			(xy 47.311691 -167.839088) (xy 47.266333 -167.806637) (xy 47.226184 -167.767928) (xy 47.192098 -167.723785)
			(xy 47.164802 -167.67515) (xy 47.144879 -167.623059) (xy 47.132753 -167.568622) (xy 47.128682 -167.513)
			(xy 34.621367 -167.513) (xy 34.615932 -167.533283) (xy 34.592996 -167.588656) (xy 34.563029 -167.640562)
			(xy 34.526542 -167.688112) (xy 34.484162 -167.730492) (xy 34.436612 -167.766979) (xy 34.384706 -167.796946)
			(xy 34.329333 -167.819882) (xy 34.27144 -167.835395) (xy 34.212018 -167.843218) (xy 34.152082 -167.843218)
			(xy 34.09266 -167.835395) (xy 34.034767 -167.819882) (xy 33.979394 -167.796946) (xy 33.927488 -167.766979)
			(xy 33.879938 -167.730492) (xy 33.837558 -167.688112) (xy 33.801071 -167.640562) (xy 33.771104 -167.588656)
			(xy 33.748168 -167.533283) (xy 33.732655 -167.47539) (xy 33.724832 -167.415968) (xy 32.021351 -167.415968)
			(xy 32.033692 -167.437344) (xy 32.056628 -167.492717) (xy 32.072141 -167.55061) (xy 32.079964 -167.610032)
			(xy 32.080454 -167.64) (xy 32.079964 -167.669968) (xy 32.072141 -167.72939) (xy 32.056628 -167.787283)
			(xy 32.033692 -167.842656) (xy 32.003725 -167.894562) (xy 31.967238 -167.942112) (xy 31.924858 -167.984492)
			(xy 31.877308 -168.020979) (xy 31.825402 -168.050946) (xy 31.770029 -168.073882) (xy 31.712136 -168.089395)
			(xy 31.652714 -168.097218) (xy 31.592778 -168.097218) (xy 31.533356 -168.089395) (xy 31.475463 -168.073882)
			(xy 31.42009 -168.050946) (xy 31.368184 -168.020979) (xy 31.320634 -167.984492) (xy 31.278254 -167.942112)
			(xy 31.241767 -167.894562) (xy 31.2118 -167.842656) (xy 31.188864 -167.787283) (xy 31.173351 -167.72939)
			(xy 31.165528 -167.669968) (xy 24.595346 -167.669968) (xy 24.587523 -167.72939) (xy 24.57201 -167.787283)
			(xy 24.549074 -167.842656) (xy 24.519107 -167.894562) (xy 24.48262 -167.942112) (xy 24.44024 -167.984492)
			(xy 24.39269 -168.020979) (xy 24.340784 -168.050946) (xy 24.285411 -168.073882) (xy 24.227518 -168.089395)
			(xy 24.168096 -168.097218) (xy 24.10816 -168.097218) (xy 24.048738 -168.089395) (xy 23.990845 -168.073882)
			(xy 23.935472 -168.050946) (xy 23.883566 -168.020979) (xy 23.836016 -167.984492) (xy 23.793636 -167.942112)
			(xy 23.757149 -167.894562) (xy 23.727182 -167.842656) (xy 23.704246 -167.787283) (xy 23.688733 -167.72939)
			(xy 23.68091 -167.669968) (xy 10.80516 -167.669968) (xy 10.80516 -167.771826) (xy 10.804647 -167.801476)
			(xy 10.797259 -167.860317) (xy 10.790428 -167.889174) (xy 10.788904 -167.89527) (xy 10.788904 -168.343068)
			(xy 12.99894 -168.343068) (xy 12.99894 -168.283132) (xy 13.006763 -168.22371) (xy 13.022276 -168.165817)
			(xy 13.045212 -168.110444) (xy 13.075179 -168.058538) (xy 13.111666 -168.010988) (xy 13.154046 -167.968608)
			(xy 13.201596 -167.932121) (xy 13.253502 -167.902154) (xy 13.308875 -167.879218) (xy 13.366768 -167.863705)
			(xy 13.42619 -167.855882) (xy 13.486126 -167.855882) (xy 13.545548 -167.863705) (xy 13.603441 -167.879218)
			(xy 13.658814 -167.902154) (xy 13.71072 -167.932121) (xy 13.75827 -167.968608) (xy 13.80065 -168.010988)
			(xy 13.837137 -168.058538) (xy 13.867104 -168.110444) (xy 13.89004 -168.165817) (xy 13.905553 -168.22371)
			(xy 13.913376 -168.283132) (xy 13.913866 -168.3131) (xy 13.913376 -168.343068) (xy 13.905553 -168.40249)
			(xy 13.89004 -168.460383) (xy 13.867104 -168.515756) (xy 13.837137 -168.567662) (xy 13.80065 -168.615212)
			(xy 13.75827 -168.657592) (xy 13.71072 -168.694079) (xy 13.658814 -168.724046) (xy 13.603441 -168.746982)
			(xy 13.545548 -168.762495) (xy 13.486126 -168.770318) (xy 13.42619 -168.770318) (xy 13.366768 -168.762495)
			(xy 13.308875 -168.746982) (xy 13.253502 -168.724046) (xy 13.201596 -168.694079) (xy 13.154046 -168.657592)
			(xy 13.111666 -168.615212) (xy 13.075179 -168.567662) (xy 13.045212 -168.515756) (xy 13.022276 -168.460383)
			(xy 13.006763 -168.40249) (xy 12.99894 -168.343068) (xy 10.788904 -168.343068) (xy 10.788904 -169.265092)
			(xy 10.789326 -169.275113) (xy 10.796994 -169.293631) (xy 10.811166 -169.307804) (xy 10.829683 -169.315473)
			(xy 10.839704 -169.315892) (xy 11.23696 -169.315892) (xy 11.264579 -169.316331) (xy 11.31945 -169.322692)
			(xy 11.346434 -169.328592) (xy 11.357102 -169.331132) (xy 11.378184 -169.326814) (xy 11.44905 -169.276776)
			(xy 11.457593 -169.270161) (xy 11.468654 -169.251626) (xy 11.470386 -169.240962) (xy 11.470386 -169.240708)
			(xy 11.474199 -169.210543) (xy 11.488823 -169.151526) (xy 11.511132 -169.094964) (xy 11.540733 -169.041854)
			(xy 11.577106 -168.99313) (xy 11.619609 -168.949652) (xy 11.667495 -168.912183) (xy 11.71992 -168.881385)
			(xy 11.775961 -168.857799) (xy 11.834632 -168.84184) (xy 11.894899 -168.83379) (xy 11.9253 -168.833292)
			(xy 11.955268 -168.833782) (xy 12.01469 -168.841605) (xy 12.072583 -168.857118) (xy 12.127956 -168.880054)
			(xy 12.179862 -168.910021) (xy 12.227412 -168.946508) (xy 12.269792 -168.988888) (xy 12.306279 -169.036438)
			(xy 12.336246 -169.088344) (xy 12.359182 -169.143717) (xy 12.374695 -169.20161) (xy 12.382518 -169.261032)
			(xy 12.383008 -169.291) (xy 12.382502 -169.31822) (xy 16.249553 -169.31822) (xy 16.249558 -169.263713)
			(xy 16.25732 -169.209761) (xy 16.272681 -169.157464) (xy 16.295329 -169.107884) (xy 16.324803 -169.062033)
			(xy 16.360502 -169.020843) (xy 16.4017 -168.985153) (xy 16.447558 -168.955689) (xy 16.497142 -168.933052)
			(xy 16.549443 -168.917702) (xy 16.603396 -168.909952) (xy 16.63065 -168.909492) (xy 16.651848 -168.909791)
			(xy 16.693983 -168.914501) (xy 16.714724 -168.91889) (xy 16.729674 -168.921689) (xy 16.759983 -168.919394)
			(xy 16.788276 -168.908283) (xy 16.812048 -168.889339) (xy 16.829195 -168.864241) (xy 16.838198 -168.835208)
			(xy 16.838261 -168.804811) (xy 16.834358 -168.790112) (xy 16.825012 -168.757438) (xy 16.814934 -168.690232)
			(xy 16.814292 -168.656254) (xy 16.814292 -168.656) (xy 16.814782 -168.626032) (xy 16.822605 -168.56661)
			(xy 16.838118 -168.508717) (xy 16.861054 -168.453344) (xy 16.891021 -168.401438) (xy 16.927508 -168.353888)
			(xy 16.969888 -168.311508) (xy 17.017438 -168.275021) (xy 17.069344 -168.245054) (xy 17.124717 -168.222118)
			(xy 17.18261 -168.206605) (xy 17.242032 -168.198782) (xy 17.301968 -168.198782) (xy 17.36139 -168.206605)
			(xy 17.419283 -168.222118) (xy 17.474656 -168.245054) (xy 17.526562 -168.275021) (xy 17.574112 -168.311508)
			(xy 17.616492 -168.353888) (xy 17.652979 -168.401438) (xy 17.682946 -168.453344) (xy 17.689138 -168.468294)
			(xy 22.86711 -168.468294) (xy 22.871181 -168.412672) (xy 22.883307 -168.358235) (xy 22.90323 -168.306144)
			(xy 22.930526 -168.257509) (xy 22.964612 -168.213366) (xy 23.004761 -168.174657) (xy 23.050119 -168.142206)
			(xy 23.099719 -168.116705) (xy 23.152503 -168.098698) (xy 23.207346 -168.088568) (xy 23.26308 -168.086531)
			(xy 23.318517 -168.092631) (xy 23.372474 -168.106737) (xy 23.423803 -168.128549) (xy 23.471409 -168.157603)
			(xy 23.514277 -168.193278) (xy 23.551494 -168.234815) (xy 23.582267 -168.281328) (xy 23.605939 -168.331825)
			(xy 23.622007 -168.385232) (xy 23.630127 -168.440408) (xy 23.630636 -168.468294) (xy 23.630127 -168.49618)
			(xy 23.622007 -168.551356) (xy 23.619717 -168.558968) (xy 41.84572 -168.558968) (xy 41.84572 -168.499032)
			(xy 41.853543 -168.43961) (xy 41.869056 -168.381717) (xy 41.891992 -168.326344) (xy 41.921959 -168.274438)
			(xy 41.958446 -168.226888) (xy 42.000826 -168.184508) (xy 42.048376 -168.148021) (xy 42.100282 -168.118054)
			(xy 42.155655 -168.095118) (xy 42.213548 -168.079605) (xy 42.27297 -168.071782) (xy 42.332906 -168.071782)
			(xy 42.392328 -168.079605) (xy 42.450221 -168.095118) (xy 42.505594 -168.118054) (xy 42.5575 -168.148021)
			(xy 42.60505 -168.184508) (xy 42.64743 -168.226888) (xy 42.683917 -168.274438) (xy 42.713884 -168.326344)
			(xy 42.73682 -168.381717) (xy 42.752333 -168.43961) (xy 42.760156 -168.499032) (xy 42.760646 -168.529)
			(xy 42.760156 -168.558968) (xy 47.053482 -168.558968) (xy 47.053482 -168.499032) (xy 47.061305 -168.43961)
			(xy 47.076818 -168.381717) (xy 47.099754 -168.326344) (xy 47.129721 -168.274438) (xy 47.166208 -168.226888)
			(xy 47.208588 -168.184508) (xy 47.256138 -168.148021) (xy 47.308044 -168.118054) (xy 47.363417 -168.095118)
			(xy 47.42131 -168.079605) (xy 47.480732 -168.071782) (xy 47.540668 -168.071782) (xy 47.60009 -168.079605)
			(xy 47.657983 -168.095118) (xy 47.713356 -168.118054) (xy 47.765262 -168.148021) (xy 47.812812 -168.184508)
			(xy 47.855192 -168.226888) (xy 47.891679 -168.274438) (xy 47.921646 -168.326344) (xy 47.944582 -168.381717)
			(xy 47.960095 -168.43961) (xy 47.967918 -168.499032) (xy 47.968408 -168.529) (xy 47.967918 -168.558968)
			(xy 47.960095 -168.61839) (xy 47.944582 -168.676283) (xy 47.921646 -168.731656) (xy 47.891679 -168.783562)
			(xy 47.855192 -168.831112) (xy 47.812812 -168.873492) (xy 47.765262 -168.909979) (xy 47.713356 -168.939946)
			(xy 47.657983 -168.962882) (xy 47.60009 -168.978395) (xy 47.540668 -168.986218) (xy 47.480732 -168.986218)
			(xy 47.42131 -168.978395) (xy 47.363417 -168.962882) (xy 47.308044 -168.939946) (xy 47.256138 -168.909979)
			(xy 47.208588 -168.873492) (xy 47.166208 -168.831112) (xy 47.129721 -168.783562) (xy 47.099754 -168.731656)
			(xy 47.076818 -168.676283) (xy 47.061305 -168.61839) (xy 47.053482 -168.558968) (xy 42.760156 -168.558968)
			(xy 42.752333 -168.61839) (xy 42.73682 -168.676283) (xy 42.713884 -168.731656) (xy 42.683917 -168.783562)
			(xy 42.64743 -168.831112) (xy 42.60505 -168.873492) (xy 42.5575 -168.909979) (xy 42.505594 -168.939946)
			(xy 42.450221 -168.962882) (xy 42.392328 -168.978395) (xy 42.332906 -168.986218) (xy 42.27297 -168.986218)
			(xy 42.213548 -168.978395) (xy 42.155655 -168.962882) (xy 42.100282 -168.939946) (xy 42.048376 -168.909979)
			(xy 42.000826 -168.873492) (xy 41.958446 -168.831112) (xy 41.921959 -168.783562) (xy 41.891992 -168.731656)
			(xy 41.869056 -168.676283) (xy 41.853543 -168.61839) (xy 41.84572 -168.558968) (xy 23.619717 -168.558968)
			(xy 23.605939 -168.604763) (xy 23.582267 -168.65526) (xy 23.551494 -168.701773) (xy 23.514277 -168.74331)
			(xy 23.471409 -168.778985) (xy 23.423803 -168.808039) (xy 23.372474 -168.829851) (xy 23.318517 -168.843957)
			(xy 23.26308 -168.850057) (xy 23.207346 -168.84802) (xy 23.152503 -168.83789) (xy 23.099719 -168.819883)
			(xy 23.050119 -168.794382) (xy 23.004761 -168.761931) (xy 22.964612 -168.723222) (xy 22.930526 -168.679079)
			(xy 22.90323 -168.630444) (xy 22.883307 -168.578353) (xy 22.871181 -168.523916) (xy 22.86711 -168.468294)
			(xy 17.689138 -168.468294) (xy 17.705882 -168.508717) (xy 17.721395 -168.56661) (xy 17.729218 -168.626032)
			(xy 17.729218 -168.685968) (xy 17.721395 -168.74539) (xy 17.705882 -168.803283) (xy 17.682946 -168.858656)
			(xy 17.652979 -168.910562) (xy 17.616492 -168.958112) (xy 17.574112 -169.000492) (xy 17.526562 -169.036979)
			(xy 17.474656 -169.066946) (xy 17.419283 -169.089882) (xy 17.36139 -169.105395) (xy 17.301968 -169.113218)
			(xy 17.272 -169.113708) (xy 17.271492 -169.113708) (xy 17.236444 -169.113073) (xy 17.167173 -169.102352)
			(xy 17.13357 -169.092372) (xy 17.118933 -169.088254) (xy 17.088542 -169.087972) (xy 17.059413 -169.096646)
			(xy 17.034127 -169.113508) (xy 17.014923 -169.137064) (xy 17.003501 -169.165229) (xy 17.000873 -169.195508)
			(xy 17.003522 -169.210482) (xy 17.007551 -169.230368) (xy 17.011876 -169.270712) (xy 17.012158 -169.291)
			(xy 17.011645 -169.318254) (xy 17.003887 -169.372206) (xy 16.98853 -169.424505) (xy 16.965887 -169.474086)
			(xy 16.936417 -169.51994) (xy 16.900722 -169.561133) (xy 16.859527 -169.596827) (xy 16.813672 -169.626295)
			(xy 16.76409 -169.648936) (xy 16.71179 -169.664291) (xy 16.657837 -169.672046) (xy 16.60333 -169.672043)
			(xy 16.549378 -169.664284) (xy 16.497079 -169.648925) (xy 16.447499 -169.626279) (xy 16.401646 -169.596807)
			(xy 16.360455 -169.56111) (xy 16.324763 -169.519914) (xy 16.295297 -169.474057) (xy 16.272658 -169.424474)
			(xy 16.257306 -169.372173) (xy 16.249553 -169.31822) (xy 12.382502 -169.31822) (xy 12.382424 -169.322436)
			(xy 12.373831 -169.384719) (xy 12.356793 -169.445239) (xy 12.33163 -169.502856) (xy 12.298817 -169.556487)
			(xy 12.25897 -169.60512) (xy 12.212842 -169.647841) (xy 12.161299 -169.683846) (xy 12.105313 -169.712455)
			(xy 12.045937 -169.733131) (xy 12.015216 -169.739818) (xy 12.00404 -169.742104) (xy 11.986006 -169.755312)
			(xy 11.943334 -169.833544) (xy 11.93846 -169.843601) (xy 11.936999 -169.865871) (xy 11.94054 -169.87647)
			(xy 11.951146 -169.904679) (xy 11.966062 -169.963071) (xy 11.973592 -170.022867) (xy 11.974068 -170.053)
			(xy 11.973578 -170.083132) (xy 11.966041 -170.142925) (xy 11.965461 -170.145198) (xy 17.068782 -170.145198)
			(xy 17.068782 -170.085262) (xy 17.076605 -170.02584) (xy 17.092118 -169.967947) (xy 17.115054 -169.912574)
			(xy 17.145021 -169.860668) (xy 17.181508 -169.813118) (xy 17.223888 -169.770738) (xy 17.271438 -169.734251)
			(xy 17.323344 -169.704284) (xy 17.378717 -169.681348) (xy 17.43661 -169.665835) (xy 17.496032 -169.658012)
			(xy 17.555968 -169.658012) (xy 17.61539 -169.665835) (xy 17.673283 -169.681348) (xy 17.728656 -169.704284)
			(xy 17.780562 -169.734251) (xy 17.828112 -169.770738) (xy 17.870492 -169.813118) (xy 17.906979 -169.860668)
			(xy 17.936946 -169.912574) (xy 17.959882 -169.967947) (xy 17.963614 -169.981876) (xy 30.886636 -169.981876)
			(xy 30.886636 -169.92194) (xy 30.894459 -169.862518) (xy 30.909972 -169.804625) (xy 30.932908 -169.749252)
			(xy 30.962875 -169.697346) (xy 30.999362 -169.649796) (xy 31.041742 -169.607416) (xy 31.089292 -169.570929)
			(xy 31.141198 -169.540962) (xy 31.196571 -169.518026) (xy 31.254464 -169.502513) (xy 31.313886 -169.49469)
			(xy 31.373822 -169.49469) (xy 31.433244 -169.502513) (xy 31.491137 -169.518026) (xy 31.54651 -169.540962)
			(xy 31.598416 -169.570929) (xy 31.645966 -169.607416) (xy 31.688346 -169.649796) (xy 31.724833 -169.697346)
			(xy 31.7548 -169.749252) (xy 31.777736 -169.804625) (xy 31.784259 -169.828968) (xy 44.113432 -169.828968)
			(xy 44.113432 -169.769032) (xy 44.121255 -169.70961) (xy 44.136768 -169.651717) (xy 44.159704 -169.596344)
			(xy 44.189671 -169.544438) (xy 44.226158 -169.496888) (xy 44.268538 -169.454508) (xy 44.316088 -169.418021)
			(xy 44.367994 -169.388054) (xy 44.423367 -169.365118) (xy 44.48126 -169.349605) (xy 44.540682 -169.341782)
			(xy 44.600618 -169.341782) (xy 44.66004 -169.349605) (xy 44.717933 -169.365118) (xy 44.773306 -169.388054)
			(xy 44.825212 -169.418021) (xy 44.872762 -169.454508) (xy 44.915142 -169.496888) (xy 44.951629 -169.544438)
			(xy 44.981596 -169.596344) (xy 45.004532 -169.651717) (xy 45.020045 -169.70961) (xy 45.027868 -169.769032)
			(xy 45.028358 -169.799) (xy 45.027868 -169.828968) (xy 45.020045 -169.88839) (xy 45.004532 -169.946283)
			(xy 44.981596 -170.001656) (xy 44.951629 -170.053562) (xy 44.915142 -170.101112) (xy 44.872762 -170.143492)
			(xy 44.825212 -170.179979) (xy 44.773306 -170.209946) (xy 44.717933 -170.232882) (xy 44.66004 -170.248395)
			(xy 44.600618 -170.256218) (xy 44.540682 -170.256218) (xy 44.48126 -170.248395) (xy 44.423367 -170.232882)
			(xy 44.367994 -170.209946) (xy 44.316088 -170.179979) (xy 44.268538 -170.143492) (xy 44.226158 -170.101112)
			(xy 44.189671 -170.053562) (xy 44.159704 -170.001656) (xy 44.136768 -169.946283) (xy 44.121255 -169.88839)
			(xy 44.113432 -169.828968) (xy 31.784259 -169.828968) (xy 31.793249 -169.862518) (xy 31.801072 -169.92194)
			(xy 31.801562 -169.951908) (xy 31.801072 -169.981876) (xy 31.793249 -170.041298) (xy 31.777736 -170.099191)
			(xy 31.7548 -170.154564) (xy 31.724833 -170.20647) (xy 31.688346 -170.25402) (xy 31.645966 -170.2964)
			(xy 31.598416 -170.332887) (xy 31.54651 -170.362854) (xy 31.491137 -170.38579) (xy 31.433244 -170.401303)
			(xy 31.373822 -170.409126) (xy 31.313886 -170.409126) (xy 31.254464 -170.401303) (xy 31.196571 -170.38579)
			(xy 31.141198 -170.362854) (xy 31.089292 -170.332887) (xy 31.041742 -170.2964) (xy 30.999362 -170.25402)
			(xy 30.962875 -170.20647) (xy 30.932908 -170.154564) (xy 30.909972 -170.099191) (xy 30.894459 -170.041298)
			(xy 30.886636 -169.981876) (xy 17.963614 -169.981876) (xy 17.975395 -170.02584) (xy 17.983218 -170.085262)
			(xy 17.983708 -170.11523) (xy 17.983218 -170.145198) (xy 17.975395 -170.20462) (xy 17.959882 -170.262513)
			(xy 17.936946 -170.317886) (xy 17.906979 -170.369792) (xy 17.870492 -170.417342) (xy 17.828112 -170.459722)
			(xy 17.780562 -170.496209) (xy 17.728656 -170.526176) (xy 17.673283 -170.549112) (xy 17.628918 -170.561)
			(xy 25.344118 -170.561) (xy 25.348189 -170.505378) (xy 25.360315 -170.450941) (xy 25.380238 -170.39885)
			(xy 25.407534 -170.350215) (xy 25.44162 -170.306072) (xy 25.481769 -170.267363) (xy 25.527127 -170.234912)
			(xy 25.576727 -170.209411) (xy 25.629511 -170.191404) (xy 25.684354 -170.181274) (xy 25.740088 -170.179237)
			(xy 25.795525 -170.185337) (xy 25.849482 -170.199443) (xy 25.900811 -170.221255) (xy 25.948417 -170.250309)
			(xy 25.991285 -170.285984) (xy 26.028502 -170.327521) (xy 26.059275 -170.374034) (xy 26.082947 -170.424531)
			(xy 26.099015 -170.477938) (xy 26.107135 -170.533114) (xy 26.107644 -170.561) (xy 26.107135 -170.588886)
			(xy 26.10081 -170.631862) (xy 39.941736 -170.631862) (xy 39.941736 -170.571926) (xy 39.949559 -170.512504)
			(xy 39.965072 -170.454611) (xy 39.988008 -170.399238) (xy 40.017975 -170.347332) (xy 40.054462 -170.299782)
			(xy 40.096842 -170.257402) (xy 40.144392 -170.220915) (xy 40.196298 -170.190948) (xy 40.251671 -170.168012)
			(xy 40.309564 -170.152499) (xy 40.368986 -170.144676) (xy 40.428922 -170.144676) (xy 40.488344 -170.152499)
			(xy 40.546237 -170.168012) (xy 40.60161 -170.190948) (xy 40.653516 -170.220915) (xy 40.701066 -170.257402)
			(xy 40.743446 -170.299782) (xy 40.779933 -170.347332) (xy 40.8099 -170.399238) (xy 40.832836 -170.454611)
			(xy 40.848349 -170.512504) (xy 40.856172 -170.571926) (xy 40.856662 -170.601894) (xy 40.856172 -170.631862)
			(xy 40.848349 -170.691284) (xy 40.832836 -170.749177) (xy 40.8099 -170.80455) (xy 40.779933 -170.856456)
			(xy 40.743446 -170.904006) (xy 40.701066 -170.946386) (xy 40.653516 -170.982873) (xy 40.60161 -171.01284)
			(xy 40.546237 -171.035776) (xy 40.488344 -171.051289) (xy 40.428922 -171.059112) (xy 40.368986 -171.059112)
			(xy 40.309564 -171.051289) (xy 40.251671 -171.035776) (xy 40.196298 -171.01284) (xy 40.144392 -170.982873)
			(xy 40.096842 -170.946386) (xy 40.054462 -170.904006) (xy 40.017975 -170.856456) (xy 39.988008 -170.80455)
			(xy 39.965072 -170.749177) (xy 39.949559 -170.691284) (xy 39.941736 -170.631862) (xy 26.10081 -170.631862)
			(xy 26.099015 -170.644062) (xy 26.082947 -170.697469) (xy 26.059275 -170.747966) (xy 26.028502 -170.794479)
			(xy 25.991285 -170.836016) (xy 25.948417 -170.871691) (xy 25.900811 -170.900745) (xy 25.849482 -170.922557)
			(xy 25.795525 -170.936663) (xy 25.740088 -170.942763) (xy 25.684354 -170.940726) (xy 25.629511 -170.930596)
			(xy 25.576727 -170.912589) (xy 25.527127 -170.887088) (xy 25.481769 -170.854637) (xy 25.44162 -170.815928)
			(xy 25.407534 -170.771785) (xy 25.380238 -170.72315) (xy 25.360315 -170.671059) (xy 25.348189 -170.616622)
			(xy 25.344118 -170.561) (xy 17.628918 -170.561) (xy 17.61539 -170.564625) (xy 17.555968 -170.572448)
			(xy 17.496032 -170.572448) (xy 17.43661 -170.564625) (xy 17.378717 -170.549112) (xy 17.323344 -170.526176)
			(xy 17.271438 -170.496209) (xy 17.223888 -170.459722) (xy 17.181508 -170.417342) (xy 17.145021 -170.369792)
			(xy 17.115054 -170.317886) (xy 17.092118 -170.262513) (xy 17.076605 -170.20462) (xy 17.068782 -170.145198)
			(xy 11.965461 -170.145198) (xy 11.951134 -170.201317) (xy 11.94054 -170.22953) (xy 11.937035 -170.240135)
			(xy 11.93848 -170.262397) (xy 11.943334 -170.272456) (xy 11.986006 -170.350688) (xy 12.00404 -170.363896)
			(xy 12.015216 -170.366182) (xy 12.045949 -170.372824) (xy 12.105327 -170.393509) (xy 12.161315 -170.422126)
			(xy 12.212861 -170.458136) (xy 12.258993 -170.500862) (xy 12.298843 -170.549499) (xy 12.305881 -170.561)
			(xy 16.254982 -170.561) (xy 16.259053 -170.505378) (xy 16.271179 -170.450941) (xy 16.291102 -170.39885)
			(xy 16.318398 -170.350215) (xy 16.352484 -170.306072) (xy 16.392633 -170.267363) (xy 16.437991 -170.234912)
			(xy 16.487591 -170.209411) (xy 16.540375 -170.191404) (xy 16.595218 -170.181274) (xy 16.650952 -170.179237)
			(xy 16.706389 -170.185337) (xy 16.760346 -170.199443) (xy 16.811675 -170.221255) (xy 16.859281 -170.250309)
			(xy 16.902149 -170.285984) (xy 16.939366 -170.327521) (xy 16.970139 -170.374034) (xy 16.993811 -170.424531)
			(xy 17.009879 -170.477938) (xy 17.017999 -170.533114) (xy 17.018508 -170.561) (xy 17.017999 -170.588886)
			(xy 17.009879 -170.644062) (xy 16.993811 -170.697469) (xy 16.970139 -170.747966) (xy 16.939366 -170.794479)
			(xy 16.902149 -170.836016) (xy 16.859281 -170.871691) (xy 16.811675 -170.900745) (xy 16.760346 -170.922557)
			(xy 16.706389 -170.936663) (xy 16.650952 -170.942763) (xy 16.595218 -170.940726) (xy 16.540375 -170.930596)
			(xy 16.487591 -170.912589) (xy 16.437991 -170.887088) (xy 16.392633 -170.854637) (xy 16.352484 -170.815928)
			(xy 16.318398 -170.771785) (xy 16.291102 -170.72315) (xy 16.271179 -170.671059) (xy 16.259053 -170.616622)
			(xy 16.254982 -170.561) (xy 12.305881 -170.561) (xy 12.331663 -170.603132) (xy 12.356834 -170.660752)
			(xy 12.373882 -170.721275) (xy 12.382488 -170.783561) (xy 12.383008 -170.815) (xy 12.382518 -170.844968)
			(xy 12.374695 -170.90439) (xy 12.359182 -170.962283) (xy 12.336246 -171.017656) (xy 12.306279 -171.069562)
			(xy 12.269792 -171.117112) (xy 12.227412 -171.159492) (xy 12.179862 -171.195979) (xy 12.127956 -171.225946)
			(xy 12.072583 -171.248882) (xy 12.01469 -171.264395) (xy 11.955268 -171.272218) (xy 11.895332 -171.272218)
			(xy 11.83591 -171.264395) (xy 11.778017 -171.248882) (xy 11.722644 -171.225946) (xy 11.670738 -171.195979)
			(xy 11.623188 -171.159492) (xy 11.580808 -171.117112) (xy 11.544321 -171.069562) (xy 11.514354 -171.017656)
			(xy 11.491418 -170.962283) (xy 11.475905 -170.90439) (xy 11.468082 -170.844968) (xy 11.467592 -170.815)
			(xy 11.467592 -170.814492) (xy 11.467961 -170.788858) (xy 11.473709 -170.737913) (xy 11.485119 -170.68793)
			(xy 11.493246 -170.663616) (xy 11.497056 -170.652948) (xy 11.49477 -170.630596) (xy 11.443462 -170.543982)
			(xy 11.425174 -170.531536) (xy 11.413744 -170.529758) (xy 11.384014 -170.524467) (xy 11.32606 -170.507504)
			(xy 11.270675 -170.483443) (xy 11.218724 -170.452662) (xy 11.171018 -170.415641) (xy 11.14933 -170.39463)
			(xy 11.051794 -170.297094) (xy 11.044391 -170.290258) (xy 11.025794 -170.282536) (xy 11.015726 -170.282108)
			(xy 10.839704 -170.282108) (xy 10.829682 -170.282523) (xy 10.811164 -170.290193) (xy 10.796991 -170.304367)
			(xy 10.789322 -170.322886) (xy 10.788904 -170.332908) (xy 10.788904 -172.313092) (xy 10.789326 -172.323113)
			(xy 10.796994 -172.341631) (xy 10.811166 -172.355804) (xy 10.829683 -172.363473) (xy 10.839704 -172.363892)
			(xy 11.10996 -172.363892) (xy 11.141594 -172.364389) (xy 11.204321 -172.372633) (xy 11.265435 -172.388998)
			(xy 11.323889 -172.413203) (xy 11.378681 -172.444834) (xy 11.428873 -172.48335) (xy 11.439055 -172.49322)
			(xy 16.249553 -172.49322) (xy 16.249558 -172.438713) (xy 16.25732 -172.384761) (xy 16.272681 -172.332464)
			(xy 16.295329 -172.282884) (xy 16.324803 -172.237033) (xy 16.360502 -172.195843) (xy 16.4017 -172.160153)
			(xy 16.447558 -172.130689) (xy 16.497142 -172.108052) (xy 16.549443 -172.092702) (xy 16.603396 -172.084952)
			(xy 16.63065 -172.084492) (xy 16.651848 -172.084791) (xy 16.693983 -172.089501) (xy 16.714724 -172.09389)
			(xy 16.729674 -172.096689) (xy 16.759983 -172.094394) (xy 16.788276 -172.083283) (xy 16.812048 -172.064339)
			(xy 16.829195 -172.039241) (xy 16.838198 -172.010208) (xy 16.838261 -171.979811) (xy 16.834358 -171.965112)
			(xy 16.825012 -171.932438) (xy 16.814934 -171.865232) (xy 16.814292 -171.831254) (xy 16.814292 -171.831)
			(xy 16.814782 -171.801032) (xy 16.822605 -171.74161) (xy 16.838118 -171.683717) (xy 16.861054 -171.628344)
			(xy 16.891021 -171.576438) (xy 16.927508 -171.528888) (xy 16.969888 -171.486508) (xy 17.017438 -171.450021)
			(xy 17.069344 -171.420054) (xy 17.124717 -171.397118) (xy 17.18261 -171.381605) (xy 17.242032 -171.373782)
			(xy 17.301968 -171.373782) (xy 17.36139 -171.381605) (xy 17.419283 -171.397118) (xy 17.474656 -171.420054)
			(xy 17.526562 -171.450021) (xy 17.574112 -171.486508) (xy 17.616492 -171.528888) (xy 17.652979 -171.576438)
			(xy 17.670605 -171.606968) (xy 25.275268 -171.606968) (xy 25.275268 -171.547032) (xy 25.283091 -171.48761)
			(xy 25.298604 -171.429717) (xy 25.32154 -171.374344) (xy 25.351507 -171.322438) (xy 25.387994 -171.274888)
			(xy 25.430374 -171.232508) (xy 25.477924 -171.196021) (xy 25.52983 -171.166054) (xy 25.585203 -171.143118)
			(xy 25.643096 -171.127605) (xy 25.702518 -171.119782) (xy 25.762454 -171.119782) (xy 25.821876 -171.127605)
			(xy 25.879769 -171.143118) (xy 25.935142 -171.166054) (xy 25.987048 -171.196021) (xy 26.034598 -171.232508)
			(xy 26.076978 -171.274888) (xy 26.088945 -171.290484) (xy 42.133248 -171.290484) (xy 42.133248 -171.230548)
			(xy 42.141071 -171.171126) (xy 42.156584 -171.113233) (xy 42.17952 -171.05786) (xy 42.209487 -171.005954)
			(xy 42.245974 -170.958404) (xy 42.288354 -170.916024) (xy 42.335904 -170.879537) (xy 42.38781 -170.84957)
			(xy 42.443183 -170.826634) (xy 42.501076 -170.811121) (xy 42.560498 -170.803298) (xy 42.620434 -170.803298)
			(xy 42.679856 -170.811121) (xy 42.694332 -170.815) (xy 44.194982 -170.815) (xy 44.199053 -170.759378)
			(xy 44.211179 -170.704941) (xy 44.231102 -170.65285) (xy 44.258398 -170.604215) (xy 44.292484 -170.560072)
			(xy 44.332633 -170.521363) (xy 44.377991 -170.488912) (xy 44.427591 -170.463411) (xy 44.480375 -170.445404)
			(xy 44.535218 -170.435274) (xy 44.590952 -170.433237) (xy 44.646389 -170.439337) (xy 44.700346 -170.453443)
			(xy 44.751675 -170.475255) (xy 44.799281 -170.504309) (xy 44.842149 -170.539984) (xy 44.879366 -170.581521)
			(xy 44.910139 -170.628034) (xy 44.933811 -170.678531) (xy 44.949879 -170.731938) (xy 44.957999 -170.787114)
			(xy 44.958508 -170.815) (xy 44.957999 -170.842886) (xy 44.949879 -170.898062) (xy 44.933811 -170.951469)
			(xy 44.910139 -171.001966) (xy 44.879366 -171.048479) (xy 44.842149 -171.090016) (xy 44.799281 -171.125691)
			(xy 44.751675 -171.154745) (xy 44.700346 -171.176557) (xy 44.646389 -171.190663) (xy 44.590952 -171.196763)
			(xy 44.535218 -171.194726) (xy 44.480375 -171.184596) (xy 44.427591 -171.166589) (xy 44.377991 -171.141088)
			(xy 44.332633 -171.108637) (xy 44.292484 -171.069928) (xy 44.258398 -171.025785) (xy 44.231102 -170.97715)
			(xy 44.211179 -170.925059) (xy 44.199053 -170.870622) (xy 44.194982 -170.815) (xy 42.694332 -170.815)
			(xy 42.737749 -170.826634) (xy 42.793122 -170.84957) (xy 42.845028 -170.879537) (xy 42.892578 -170.916024)
			(xy 42.934958 -170.958404) (xy 42.971445 -171.005954) (xy 43.001412 -171.05786) (xy 43.024348 -171.113233)
			(xy 43.039861 -171.171126) (xy 43.047684 -171.230548) (xy 43.048174 -171.260516) (xy 43.047684 -171.290484)
			(xy 43.039861 -171.349906) (xy 43.024348 -171.407799) (xy 43.001412 -171.463172) (xy 42.971445 -171.515078)
			(xy 42.934958 -171.562628) (xy 42.892578 -171.605008) (xy 42.845028 -171.641495) (xy 42.793122 -171.671462)
			(xy 42.737749 -171.694398) (xy 42.679856 -171.709911) (xy 42.620434 -171.717734) (xy 42.560498 -171.717734)
			(xy 42.501076 -171.709911) (xy 42.443183 -171.694398) (xy 42.38781 -171.671462) (xy 42.335904 -171.641495)
			(xy 42.288354 -171.605008) (xy 42.245974 -171.562628) (xy 42.209487 -171.515078) (xy 42.17952 -171.463172)
			(xy 42.156584 -171.407799) (xy 42.141071 -171.349906) (xy 42.133248 -171.290484) (xy 26.088945 -171.290484)
			(xy 26.113465 -171.322438) (xy 26.143432 -171.374344) (xy 26.166368 -171.429717) (xy 26.181881 -171.48761)
			(xy 26.189704 -171.547032) (xy 26.190194 -171.577) (xy 26.189704 -171.606968) (xy 26.181881 -171.66639)
			(xy 26.166368 -171.724283) (xy 26.143432 -171.779656) (xy 26.113465 -171.831562) (xy 26.076978 -171.879112)
			(xy 26.034598 -171.921492) (xy 25.987048 -171.957979) (xy 25.935142 -171.987946) (xy 25.879769 -172.010882)
			(xy 25.821876 -172.026395) (xy 25.762454 -172.034218) (xy 25.702518 -172.034218) (xy 25.643096 -172.026395)
			(xy 25.585203 -172.010882) (xy 25.52983 -171.987946) (xy 25.477924 -171.957979) (xy 25.430374 -171.921492)
			(xy 25.387994 -171.879112) (xy 25.351507 -171.831562) (xy 25.32154 -171.779656) (xy 25.298604 -171.724283)
			(xy 25.283091 -171.66639) (xy 25.275268 -171.606968) (xy 17.670605 -171.606968) (xy 17.682946 -171.628344)
			(xy 17.705882 -171.683717) (xy 17.721395 -171.74161) (xy 17.729218 -171.801032) (xy 17.729218 -171.860968)
			(xy 17.721395 -171.92039) (xy 17.705882 -171.978283) (xy 17.682946 -172.033656) (xy 17.652979 -172.085562)
			(xy 17.616492 -172.133112) (xy 17.574112 -172.175492) (xy 17.526562 -172.211979) (xy 17.474656 -172.241946)
			(xy 17.419283 -172.264882) (xy 17.36139 -172.280395) (xy 17.301968 -172.288218) (xy 17.272 -172.288708)
			(xy 17.271492 -172.288708) (xy 17.236444 -172.288073) (xy 17.167173 -172.277352) (xy 17.13357 -172.267372)
			(xy 17.118933 -172.263254) (xy 17.088542 -172.262972) (xy 17.059413 -172.271646) (xy 17.034127 -172.288508)
			(xy 17.014923 -172.312064) (xy 17.003501 -172.340229) (xy 17.000873 -172.370508) (xy 17.003522 -172.385482)
			(xy 17.007551 -172.405368) (xy 17.011876 -172.445712) (xy 17.012158 -172.466) (xy 17.011645 -172.493254)
			(xy 17.003887 -172.547206) (xy 16.98853 -172.599505) (xy 16.965887 -172.649086) (xy 16.936417 -172.69494)
			(xy 16.900722 -172.736133) (xy 16.884755 -172.749968) (xy 21.386782 -172.749968) (xy 21.386782 -172.690032)
			(xy 21.394605 -172.63061) (xy 21.410118 -172.572717) (xy 21.433054 -172.517344) (xy 21.463021 -172.465438)
			(xy 21.499508 -172.417888) (xy 21.541888 -172.375508) (xy 21.589438 -172.339021) (xy 21.641344 -172.309054)
			(xy 21.696717 -172.286118) (xy 21.75461 -172.270605) (xy 21.814032 -172.262782) (xy 21.873968 -172.262782)
			(xy 21.93339 -172.270605) (xy 21.991283 -172.286118) (xy 22.046656 -172.309054) (xy 22.098562 -172.339021)
			(xy 22.146112 -172.375508) (xy 22.188492 -172.417888) (xy 22.224979 -172.465438) (xy 22.254946 -172.517344)
			(xy 22.277882 -172.572717) (xy 22.283317 -172.593) (xy 44.627292 -172.593) (xy 44.627867 -172.562402)
			(xy 44.63601 -172.50175) (xy 44.652163 -172.442725) (xy 44.676038 -172.386379) (xy 44.707211 -172.333717)
			(xy 44.745123 -172.28568) (xy 44.789099 -172.243124) (xy 44.838355 -172.206808) (xy 44.892011 -172.177381)
			(xy 44.94911 -172.155368) (xy 45.008634 -172.14116) (xy 45.039026 -172.137578) (xy 45.052795 -172.135767)
			(xy 45.078644 -172.125636) (xy 45.100809 -172.108918) (xy 45.117652 -172.086848) (xy 45.127929 -172.061058)
			(xy 45.13088 -172.033452) (xy 45.126287 -172.006071) (xy 45.120814 -171.993306) (xy 45.109347 -171.967803)
			(xy 45.093189 -171.914272) (xy 45.085 -171.858958) (xy 45.084492 -171.831) (xy 45.084978 -171.803749)
			(xy 45.092734 -171.749801) (xy 45.108089 -171.697506) (xy 45.130731 -171.647929) (xy 45.160197 -171.602079)
			(xy 45.195888 -171.560888) (xy 45.237079 -171.525197) (xy 45.282929 -171.495731) (xy 45.332506 -171.473089)
			(xy 45.384801 -171.457734) (xy 45.438749 -171.449978) (xy 45.493251 -171.449978) (xy 45.547199 -171.457734)
			(xy 45.599494 -171.473089) (xy 45.649071 -171.495731) (xy 45.694921 -171.525197) (xy 45.732291 -171.557577)
			(xy 46.100734 -171.557577) (xy 46.100734 -171.444023) (xy 46.108655 -171.330747) (xy 46.124458 -171.218299)
			(xy 46.148067 -171.107228) (xy 46.179367 -170.998073) (xy 46.218204 -170.891368) (xy 46.26439 -170.787633)
			(xy 46.3177 -170.687371) (xy 46.377874 -170.591073) (xy 46.444619 -170.499207) (xy 46.517609 -170.41222)
			(xy 46.59649 -170.330537) (xy 46.680876 -170.254555) (xy 46.770357 -170.184645) (xy 46.864497 -170.121147)
			(xy 46.962837 -170.06437) (xy 47.064897 -170.014592) (xy 47.170182 -169.972054) (xy 47.278177 -169.936964)
			(xy 47.388357 -169.909493) (xy 47.500185 -169.889775) (xy 47.613116 -169.877905) (xy 47.7266 -169.873943)
			(xy 47.840084 -169.877905) (xy 47.953015 -169.889775) (xy 48.064843 -169.909493) (xy 48.175023 -169.936964)
			(xy 48.283018 -169.972054) (xy 48.388303 -170.014592) (xy 48.490363 -170.06437) (xy 48.588703 -170.121147)
			(xy 48.682843 -170.184645) (xy 48.772324 -170.254555) (xy 48.85671 -170.330537) (xy 48.935591 -170.41222)
			(xy 49.008581 -170.499207) (xy 49.075326 -170.591073) (xy 49.1355 -170.687371) (xy 49.18881 -170.787633)
			(xy 49.234996 -170.891368) (xy 49.273833 -170.998073) (xy 49.305133 -171.107228) (xy 49.328742 -171.218299)
			(xy 49.344545 -171.330747) (xy 49.352466 -171.444023) (xy 49.352962 -171.5008) (xy 49.352466 -171.557577)
			(xy 49.344545 -171.670853) (xy 49.328742 -171.783301) (xy 49.305133 -171.894372) (xy 49.273833 -172.003527)
			(xy 49.234996 -172.110232) (xy 49.18881 -172.213967) (xy 49.1355 -172.314229) (xy 49.075326 -172.410527)
			(xy 49.008581 -172.502393) (xy 48.935591 -172.58938) (xy 48.85671 -172.671063) (xy 48.772324 -172.747045)
			(xy 48.682843 -172.816955) (xy 48.588703 -172.880453) (xy 48.490363 -172.93723) (xy 48.388303 -172.987008)
			(xy 48.283018 -173.029546) (xy 48.175023 -173.064636) (xy 48.064843 -173.092107) (xy 47.953015 -173.111825)
			(xy 47.840084 -173.123695) (xy 47.7266 -173.127658) (xy 47.613116 -173.123695) (xy 47.500185 -173.111825)
			(xy 47.388357 -173.092107) (xy 47.278177 -173.064636) (xy 47.170182 -173.029546) (xy 47.064897 -172.987008)
			(xy 46.962837 -172.93723) (xy 46.864497 -172.880453) (xy 46.770357 -172.816955) (xy 46.680876 -172.747045)
			(xy 46.59649 -172.671063) (xy 46.517609 -172.58938) (xy 46.444619 -172.502393) (xy 46.377874 -172.410527)
			(xy 46.3177 -172.314229) (xy 46.26439 -172.213967) (xy 46.218204 -172.110232) (xy 46.179367 -172.003527)
			(xy 46.148067 -171.894372) (xy 46.124458 -171.783301) (xy 46.108655 -171.670853) (xy 46.100734 -171.557577)
			(xy 45.732291 -171.557577) (xy 45.736112 -171.560888) (xy 45.771803 -171.602079) (xy 45.801269 -171.647929)
			(xy 45.823911 -171.697506) (xy 45.839266 -171.749801) (xy 45.847022 -171.803749) (xy 45.847508 -171.831)
			(xy 45.84699 -171.85999) (xy 45.838217 -171.917302) (xy 45.820874 -171.972627) (xy 45.795359 -172.024691)
			(xy 45.76226 -172.072295) (xy 45.72234 -172.114343) (xy 45.676517 -172.149866) (xy 45.625847 -172.178048)
			(xy 45.571497 -172.198238) (xy 45.543216 -172.204634) (xy 45.529764 -172.20799) (xy 45.505171 -172.220757)
			(xy 45.484914 -172.239663) (xy 45.470483 -172.263318) (xy 45.46294 -172.289981) (xy 45.462841 -172.317691)
			(xy 45.470191 -172.344407) (xy 45.476922 -172.356526) (xy 45.492515 -172.383409) (xy 45.517121 -172.440478)
			(xy 45.533781 -172.50035) (xy 45.542188 -172.561926) (xy 45.542708 -172.593) (xy 45.542218 -172.622968)
			(xy 45.534395 -172.68239) (xy 45.518882 -172.740283) (xy 45.495946 -172.795656) (xy 45.465979 -172.847562)
			(xy 45.429492 -172.895112) (xy 45.387112 -172.937492) (xy 45.339562 -172.973979) (xy 45.287656 -173.003946)
			(xy 45.232283 -173.026882) (xy 45.17439 -173.042395) (xy 45.114968 -173.050218) (xy 45.055032 -173.050218)
			(xy 44.99561 -173.042395) (xy 44.937717 -173.026882) (xy 44.882344 -173.003946) (xy 44.830438 -172.973979)
			(xy 44.782888 -172.937492) (xy 44.740508 -172.895112) (xy 44.704021 -172.847562) (xy 44.674054 -172.795656)
			(xy 44.651118 -172.740283) (xy 44.635605 -172.68239) (xy 44.627782 -172.622968) (xy 44.627292 -172.593)
			(xy 22.283317 -172.593) (xy 22.293395 -172.63061) (xy 22.301218 -172.690032) (xy 22.301708 -172.72)
			(xy 22.301218 -172.749968) (xy 22.293395 -172.80939) (xy 22.277882 -172.867283) (xy 22.254946 -172.922656)
			(xy 22.224979 -172.974562) (xy 22.188492 -173.022112) (xy 22.146112 -173.064492) (xy 22.098562 -173.100979)
			(xy 22.046656 -173.130946) (xy 21.991283 -173.153882) (xy 21.93339 -173.169395) (xy 21.873968 -173.177218)
			(xy 21.814032 -173.177218) (xy 21.75461 -173.169395) (xy 21.696717 -173.153882) (xy 21.641344 -173.130946)
			(xy 21.589438 -173.100979) (xy 21.541888 -173.064492) (xy 21.499508 -173.022112) (xy 21.463021 -172.974562)
			(xy 21.433054 -172.922656) (xy 21.410118 -172.867283) (xy 21.394605 -172.80939) (xy 21.386782 -172.749968)
			(xy 16.884755 -172.749968) (xy 16.859527 -172.771827) (xy 16.813672 -172.801295) (xy 16.76409 -172.823936)
			(xy 16.71179 -172.839291) (xy 16.657837 -172.847046) (xy 16.60333 -172.847043) (xy 16.549378 -172.839284)
			(xy 16.497079 -172.823925) (xy 16.447499 -172.801279) (xy 16.401646 -172.771807) (xy 16.360455 -172.73611)
			(xy 16.324763 -172.694914) (xy 16.295297 -172.649057) (xy 16.272658 -172.599474) (xy 16.257306 -172.547173)
			(xy 16.249553 -172.49322) (xy 11.439055 -172.49322) (xy 11.45159 -172.50537) (xy 11.83259 -172.88637)
			(xy 11.854598 -172.909095) (xy 11.893101 -172.959293) (xy 11.924724 -173.014086) (xy 11.948927 -173.072537)
			(xy 11.965296 -173.133646) (xy 11.969958 -173.169068) (xy 12.99894 -173.169068) (xy 12.99894 -173.109132)
			(xy 13.006763 -173.04971) (xy 13.022276 -172.991817) (xy 13.045212 -172.936444) (xy 13.075179 -172.884538)
			(xy 13.111666 -172.836988) (xy 13.154046 -172.794608) (xy 13.201596 -172.758121) (xy 13.253502 -172.728154)
			(xy 13.308875 -172.705218) (xy 13.366768 -172.689705) (xy 13.42619 -172.681882) (xy 13.486126 -172.681882)
			(xy 13.545548 -172.689705) (xy 13.603441 -172.705218) (xy 13.658814 -172.728154) (xy 13.71072 -172.758121)
			(xy 13.75827 -172.794608) (xy 13.80065 -172.836988) (xy 13.837137 -172.884538) (xy 13.867104 -172.936444)
			(xy 13.89004 -172.991817) (xy 13.905553 -173.04971) (xy 13.913376 -173.109132) (xy 13.913866 -173.1391)
			(xy 13.913376 -173.169068) (xy 13.905553 -173.22849) (xy 13.89004 -173.286383) (xy 13.878979 -173.313086)
			(xy 42.12385 -173.313086) (xy 42.12385 -173.25315) (xy 42.131673 -173.193728) (xy 42.147186 -173.135835)
			(xy 42.170122 -173.080462) (xy 42.200089 -173.028556) (xy 42.236576 -172.981006) (xy 42.278956 -172.938626)
			(xy 42.326506 -172.902139) (xy 42.378412 -172.872172) (xy 42.433785 -172.849236) (xy 42.491678 -172.833723)
			(xy 42.5511 -172.8259) (xy 42.611036 -172.8259) (xy 42.670458 -172.833723) (xy 42.728351 -172.849236)
			(xy 42.783724 -172.872172) (xy 42.83563 -172.902139) (xy 42.88318 -172.938626) (xy 42.92556 -172.981006)
			(xy 42.962047 -173.028556) (xy 42.992014 -173.080462) (xy 43.01495 -173.135835) (xy 43.030463 -173.193728)
			(xy 43.038286 -173.25315) (xy 43.038776 -173.283118) (xy 43.038286 -173.313086) (xy 43.030463 -173.372508)
			(xy 43.01495 -173.430401) (xy 42.992014 -173.485774) (xy 42.962047 -173.53768) (xy 42.92556 -173.58523)
			(xy 42.88318 -173.62761) (xy 42.83563 -173.664097) (xy 42.783724 -173.694064) (xy 42.728351 -173.717)
			(xy 42.670458 -173.732513) (xy 42.611036 -173.740336) (xy 42.5511 -173.740336) (xy 42.491678 -173.732513)
			(xy 42.433785 -173.717) (xy 42.378412 -173.694064) (xy 42.326506 -173.664097) (xy 42.278956 -173.62761)
			(xy 42.236576 -173.58523) (xy 42.200089 -173.53768) (xy 42.170122 -173.485774) (xy 42.147186 -173.430401)
			(xy 42.131673 -173.372508) (xy 42.12385 -173.313086) (xy 13.878979 -173.313086) (xy 13.867104 -173.341756)
			(xy 13.837137 -173.393662) (xy 13.80065 -173.441212) (xy 13.75827 -173.483592) (xy 13.71072 -173.520079)
			(xy 13.658814 -173.550046) (xy 13.603441 -173.572982) (xy 13.545548 -173.588495) (xy 13.486126 -173.596318)
			(xy 13.42619 -173.596318) (xy 13.366768 -173.588495) (xy 13.308875 -173.572982) (xy 13.253502 -173.550046)
			(xy 13.201596 -173.520079) (xy 13.154046 -173.483592) (xy 13.111666 -173.441212) (xy 13.075179 -173.393662)
			(xy 13.045212 -173.341756) (xy 13.022276 -173.286383) (xy 13.006763 -173.22849) (xy 12.99894 -173.169068)
			(xy 11.969958 -173.169068) (xy 11.973551 -173.196368) (xy 11.974068 -173.228) (xy 11.973613 -173.259634)
			(xy 11.965354 -173.32236) (xy 11.948979 -173.383472) (xy 11.924766 -173.441923) (xy 11.893131 -173.496713)
			(xy 11.854614 -173.546905) (xy 11.809875 -173.59164) (xy 11.75968 -173.630153) (xy 11.704887 -173.661784)
			(xy 11.646434 -173.685992) (xy 11.585321 -173.702362) (xy 11.522594 -173.710615) (xy 11.49096 -173.711108)
			(xy 11.459327 -173.710598) (xy 11.3966 -173.702357) (xy 11.335486 -173.685995) (xy 11.277032 -173.661792)
			(xy 11.22224 -173.630163) (xy 11.172047 -173.591649) (xy 11.14933 -173.56963) (xy 10.924794 -173.345094)
			(xy 10.917391 -173.338258) (xy 10.898794 -173.330536) (xy 10.888726 -173.330108) (xy 10.839704 -173.330108)
			(xy 10.829682 -173.330523) (xy 10.811164 -173.338193) (xy 10.796991 -173.352367) (xy 10.789322 -173.370886)
			(xy 10.788904 -173.380908) (xy 10.788904 -173.863) (xy 10.788392 -173.89462) (xy 10.78014 -173.95732)
			(xy 10.771386 -173.99) (xy 16.248632 -173.99) (xy 16.252703 -173.934378) (xy 16.264829 -173.879941)
			(xy 16.284752 -173.82785) (xy 16.312048 -173.779215) (xy 16.346134 -173.735072) (xy 16.386283 -173.696363)
			(xy 16.431641 -173.663912) (xy 16.481241 -173.638411) (xy 16.534025 -173.620404) (xy 16.588868 -173.610274)
			(xy 16.644602 -173.608237) (xy 16.700039 -173.614337) (xy 16.753996 -173.628443) (xy 16.805325 -173.650255)
			(xy 16.852931 -173.679309) (xy 16.895799 -173.714984) (xy 16.933016 -173.756521) (xy 16.963789 -173.803034)
			(xy 16.987461 -173.853531) (xy 16.99031 -173.863) (xy 45.464982 -173.863) (xy 45.469053 -173.807378)
			(xy 45.481179 -173.752941) (xy 45.501102 -173.70085) (xy 45.528398 -173.652215) (xy 45.562484 -173.608072)
			(xy 45.602633 -173.569363) (xy 45.647991 -173.536912) (xy 45.697591 -173.511411) (xy 45.750375 -173.493404)
			(xy 45.805218 -173.483274) (xy 45.860952 -173.481237) (xy 45.916389 -173.487337) (xy 45.970346 -173.501443)
			(xy 46.021675 -173.523255) (xy 46.069281 -173.552309) (xy 46.112149 -173.587984) (xy 46.149366 -173.629521)
			(xy 46.180139 -173.676034) (xy 46.203811 -173.726531) (xy 46.219879 -173.779938) (xy 46.227999 -173.835114)
			(xy 46.228508 -173.863) (xy 46.227999 -173.890886) (xy 46.219879 -173.946062) (xy 46.203811 -173.999469)
			(xy 46.180139 -174.049966) (xy 46.149366 -174.096479) (xy 46.112149 -174.138016) (xy 46.069281 -174.173691)
			(xy 46.021675 -174.202745) (xy 45.970346 -174.224557) (xy 45.916389 -174.238663) (xy 45.860952 -174.244763)
			(xy 45.805218 -174.242726) (xy 45.750375 -174.232596) (xy 45.697591 -174.214589) (xy 45.647991 -174.189088)
			(xy 45.602633 -174.156637) (xy 45.562484 -174.117928) (xy 45.528398 -174.073785) (xy 45.501102 -174.02515)
			(xy 45.481179 -173.973059) (xy 45.469053 -173.918622) (xy 45.464982 -173.863) (xy 16.99031 -173.863)
			(xy 17.003529 -173.906938) (xy 17.011649 -173.962114) (xy 17.012158 -173.99) (xy 17.011649 -174.017886)
			(xy 17.003529 -174.073062) (xy 16.987461 -174.126469) (xy 16.963789 -174.176966) (xy 16.933016 -174.223479)
			(xy 16.895799 -174.265016) (xy 16.852931 -174.300691) (xy 16.805325 -174.329745) (xy 16.753996 -174.351557)
			(xy 16.700039 -174.365663) (xy 16.644602 -174.371763) (xy 16.588868 -174.369726) (xy 16.534025 -174.359596)
			(xy 16.481241 -174.341589) (xy 16.431641 -174.316088) (xy 16.386283 -174.283637) (xy 16.346134 -174.244928)
			(xy 16.312048 -174.200785) (xy 16.284752 -174.15215) (xy 16.264829 -174.100059) (xy 16.252703 -174.045622)
			(xy 16.248632 -173.99) (xy 10.771386 -173.99) (xy 10.763777 -174.018407) (xy 10.739584 -174.076837)
			(xy 10.707973 -174.13161) (xy 10.669485 -174.181791) (xy 10.624779 -174.22652) (xy 10.574619 -174.265034)
			(xy 10.519862 -174.296673) (xy 10.461444 -174.320897) (xy 10.400366 -174.337291) (xy 10.33767 -174.345575)
			(xy 10.30605 -174.346108) (xy 10.273444 -174.345596) (xy 10.208825 -174.336818) (xy 10.145974 -174.319427)
			(xy 10.086034 -174.29374) (xy 10.030094 -174.260223) (xy 9.97917 -174.219487) (xy 9.956292 -174.196248)
			(xy 9.941306 -174.1805) (xy 9.933178 -174.1805) (xy 9.90346 -174.150782) (xy 9.90346 -174.144686)
			(xy 9.903268 -174.137728) (xy 9.899529 -174.124325) (xy 9.896094 -174.11827) (xy 9.89584 -174.11827)
			(xy 9.89584 -174.118016) (xy 9.878651 -174.089226) (xy 9.851508 -174.027913) (xy 9.833104 -173.963436)
			(xy 9.82379 -173.897034) (xy 9.823196 -173.863508) (xy 2.896108 -173.863508) (xy 2.896108 -175.289968)
			(xy 3.333732 -175.289968) (xy 3.333732 -175.230032) (xy 3.341555 -175.17061) (xy 3.357068 -175.112717)
			(xy 3.380004 -175.057344) (xy 3.409971 -175.005438) (xy 3.446458 -174.957888) (xy 3.488838 -174.915508)
			(xy 3.536388 -174.879021) (xy 3.588294 -174.849054) (xy 3.643667 -174.826118) (xy 3.70156 -174.810605)
			(xy 3.760982 -174.802782) (xy 3.820918 -174.802782) (xy 3.88034 -174.810605) (xy 3.938233 -174.826118)
			(xy 3.993606 -174.849054) (xy 4.045512 -174.879021) (xy 4.093062 -174.915508) (xy 4.135442 -174.957888)
			(xy 4.171929 -175.005438) (xy 4.185889 -175.029618) (xy 14.649432 -175.029618) (xy 14.649432 -174.969682)
			(xy 14.657255 -174.91026) (xy 14.672768 -174.852367) (xy 14.695704 -174.796994) (xy 14.725671 -174.745088)
			(xy 14.762158 -174.697538) (xy 14.804538 -174.655158) (xy 14.852088 -174.618671) (xy 14.903994 -174.588704)
			(xy 14.959367 -174.565768) (xy 15.01726 -174.550255) (xy 15.076682 -174.542432) (xy 15.136618 -174.542432)
			(xy 15.19604 -174.550255) (xy 15.253933 -174.565768) (xy 15.309306 -174.588704) (xy 15.361212 -174.618671)
			(xy 15.408762 -174.655158) (xy 15.451142 -174.697538) (xy 15.487629 -174.745088) (xy 15.508921 -174.781968)
			(xy 21.386782 -174.781968) (xy 21.386782 -174.722032) (xy 21.394605 -174.66261) (xy 21.410118 -174.604717)
			(xy 21.433054 -174.549344) (xy 21.463021 -174.497438) (xy 21.499508 -174.449888) (xy 21.541888 -174.407508)
			(xy 21.589438 -174.371021) (xy 21.641344 -174.341054) (xy 21.696717 -174.318118) (xy 21.75461 -174.302605)
			(xy 21.814032 -174.294782) (xy 21.873968 -174.294782) (xy 21.93339 -174.302605) (xy 21.991283 -174.318118)
			(xy 22.046656 -174.341054) (xy 22.098562 -174.371021) (xy 22.146112 -174.407508) (xy 22.188492 -174.449888)
			(xy 22.224979 -174.497438) (xy 22.254946 -174.549344) (xy 22.277882 -174.604717) (xy 22.293395 -174.66261)
			(xy 22.301218 -174.722032) (xy 22.301708 -174.752) (xy 22.301218 -174.781968) (xy 22.293395 -174.84139)
			(xy 22.277882 -174.899283) (xy 22.254946 -174.954656) (xy 22.224979 -175.006562) (xy 22.188492 -175.054112)
			(xy 22.146112 -175.096492) (xy 22.098562 -175.132979) (xy 22.046656 -175.162946) (xy 21.991283 -175.185882)
			(xy 21.93339 -175.201395) (xy 21.873968 -175.209218) (xy 21.814032 -175.209218) (xy 21.75461 -175.201395)
			(xy 21.696717 -175.185882) (xy 21.641344 -175.162946) (xy 21.589438 -175.132979) (xy 21.541888 -175.096492)
			(xy 21.499508 -175.054112) (xy 21.463021 -175.006562) (xy 21.433054 -174.954656) (xy 21.410118 -174.899283)
			(xy 21.394605 -174.84139) (xy 21.386782 -174.781968) (xy 15.508921 -174.781968) (xy 15.517596 -174.796994)
			(xy 15.540532 -174.852367) (xy 15.556045 -174.91026) (xy 15.563868 -174.969682) (xy 15.564358 -174.99965)
			(xy 15.563868 -175.029618) (xy 15.556045 -175.08904) (xy 15.540532 -175.146933) (xy 15.517596 -175.202306)
			(xy 15.487629 -175.254212) (xy 15.479682 -175.264568) (xy 29.387782 -175.264568) (xy 29.387782 -175.204632)
			(xy 29.395605 -175.14521) (xy 29.411118 -175.087317) (xy 29.434054 -175.031944) (xy 29.464021 -174.980038)
			(xy 29.500508 -174.932488) (xy 29.542888 -174.890108) (xy 29.590438 -174.853621) (xy 29.642344 -174.823654)
			(xy 29.697717 -174.800718) (xy 29.75561 -174.785205) (xy 29.815032 -174.777382) (xy 29.874968 -174.777382)
			(xy 29.93439 -174.785205) (xy 29.992283 -174.800718) (xy 30.047656 -174.823654) (xy 30.099562 -174.853621)
			(xy 30.147112 -174.890108) (xy 30.189492 -174.932488) (xy 30.225979 -174.980038) (xy 30.245805 -175.014378)
			(xy 31.593772 -175.014378) (xy 31.593772 -174.954442) (xy 31.601595 -174.89502) (xy 31.617108 -174.837127)
			(xy 31.640044 -174.781754) (xy 31.670011 -174.729848) (xy 31.706498 -174.682298) (xy 31.748878 -174.639918)
			(xy 31.796428 -174.603431) (xy 31.848334 -174.573464) (xy 31.903707 -174.550528) (xy 31.9616 -174.535015)
			(xy 32.021022 -174.527192) (xy 32.080958 -174.527192) (xy 32.14038 -174.535015) (xy 32.198273 -174.550528)
			(xy 32.253646 -174.573464) (xy 32.305552 -174.603431) (xy 32.353102 -174.639918) (xy 32.395482 -174.682298)
			(xy 32.431969 -174.729848) (xy 32.444758 -174.752) (xy 45.972982 -174.752) (xy 45.977053 -174.696378)
			(xy 45.989179 -174.641941) (xy 46.009102 -174.58985) (xy 46.036398 -174.541215) (xy 46.070484 -174.497072)
			(xy 46.110633 -174.458363) (xy 46.155991 -174.425912) (xy 46.205591 -174.400411) (xy 46.258375 -174.382404)
			(xy 46.313218 -174.372274) (xy 46.368952 -174.370237) (xy 46.424389 -174.376337) (xy 46.478346 -174.390443)
			(xy 46.529675 -174.412255) (xy 46.577281 -174.441309) (xy 46.620149 -174.476984) (xy 46.657366 -174.518521)
			(xy 46.688139 -174.565034) (xy 46.711811 -174.615531) (xy 46.727879 -174.668938) (xy 46.735999 -174.724114)
			(xy 46.736508 -174.752) (xy 46.735999 -174.779886) (xy 46.727879 -174.835062) (xy 46.711811 -174.888469)
			(xy 46.688139 -174.938966) (xy 46.657366 -174.985479) (xy 46.620149 -175.027016) (xy 46.577281 -175.062691)
			(xy 46.529675 -175.091745) (xy 46.478346 -175.113557) (xy 46.424389 -175.127663) (xy 46.368952 -175.133763)
			(xy 46.313218 -175.131726) (xy 46.258375 -175.121596) (xy 46.205591 -175.103589) (xy 46.155991 -175.078088)
			(xy 46.110633 -175.045637) (xy 46.070484 -175.006928) (xy 46.036398 -174.962785) (xy 46.009102 -174.91415)
			(xy 45.989179 -174.862059) (xy 45.977053 -174.807622) (xy 45.972982 -174.752) (xy 32.444758 -174.752)
			(xy 32.461936 -174.781754) (xy 32.484872 -174.837127) (xy 32.500385 -174.89502) (xy 32.508208 -174.954442)
			(xy 32.508698 -174.98441) (xy 32.508208 -175.014378) (xy 32.500385 -175.0738) (xy 32.484872 -175.131693)
			(xy 32.461936 -175.187066) (xy 32.431969 -175.238972) (xy 32.395482 -175.286522) (xy 32.353102 -175.328902)
			(xy 32.305552 -175.365389) (xy 32.253646 -175.395356) (xy 32.198273 -175.418292) (xy 32.14038 -175.433805)
			(xy 32.080958 -175.441628) (xy 32.021022 -175.441628) (xy 31.9616 -175.433805) (xy 31.903707 -175.418292)
			(xy 31.848334 -175.395356) (xy 31.796428 -175.365389) (xy 31.748878 -175.328902) (xy 31.706498 -175.286522)
			(xy 31.670011 -175.238972) (xy 31.640044 -175.187066) (xy 31.617108 -175.131693) (xy 31.601595 -175.0738)
			(xy 31.593772 -175.014378) (xy 30.245805 -175.014378) (xy 30.255946 -175.031944) (xy 30.278882 -175.087317)
			(xy 30.294395 -175.14521) (xy 30.302218 -175.204632) (xy 30.302708 -175.2346) (xy 30.302218 -175.264568)
			(xy 30.294395 -175.32399) (xy 30.278882 -175.381883) (xy 30.255946 -175.437256) (xy 30.225979 -175.489162)
			(xy 30.189492 -175.536712) (xy 30.147112 -175.579092) (xy 30.099562 -175.615579) (xy 30.047656 -175.645546)
			(xy 29.992283 -175.668482) (xy 29.93439 -175.683995) (xy 29.874968 -175.691818) (xy 29.815032 -175.691818)
			(xy 29.75561 -175.683995) (xy 29.697717 -175.668482) (xy 29.642344 -175.645546) (xy 29.590438 -175.615579)
			(xy 29.542888 -175.579092) (xy 29.500508 -175.536712) (xy 29.464021 -175.489162) (xy 29.434054 -175.437256)
			(xy 29.411118 -175.381883) (xy 29.395605 -175.32399) (xy 29.387782 -175.264568) (xy 15.479682 -175.264568)
			(xy 15.451142 -175.301762) (xy 15.408762 -175.344142) (xy 15.361212 -175.380629) (xy 15.309306 -175.410596)
			(xy 15.253933 -175.433532) (xy 15.19604 -175.449045) (xy 15.136618 -175.456868) (xy 15.076682 -175.456868)
			(xy 15.01726 -175.449045) (xy 14.959367 -175.433532) (xy 14.903994 -175.410596) (xy 14.852088 -175.380629)
			(xy 14.804538 -175.344142) (xy 14.762158 -175.301762) (xy 14.725671 -175.254212) (xy 14.695704 -175.202306)
			(xy 14.672768 -175.146933) (xy 14.657255 -175.08904) (xy 14.649432 -175.029618) (xy 4.185889 -175.029618)
			(xy 4.201896 -175.057344) (xy 4.224832 -175.112717) (xy 4.240345 -175.17061) (xy 4.248168 -175.230032)
			(xy 4.248658 -175.26) (xy 4.248168 -175.289968) (xy 4.240345 -175.34939) (xy 4.224832 -175.407283)
			(xy 4.201896 -175.462656) (xy 4.171929 -175.514562) (xy 4.135442 -175.562112) (xy 4.093062 -175.604492)
			(xy 4.045512 -175.640979) (xy 3.993606 -175.670946) (xy 3.938233 -175.693882) (xy 3.88034 -175.709395)
			(xy 3.820918 -175.717218) (xy 3.760982 -175.717218) (xy 3.70156 -175.709395) (xy 3.643667 -175.693882)
			(xy 3.588294 -175.670946) (xy 3.536388 -175.640979) (xy 3.488838 -175.604492) (xy 3.446458 -175.562112)
			(xy 3.409971 -175.514562) (xy 3.380004 -175.462656) (xy 3.357068 -175.407283) (xy 3.341555 -175.34939)
			(xy 3.333732 -175.289968) (xy 2.896108 -175.289968) (xy 2.896108 -175.797968) (xy 33.470832 -175.797968)
			(xy 33.470832 -175.738032) (xy 33.478655 -175.67861) (xy 33.494168 -175.620717) (xy 33.517104 -175.565344)
			(xy 33.547071 -175.513438) (xy 33.583558 -175.465888) (xy 33.625938 -175.423508) (xy 33.673488 -175.387021)
			(xy 33.725394 -175.357054) (xy 33.780767 -175.334118) (xy 33.83866 -175.318605) (xy 33.898082 -175.310782)
			(xy 33.958018 -175.310782) (xy 34.01744 -175.318605) (xy 34.075333 -175.334118) (xy 34.130706 -175.357054)
			(xy 34.182612 -175.387021) (xy 34.230162 -175.423508) (xy 34.272542 -175.465888) (xy 34.309029 -175.513438)
			(xy 34.338996 -175.565344) (xy 34.361932 -175.620717) (xy 34.377445 -175.67861) (xy 34.385268 -175.738032)
			(xy 34.385758 -175.768) (xy 34.385268 -175.797968) (xy 34.384031 -175.807366) (xy 39.41113 -175.807366)
			(xy 39.41113 -175.74743) (xy 39.418953 -175.688008) (xy 39.434466 -175.630115) (xy 39.457402 -175.574742)
			(xy 39.487369 -175.522836) (xy 39.523856 -175.475286) (xy 39.566236 -175.432906) (xy 39.613786 -175.396419)
			(xy 39.665692 -175.366452) (xy 39.721065 -175.343516) (xy 39.778958 -175.328003) (xy 39.83838 -175.32018)
			(xy 39.898316 -175.32018) (xy 39.957738 -175.328003) (xy 40.015631 -175.343516) (xy 40.071004 -175.366452)
			(xy 40.12291 -175.396419) (xy 40.17046 -175.432906) (xy 40.21284 -175.475286) (xy 40.249327 -175.522836)
			(xy 40.279294 -175.574742) (xy 40.30223 -175.630115) (xy 40.317743 -175.688008) (xy 40.325566 -175.74743)
			(xy 40.326056 -175.777398) (xy 40.325566 -175.807366) (xy 40.317743 -175.866788) (xy 40.30223 -175.924681)
			(xy 40.302111 -175.924968) (xy 41.976022 -175.924968) (xy 41.976022 -175.865032) (xy 41.983845 -175.80561)
			(xy 41.999358 -175.747717) (xy 42.022294 -175.692344) (xy 42.052261 -175.640438) (xy 42.088748 -175.592888)
			(xy 42.131128 -175.550508) (xy 42.178678 -175.514021) (xy 42.230584 -175.484054) (xy 42.285957 -175.461118)
			(xy 42.34385 -175.445605) (xy 42.403272 -175.437782) (xy 42.463208 -175.437782) (xy 42.52263 -175.445605)
			(xy 42.580523 -175.461118) (xy 42.635896 -175.484054) (xy 42.687802 -175.514021) (xy 42.735352 -175.550508)
			(xy 42.777732 -175.592888) (xy 42.814219 -175.640438) (xy 42.844186 -175.692344) (xy 42.867122 -175.747717)
			(xy 42.882635 -175.80561) (xy 42.890458 -175.865032) (xy 42.890948 -175.895) (xy 42.890458 -175.924968)
			(xy 42.882635 -175.98439) (xy 42.867122 -176.042283) (xy 42.844186 -176.097656) (xy 42.814219 -176.149562)
			(xy 42.777732 -176.197112) (xy 42.735352 -176.239492) (xy 42.687802 -176.275979) (xy 42.635896 -176.305946)
			(xy 42.635843 -176.305968) (xy 45.008782 -176.305968) (xy 45.008782 -176.246032) (xy 45.016605 -176.18661)
			(xy 45.032118 -176.128717) (xy 45.055054 -176.073344) (xy 45.085021 -176.021438) (xy 45.121508 -175.973888)
			(xy 45.163888 -175.931508) (xy 45.211438 -175.895021) (xy 45.263344 -175.865054) (xy 45.318717 -175.842118)
			(xy 45.37661 -175.826605) (xy 45.436032 -175.818782) (xy 45.495968 -175.818782) (xy 45.55539 -175.826605)
			(xy 45.613283 -175.842118) (xy 45.668656 -175.865054) (xy 45.720562 -175.895021) (xy 45.768112 -175.931508)
			(xy 45.810492 -175.973888) (xy 45.846979 -176.021438) (xy 45.876946 -176.073344) (xy 45.899882 -176.128717)
			(xy 45.915395 -176.18661) (xy 45.923218 -176.246032) (xy 45.923708 -176.276) (xy 45.923137 -176.307661)
			(xy 45.914345 -176.370372) (xy 45.906182 -176.400968) (xy 45.903664 -176.412075) (xy 45.907499 -176.434497)
			(xy 45.913548 -176.444148) (xy 45.966126 -176.518316) (xy 45.986192 -176.529492) (xy 45.997622 -176.530254)
			(xy 46.026325 -176.532618) (xy 46.082616 -176.54477) (xy 46.136441 -176.565246) (xy 46.186576 -176.593582)
			(xy 46.231881 -176.629132) (xy 46.271326 -176.67109) (xy 46.304016 -176.718501) (xy 46.329206 -176.770287)
			(xy 46.346325 -176.825272) (xy 46.354982 -176.882206) (xy 46.355508 -176.911) (xy 46.355022 -176.938251)
			(xy 46.347266 -176.992199) (xy 46.331911 -177.044494) (xy 46.309269 -177.094071) (xy 46.279803 -177.139921)
			(xy 46.244112 -177.181112) (xy 46.202921 -177.216803) (xy 46.157071 -177.246269) (xy 46.107494 -177.268911)
			(xy 46.055199 -177.284266) (xy 46.001251 -177.292022) (xy 45.946749 -177.292022) (xy 45.892801 -177.284266)
			(xy 45.840506 -177.268911) (xy 45.790929 -177.246269) (xy 45.745079 -177.216803) (xy 45.703888 -177.181112)
			(xy 45.668197 -177.139921) (xy 45.638731 -177.094071) (xy 45.616089 -177.044494) (xy 45.600734 -176.992199)
			(xy 45.592978 -176.938251) (xy 45.592492 -176.911) (xy 45.592648 -176.895821) (xy 45.595063 -176.865559)
			(xy 45.597318 -176.850548) (xy 45.597318 -176.850294) (xy 45.598447 -176.838987) (xy 45.592 -176.817232)
			(xy 45.584872 -176.808384) (xy 45.524166 -176.741074) (xy 45.50283 -176.732438) (xy 45.491654 -176.732946)
			(xy 45.4914 -176.732946) (xy 45.466 -176.733708) (xy 45.436032 -176.733218) (xy 45.37661 -176.725395)
			(xy 45.318717 -176.709882) (xy 45.263344 -176.686946) (xy 45.211438 -176.656979) (xy 45.163888 -176.620492)
			(xy 45.121508 -176.578112) (xy 45.085021 -176.530562) (xy 45.055054 -176.478656) (xy 45.032118 -176.423283)
			(xy 45.016605 -176.36539) (xy 45.008782 -176.305968) (xy 42.635843 -176.305968) (xy 42.580523 -176.328882)
			(xy 42.52263 -176.344395) (xy 42.463208 -176.352218) (xy 42.403272 -176.352218) (xy 42.34385 -176.344395)
			(xy 42.285957 -176.328882) (xy 42.230584 -176.305946) (xy 42.178678 -176.275979) (xy 42.131128 -176.239492)
			(xy 42.088748 -176.197112) (xy 42.052261 -176.149562) (xy 42.022294 -176.097656) (xy 41.999358 -176.042283)
			(xy 41.983845 -175.98439) (xy 41.976022 -175.924968) (xy 40.302111 -175.924968) (xy 40.279294 -175.980054)
			(xy 40.249327 -176.03196) (xy 40.21284 -176.07951) (xy 40.17046 -176.12189) (xy 40.12291 -176.158377)
			(xy 40.071004 -176.188344) (xy 40.015631 -176.21128) (xy 39.957738 -176.226793) (xy 39.898316 -176.234616)
			(xy 39.83838 -176.234616) (xy 39.778958 -176.226793) (xy 39.721065 -176.21128) (xy 39.665692 -176.188344)
			(xy 39.613786 -176.158377) (xy 39.566236 -176.12189) (xy 39.523856 -176.07951) (xy 39.487369 -176.03196)
			(xy 39.457402 -175.980054) (xy 39.434466 -175.924681) (xy 39.418953 -175.866788) (xy 39.41113 -175.807366)
			(xy 34.384031 -175.807366) (xy 34.377445 -175.85739) (xy 34.361932 -175.915283) (xy 34.338996 -175.970656)
			(xy 34.309029 -176.022562) (xy 34.272542 -176.070112) (xy 34.230162 -176.112492) (xy 34.182612 -176.148979)
			(xy 34.130706 -176.178946) (xy 34.075333 -176.201882) (xy 34.01744 -176.217395) (xy 33.958018 -176.225218)
			(xy 33.898082 -176.225218) (xy 33.83866 -176.217395) (xy 33.780767 -176.201882) (xy 33.725394 -176.178946)
			(xy 33.673488 -176.148979) (xy 33.625938 -176.112492) (xy 33.583558 -176.070112) (xy 33.547071 -176.022562)
			(xy 33.517104 -175.970656) (xy 33.494168 -175.915283) (xy 33.478655 -175.85739) (xy 33.470832 -175.797968)
			(xy 2.896108 -175.797968) (xy 2.896108 -176.38395) (xy 8.126982 -176.38395) (xy 8.131053 -176.328328)
			(xy 8.143179 -176.273891) (xy 8.163102 -176.2218) (xy 8.190398 -176.173165) (xy 8.224484 -176.129022)
			(xy 8.264633 -176.090313) (xy 8.309991 -176.057862) (xy 8.359591 -176.032361) (xy 8.412375 -176.014354)
			(xy 8.467218 -176.004224) (xy 8.522952 -176.002187) (xy 8.578389 -176.008287) (xy 8.632346 -176.022393)
			(xy 8.683675 -176.044205) (xy 8.731281 -176.073259) (xy 8.774149 -176.108934) (xy 8.811366 -176.150471)
			(xy 8.842139 -176.196984) (xy 8.865811 -176.247481) (xy 8.881879 -176.300888) (xy 8.889999 -176.356064)
			(xy 8.890508 -176.38395) (xy 8.889999 -176.411836) (xy 8.881879 -176.467012) (xy 8.865811 -176.520419)
			(xy 8.842139 -176.570916) (xy 8.811366 -176.617429) (xy 8.774149 -176.658966) (xy 8.731281 -176.694641)
			(xy 8.683675 -176.723695) (xy 8.632346 -176.745507) (xy 8.578389 -176.759613) (xy 8.522952 -176.765713)
			(xy 8.467218 -176.763676) (xy 8.412375 -176.753546) (xy 8.359591 -176.735539) (xy 8.309991 -176.710038)
			(xy 8.264633 -176.677587) (xy 8.224484 -176.638878) (xy 8.190398 -176.594735) (xy 8.163102 -176.5461)
			(xy 8.143179 -176.494009) (xy 8.131053 -176.439572) (xy 8.126982 -176.38395) (xy 2.896108 -176.38395)
			(xy 2.896108 -177.063904) (xy 14.782782 -177.063904) (xy 14.782782 -177.003968) (xy 14.790605 -176.944546)
			(xy 14.806118 -176.886653) (xy 14.829054 -176.83128) (xy 14.859021 -176.779374) (xy 14.895508 -176.731824)
			(xy 14.937888 -176.689444) (xy 14.985438 -176.652957) (xy 15.037344 -176.62299) (xy 15.092717 -176.600054)
			(xy 15.15061 -176.584541) (xy 15.210032 -176.576718) (xy 15.269968 -176.576718) (xy 15.32939 -176.584541)
			(xy 15.387283 -176.600054) (xy 15.442656 -176.62299) (xy 15.494562 -176.652957) (xy 15.542112 -176.689444)
			(xy 15.584492 -176.731824) (xy 15.620979 -176.779374) (xy 15.62365 -176.784) (xy 21.461982 -176.784)
			(xy 21.466053 -176.728378) (xy 21.478179 -176.673941) (xy 21.498102 -176.62185) (xy 21.525398 -176.573215)
			(xy 21.559484 -176.529072) (xy 21.599633 -176.490363) (xy 21.644991 -176.457912) (xy 21.694591 -176.432411)
			(xy 21.747375 -176.414404) (xy 21.802218 -176.404274) (xy 21.857952 -176.402237) (xy 21.913389 -176.408337)
			(xy 21.967346 -176.422443) (xy 22.018675 -176.444255) (xy 22.066281 -176.473309) (xy 22.109149 -176.508984)
			(xy 22.146366 -176.550521) (xy 22.177139 -176.597034) (xy 22.200811 -176.647531) (xy 22.216879 -176.700938)
			(xy 22.224999 -176.756114) (xy 22.225508 -176.784) (xy 29.589982 -176.784) (xy 29.594053 -176.728378)
			(xy 29.606179 -176.673941) (xy 29.626102 -176.62185) (xy 29.653398 -176.573215) (xy 29.687484 -176.529072)
			(xy 29.727633 -176.490363) (xy 29.772991 -176.457912) (xy 29.822591 -176.432411) (xy 29.875375 -176.414404)
			(xy 29.930218 -176.404274) (xy 29.985952 -176.402237) (xy 30.041389 -176.408337) (xy 30.095346 -176.422443)
			(xy 30.120114 -176.432968) (xy 32.054782 -176.432968) (xy 32.054782 -176.373032) (xy 32.062605 -176.31361)
			(xy 32.078118 -176.255717) (xy 32.101054 -176.200344) (xy 32.131021 -176.148438) (xy 32.167508 -176.100888)
			(xy 32.209888 -176.058508) (xy 32.257438 -176.022021) (xy 32.309344 -175.992054) (xy 32.364717 -175.969118)
			(xy 32.42261 -175.953605) (xy 32.482032 -175.945782) (xy 32.541968 -175.945782) (xy 32.60139 -175.953605)
			(xy 32.659283 -175.969118) (xy 32.714656 -175.992054) (xy 32.766562 -176.022021) (xy 32.814112 -176.058508)
			(xy 32.856492 -176.100888) (xy 32.892979 -176.148438) (xy 32.922946 -176.200344) (xy 32.945882 -176.255717)
			(xy 32.961395 -176.31361) (xy 32.969218 -176.373032) (xy 32.969708 -176.403) (xy 32.969218 -176.432968)
			(xy 32.961395 -176.49239) (xy 32.945882 -176.550283) (xy 32.922946 -176.605656) (xy 32.892979 -176.657562)
			(xy 32.856492 -176.705112) (xy 32.814112 -176.747492) (xy 32.766562 -176.783979) (xy 32.714656 -176.813946)
			(xy 32.659283 -176.836882) (xy 32.60139 -176.852395) (xy 32.541968 -176.860218) (xy 32.482032 -176.860218)
			(xy 32.42261 -176.852395) (xy 32.364717 -176.836882) (xy 32.309344 -176.813946) (xy 32.257438 -176.783979)
			(xy 32.209888 -176.747492) (xy 32.167508 -176.705112) (xy 32.131021 -176.657562) (xy 32.101054 -176.605656)
			(xy 32.078118 -176.550283) (xy 32.062605 -176.49239) (xy 32.054782 -176.432968) (xy 30.120114 -176.432968)
			(xy 30.146675 -176.444255) (xy 30.194281 -176.473309) (xy 30.237149 -176.508984) (xy 30.274366 -176.550521)
			(xy 30.305139 -176.597034) (xy 30.328811 -176.647531) (xy 30.344879 -176.700938) (xy 30.352999 -176.756114)
			(xy 30.353508 -176.784) (xy 30.352999 -176.811886) (xy 30.344879 -176.867062) (xy 30.328811 -176.920469)
			(xy 30.305139 -176.970966) (xy 30.274366 -177.017479) (xy 30.237149 -177.059016) (xy 30.194281 -177.094691)
			(xy 30.146675 -177.123745) (xy 30.095346 -177.145557) (xy 30.041389 -177.159663) (xy 29.985952 -177.165763)
			(xy 29.930218 -177.163726) (xy 29.875375 -177.153596) (xy 29.822591 -177.135589) (xy 29.772991 -177.110088)
			(xy 29.727633 -177.077637) (xy 29.687484 -177.038928) (xy 29.653398 -176.994785) (xy 29.626102 -176.94615)
			(xy 29.606179 -176.894059) (xy 29.594053 -176.839622) (xy 29.589982 -176.784) (xy 22.225508 -176.784)
			(xy 22.224999 -176.811886) (xy 22.216879 -176.867062) (xy 22.200811 -176.920469) (xy 22.177139 -176.970966)
			(xy 22.146366 -177.017479) (xy 22.109149 -177.059016) (xy 22.066281 -177.094691) (xy 22.018675 -177.123745)
			(xy 21.967346 -177.145557) (xy 21.913389 -177.159663) (xy 21.857952 -177.165763) (xy 21.802218 -177.163726)
			(xy 21.747375 -177.153596) (xy 21.694591 -177.135589) (xy 21.644991 -177.110088) (xy 21.599633 -177.077637)
			(xy 21.559484 -177.038928) (xy 21.525398 -176.994785) (xy 21.498102 -176.94615) (xy 21.478179 -176.894059)
			(xy 21.466053 -176.839622) (xy 21.461982 -176.784) (xy 15.62365 -176.784) (xy 15.650946 -176.83128)
			(xy 15.673882 -176.886653) (xy 15.689395 -176.944546) (xy 15.697218 -177.003968) (xy 15.697708 -177.033936)
			(xy 15.697218 -177.063904) (xy 15.689395 -177.123326) (xy 15.673882 -177.181219) (xy 15.650946 -177.236592)
			(xy 15.620979 -177.288498) (xy 15.584492 -177.336048) (xy 15.542112 -177.378428) (xy 15.494562 -177.414915)
			(xy 15.442656 -177.444882) (xy 15.387283 -177.467818) (xy 15.32939 -177.483331) (xy 15.269968 -177.491154)
			(xy 15.210032 -177.491154) (xy 15.15061 -177.483331) (xy 15.092717 -177.467818) (xy 15.037344 -177.444882)
			(xy 14.985438 -177.414915) (xy 14.937888 -177.378428) (xy 14.895508 -177.336048) (xy 14.859021 -177.288498)
			(xy 14.829054 -177.236592) (xy 14.806118 -177.181219) (xy 14.790605 -177.123326) (xy 14.782782 -177.063904)
			(xy 2.896108 -177.063904) (xy 2.896108 -178.054) (xy 47.350932 -178.054) (xy 47.355003 -177.998378)
			(xy 47.367129 -177.943941) (xy 47.387052 -177.89185) (xy 47.414348 -177.843215) (xy 47.448434 -177.799072)
			(xy 47.488583 -177.760363) (xy 47.533941 -177.727912) (xy 47.583541 -177.702411) (xy 47.636325 -177.684404)
			(xy 47.691168 -177.674274) (xy 47.746902 -177.672237) (xy 47.802339 -177.678337) (xy 47.856296 -177.692443)
			(xy 47.907625 -177.714255) (xy 47.955231 -177.743309) (xy 47.998099 -177.778984) (xy 48.035316 -177.820521)
			(xy 48.066089 -177.867034) (xy 48.089761 -177.917531) (xy 48.105829 -177.970938) (xy 48.113949 -178.026114)
			(xy 48.114458 -178.054) (xy 48.113949 -178.081886) (xy 48.105829 -178.137062) (xy 48.089761 -178.190469)
			(xy 48.066089 -178.240966) (xy 48.035316 -178.287479) (xy 47.998099 -178.329016) (xy 47.955231 -178.364691)
			(xy 47.907625 -178.393745) (xy 47.856296 -178.415557) (xy 47.802339 -178.429663) (xy 47.746902 -178.435763)
			(xy 47.691168 -178.433726) (xy 47.636325 -178.423596) (xy 47.583541 -178.405589) (xy 47.533941 -178.380088)
			(xy 47.488583 -178.347637) (xy 47.448434 -178.308928) (xy 47.414348 -178.264785) (xy 47.387052 -178.21615)
			(xy 47.367129 -178.164059) (xy 47.355003 -178.109622) (xy 47.350932 -178.054) (xy 2.896108 -178.054)
			(xy 2.896108 -181.002251) (xy 3.028928 -181.002251) (xy 3.028928 -180.947749) (xy 3.036684 -180.893801)
			(xy 3.052039 -180.841506) (xy 3.074681 -180.791929) (xy 3.104147 -180.746079) (xy 3.139838 -180.704888)
			(xy 3.181029 -180.669197) (xy 3.226879 -180.639731) (xy 3.276456 -180.617089) (xy 3.328751 -180.601734)
			(xy 3.382699 -180.593978) (xy 3.40995 -180.593492) (xy 3.410712 -180.593492) (xy 3.436041 -180.593919)
			(xy 3.486247 -180.600673) (xy 3.510788 -180.606954) (xy 3.524332 -180.610253) (xy 3.552199 -180.610124)
			(xy 3.578989 -180.602455) (xy 3.602702 -180.587818) (xy 3.621566 -180.567306) (xy 3.63417 -180.542453)
			(xy 3.639574 -180.515115) (xy 3.637374 -180.487336) (xy 3.632962 -180.474112) (xy 3.622102 -180.442437)
			(xy 3.610342 -180.376524) (xy 3.609594 -180.343048) (xy 3.609594 -180.342286) (xy 3.610082 -180.315035)
			(xy 3.617839 -180.261088) (xy 3.633194 -180.208794) (xy 3.655836 -180.159218) (xy 3.685302 -180.113368)
			(xy 3.720993 -180.072179) (xy 3.762183 -180.036488) (xy 3.808033 -180.007023) (xy 3.85761 -179.984382)
			(xy 3.909904 -179.969028) (xy 3.963851 -179.961272) (xy 4.018353 -179.961272) (xy 4.0723 -179.969029)
			(xy 4.124594 -179.984384) (xy 4.17417 -180.007025) (xy 4.22002 -180.036491) (xy 4.261209 -180.072182)
			(xy 4.2969 -180.113372) (xy 4.326366 -180.159222) (xy 4.349007 -180.208798) (xy 4.364362 -180.261092)
			(xy 4.372118 -180.315039) (xy 4.372118 -180.369541) (xy 4.364362 -180.423488) (xy 4.349007 -180.475782)
			(xy 4.326366 -180.525358) (xy 4.2969 -180.571208) (xy 4.261209 -180.612398) (xy 4.231437 -180.638196)
			(xy 4.70535 -180.638196) (xy 4.705901 -180.606547) (xy 4.714634 -180.543855) (xy 4.731921 -180.482964)
			(xy 4.757431 -180.425034) (xy 4.790677 -180.371171) (xy 4.831027 -180.322401) (xy 4.87771 -180.279655)
			(xy 4.90347 -180.26126) (xy 4.912614 -180.25491) (xy 4.924044 -180.23586) (xy 4.933188 -180.147722)
			(xy 4.933739 -180.136641) (xy 4.926511 -180.115695) (xy 4.919218 -180.107336) (xy 4.899514 -180.085926)
			(xy 4.866193 -180.038227) (xy 4.84049 -179.986028) (xy 4.822999 -179.930534) (xy 4.814125 -179.87303)
			(xy 4.813554 -179.843938) (xy 4.81404 -179.816687) (xy 4.821796 -179.762739) (xy 4.837151 -179.710444)
			(xy 4.859793 -179.660867) (xy 4.889259 -179.615017) (xy 4.92495 -179.573826) (xy 4.966141 -179.538135)
			(xy 5.011991 -179.508669) (xy 5.061568 -179.486027) (xy 5.113863 -179.470672) (xy 5.167811 -179.462916)
			(xy 5.222313 -179.462916) (xy 5.276261 -179.470672) (xy 5.311326 -179.480968) (xy 31.673782 -179.480968)
			(xy 31.673782 -179.421032) (xy 31.681605 -179.36161) (xy 31.697118 -179.303717) (xy 31.720054 -179.248344)
			(xy 31.750021 -179.196438) (xy 31.786508 -179.148888) (xy 31.828888 -179.106508) (xy 31.876438 -179.070021)
			(xy 31.928344 -179.040054) (xy 31.983717 -179.017118) (xy 32.04161 -179.001605) (xy 32.101032 -178.993782)
			(xy 32.160968 -178.993782) (xy 32.22039 -179.001605) (xy 32.278283 -179.017118) (xy 32.333656 -179.040054)
			(xy 32.385562 -179.070021) (xy 32.433112 -179.106508) (xy 32.475492 -179.148888) (xy 32.511979 -179.196438)
			(xy 32.541946 -179.248344) (xy 32.564882 -179.303717) (xy 32.578347 -179.353968) (xy 48.685432 -179.353968)
			(xy 48.685432 -179.294032) (xy 48.693255 -179.23461) (xy 48.708768 -179.176717) (xy 48.731704 -179.121344)
			(xy 48.761671 -179.069438) (xy 48.798158 -179.021888) (xy 48.840538 -178.979508) (xy 48.888088 -178.943021)
			(xy 48.939994 -178.913054) (xy 48.995367 -178.890118) (xy 49.05326 -178.874605) (xy 49.112682 -178.866782)
			(xy 49.172618 -178.866782) (xy 49.23204 -178.874605) (xy 49.289933 -178.890118) (xy 49.345306 -178.913054)
			(xy 49.397212 -178.943021) (xy 49.444762 -178.979508) (xy 49.487142 -179.021888) (xy 49.523629 -179.069438)
			(xy 49.553596 -179.121344) (xy 49.576532 -179.176717) (xy 49.592045 -179.23461) (xy 49.599868 -179.294032)
			(xy 49.600358 -179.324) (xy 49.599868 -179.353968) (xy 49.592045 -179.41339) (xy 49.576532 -179.471283)
			(xy 49.553596 -179.526656) (xy 49.523629 -179.578562) (xy 49.487142 -179.626112) (xy 49.444762 -179.668492)
			(xy 49.397212 -179.704979) (xy 49.345306 -179.734946) (xy 49.289933 -179.757882) (xy 49.23204 -179.773395)
			(xy 49.172618 -179.781218) (xy 49.112682 -179.781218) (xy 49.05326 -179.773395) (xy 48.995367 -179.757882)
			(xy 48.939994 -179.734946) (xy 48.888088 -179.704979) (xy 48.840538 -179.668492) (xy 48.798158 -179.626112)
			(xy 48.761671 -179.578562) (xy 48.731704 -179.526656) (xy 48.708768 -179.471283) (xy 48.693255 -179.41339)
			(xy 48.685432 -179.353968) (xy 32.578347 -179.353968) (xy 32.580395 -179.36161) (xy 32.588218 -179.421032)
			(xy 32.588708 -179.451) (xy 32.588218 -179.480968) (xy 32.580395 -179.54039) (xy 32.564882 -179.598283)
			(xy 32.541946 -179.653656) (xy 32.511979 -179.705562) (xy 32.475492 -179.753112) (xy 32.433112 -179.795492)
			(xy 32.385562 -179.831979) (xy 32.333656 -179.861946) (xy 32.278283 -179.884882) (xy 32.22039 -179.900395)
			(xy 32.160968 -179.908218) (xy 32.101032 -179.908218) (xy 32.04161 -179.900395) (xy 31.983717 -179.884882)
			(xy 31.928344 -179.861946) (xy 31.876438 -179.831979) (xy 31.828888 -179.795492) (xy 31.786508 -179.753112)
			(xy 31.750021 -179.705562) (xy 31.720054 -179.653656) (xy 31.697118 -179.598283) (xy 31.681605 -179.54039)
			(xy 31.673782 -179.480968) (xy 5.311326 -179.480968) (xy 5.328556 -179.486027) (xy 5.378133 -179.508669)
			(xy 5.423983 -179.538135) (xy 5.465174 -179.573826) (xy 5.500865 -179.615017) (xy 5.530331 -179.660867)
			(xy 5.552973 -179.710444) (xy 5.568328 -179.762739) (xy 5.576084 -179.816687) (xy 5.57657 -179.843938)
			(xy 5.576128 -179.870764) (xy 5.568611 -179.923885) (xy 5.553731 -179.975432) (xy 5.531782 -180.024387)
			(xy 5.511381 -180.056786) (xy 43.088542 -180.056786) (xy 43.088542 -179.99685) (xy 43.096365 -179.937428)
			(xy 43.111878 -179.879535) (xy 43.134814 -179.824162) (xy 43.164781 -179.772256) (xy 43.201268 -179.724706)
			(xy 43.243648 -179.682326) (xy 43.291198 -179.645839) (xy 43.343104 -179.615872) (xy 43.398477 -179.592936)
			(xy 43.45637 -179.577423) (xy 43.515792 -179.5696) (xy 43.575728 -179.5696) (xy 43.63515 -179.577423)
			(xy 43.693043 -179.592936) (xy 43.748416 -179.615872) (xy 43.800322 -179.645839) (xy 43.847872 -179.682326)
			(xy 43.890252 -179.724706) (xy 43.926739 -179.772256) (xy 43.956706 -179.824162) (xy 43.979642 -179.879535)
			(xy 43.995155 -179.937428) (xy 44.002978 -179.99685) (xy 44.003468 -180.026818) (xy 44.002978 -180.056786)
			(xy 43.995155 -180.116208) (xy 43.979642 -180.174101) (xy 43.956706 -180.229474) (xy 43.926739 -180.28138)
			(xy 43.890252 -180.32893) (xy 43.847872 -180.37131) (xy 43.800322 -180.407797) (xy 43.748416 -180.437764)
			(xy 43.693043 -180.4607) (xy 43.63515 -180.476213) (xy 43.575728 -180.484036) (xy 43.515792 -180.484036)
			(xy 43.45637 -180.476213) (xy 43.398477 -180.4607) (xy 43.343104 -180.437764) (xy 43.291198 -180.407797)
			(xy 43.243648 -180.37131) (xy 43.201268 -180.32893) (xy 43.164781 -180.28138) (xy 43.134814 -180.229474)
			(xy 43.111878 -180.174101) (xy 43.096365 -180.116208) (xy 43.088542 -180.056786) (xy 5.511381 -180.056786)
			(xy 5.503194 -180.069788) (xy 5.468532 -180.110739) (xy 5.448808 -180.128926) (xy 5.440426 -180.136292)
			(xy 5.431536 -180.156612) (xy 5.433822 -180.256434) (xy 5.443474 -180.276246) (xy 5.45211 -180.283358)
			(xy 5.474328 -180.302026) (xy 5.514337 -180.344062) (xy 5.548709 -180.39082) (xy 5.576892 -180.441549)
			(xy 5.598433 -180.495435) (xy 5.612987 -180.551613) (xy 5.62032 -180.60918) (xy 5.620766 -180.638196)
			(xy 5.620276 -180.668164) (xy 5.612453 -180.727586) (xy 5.59694 -180.785479) (xy 5.574004 -180.840852)
			(xy 5.561374 -180.862728) (xy 17.157682 -180.862728) (xy 17.157682 -180.802792) (xy 17.165505 -180.74337)
			(xy 17.181018 -180.685477) (xy 17.203954 -180.630104) (xy 17.233921 -180.578198) (xy 17.270408 -180.530648)
			(xy 17.312788 -180.488268) (xy 17.360338 -180.451781) (xy 17.412244 -180.421814) (xy 17.467617 -180.398878)
			(xy 17.52551 -180.383365) (xy 17.584932 -180.375542) (xy 17.644868 -180.375542) (xy 17.70429 -180.383365)
			(xy 17.762183 -180.398878) (xy 17.817556 -180.421814) (xy 17.869462 -180.451781) (xy 17.917012 -180.488268)
			(xy 17.959392 -180.530648) (xy 17.995879 -180.578198) (xy 18.025846 -180.630104) (xy 18.048782 -180.685477)
			(xy 18.064295 -180.74337) (xy 18.072118 -180.802792) (xy 18.072608 -180.83276) (xy 18.072118 -180.862728)
			(xy 18.064295 -180.92215) (xy 18.048782 -180.980043) (xy 18.025846 -181.035416) (xy 17.995879 -181.087322)
			(xy 17.96162 -181.131968) (xy 45.637432 -181.131968) (xy 45.637432 -181.072032) (xy 45.645255 -181.01261)
			(xy 45.660768 -180.954717) (xy 45.683704 -180.899344) (xy 45.713671 -180.847438) (xy 45.750158 -180.799888)
			(xy 45.792538 -180.757508) (xy 45.840088 -180.721021) (xy 45.891994 -180.691054) (xy 45.947367 -180.668118)
			(xy 46.00526 -180.652605) (xy 46.064682 -180.644782) (xy 46.124618 -180.644782) (xy 46.18404 -180.652605)
			(xy 46.241933 -180.668118) (xy 46.297306 -180.691054) (xy 46.349212 -180.721021) (xy 46.396762 -180.757508)
			(xy 46.439142 -180.799888) (xy 46.475629 -180.847438) (xy 46.505596 -180.899344) (xy 46.528532 -180.954717)
			(xy 46.544045 -181.01261) (xy 46.551868 -181.072032) (xy 46.552358 -181.102) (xy 46.551868 -181.131968)
			(xy 46.544045 -181.19139) (xy 46.528532 -181.249283) (xy 46.505596 -181.304656) (xy 46.475629 -181.356562)
			(xy 46.439142 -181.404112) (xy 46.396762 -181.446492) (xy 46.349212 -181.482979) (xy 46.297306 -181.512946)
			(xy 46.241933 -181.535882) (xy 46.18404 -181.551395) (xy 46.124618 -181.559218) (xy 46.064682 -181.559218)
			(xy 46.00526 -181.551395) (xy 45.947367 -181.535882) (xy 45.891994 -181.512946) (xy 45.840088 -181.482979)
			(xy 45.792538 -181.446492) (xy 45.750158 -181.404112) (xy 45.713671 -181.356562) (xy 45.683704 -181.304656)
			(xy 45.660768 -181.249283) (xy 45.645255 -181.19139) (xy 45.637432 -181.131968) (xy 17.96162 -181.131968)
			(xy 17.959392 -181.134872) (xy 17.917012 -181.177252) (xy 17.869462 -181.213739) (xy 17.817556 -181.243706)
			(xy 17.762183 -181.266642) (xy 17.70429 -181.282155) (xy 17.644868 -181.289978) (xy 17.584932 -181.289978)
			(xy 17.52551 -181.282155) (xy 17.467617 -181.266642) (xy 17.412244 -181.243706) (xy 17.360338 -181.213739)
			(xy 17.312788 -181.177252) (xy 17.270408 -181.134872) (xy 17.233921 -181.087322) (xy 17.203954 -181.035416)
			(xy 17.181018 -180.980043) (xy 17.165505 -180.92215) (xy 17.157682 -180.862728) (xy 5.561374 -180.862728)
			(xy 5.544037 -180.892758) (xy 5.50755 -180.940308) (xy 5.46517 -180.982688) (xy 5.41762 -181.019175)
			(xy 5.365714 -181.049142) (xy 5.310341 -181.072078) (xy 5.252448 -181.087591) (xy 5.193026 -181.095414)
			(xy 5.13309 -181.095414) (xy 5.073668 -181.087591) (xy 5.015775 -181.072078) (xy 4.960402 -181.049142)
			(xy 4.908496 -181.019175) (xy 4.860946 -180.982688) (xy 4.818566 -180.940308) (xy 4.782079 -180.892758)
			(xy 4.752112 -180.840852) (xy 4.729176 -180.785479) (xy 4.713663 -180.727586) (xy 4.70584 -180.668164)
			(xy 4.70535 -180.638196) (xy 4.231437 -180.638196) (xy 4.22002 -180.648089) (xy 4.17417 -180.677555)
			(xy 4.124594 -180.700196) (xy 4.0723 -180.715551) (xy 4.018353 -180.723308) (xy 3.991102 -180.723794)
			(xy 3.99034 -180.723794) (xy 3.965011 -180.723374) (xy 3.914805 -180.716615) (xy 3.890264 -180.710332)
			(xy 3.876728 -180.707001) (xy 3.848861 -180.707141) (xy 3.822072 -180.714818) (xy 3.798361 -180.729461)
			(xy 3.779498 -180.749975) (xy 3.766893 -180.774829) (xy 3.761486 -180.802168) (xy 3.763681 -180.829949)
			(xy 3.76809 -180.843174) (xy 3.778973 -180.874841) (xy 3.790718 -180.94076) (xy 3.791458 -180.974238)
			(xy 3.791458 -180.975) (xy 3.790972 -181.002251) (xy 3.783216 -181.056199) (xy 3.767861 -181.108494)
			(xy 3.745219 -181.158071) (xy 3.715753 -181.203921) (xy 3.680062 -181.245112) (xy 3.638871 -181.280803)
			(xy 3.593021 -181.310269) (xy 3.543444 -181.332911) (xy 3.491149 -181.348266) (xy 3.437201 -181.356022)
			(xy 3.382699 -181.356022) (xy 3.328751 -181.348266) (xy 3.276456 -181.332911) (xy 3.226879 -181.310269)
			(xy 3.181029 -181.280803) (xy 3.139838 -181.245112) (xy 3.104147 -181.203921) (xy 3.074681 -181.158071)
			(xy 3.052039 -181.108494) (xy 3.036684 -181.056199) (xy 3.028928 -181.002251) (xy 2.896108 -181.002251)
			(xy 2.896108 -181.639968) (xy 31.311832 -181.639968) (xy 31.311832 -181.580032) (xy 31.319655 -181.52061)
			(xy 31.335168 -181.462717) (xy 31.358104 -181.407344) (xy 31.388071 -181.355438) (xy 31.424558 -181.307888)
			(xy 31.466938 -181.265508) (xy 31.514488 -181.229021) (xy 31.566394 -181.199054) (xy 31.621767 -181.176118)
			(xy 31.67966 -181.160605) (xy 31.739082 -181.152782) (xy 31.799018 -181.152782) (xy 31.85844 -181.160605)
			(xy 31.916333 -181.176118) (xy 31.971706 -181.199054) (xy 32.023612 -181.229021) (xy 32.071162 -181.265508)
			(xy 32.113542 -181.307888) (xy 32.150029 -181.355438) (xy 32.179996 -181.407344) (xy 32.202932 -181.462717)
			(xy 32.218445 -181.52061) (xy 32.226268 -181.580032) (xy 32.226758 -181.61) (xy 32.226268 -181.639968)
			(xy 32.218445 -181.69939) (xy 32.202932 -181.757283) (xy 32.179996 -181.812656) (xy 32.150029 -181.864562)
			(xy 32.113542 -181.912112) (xy 32.071162 -181.954492) (xy 32.023612 -181.990979) (xy 31.971706 -182.020946)
			(xy 31.971653 -182.020968) (xy 43.124102 -182.020968) (xy 43.124102 -181.961032) (xy 43.131925 -181.90161)
			(xy 43.147438 -181.843717) (xy 43.170374 -181.788344) (xy 43.200341 -181.736438) (xy 43.236828 -181.688888)
			(xy 43.279208 -181.646508) (xy 43.326758 -181.610021) (xy 43.378664 -181.580054) (xy 43.434037 -181.557118)
			(xy 43.49193 -181.541605) (xy 43.551352 -181.533782) (xy 43.611288 -181.533782) (xy 43.67071 -181.541605)
			(xy 43.728603 -181.557118) (xy 43.783976 -181.580054) (xy 43.835882 -181.610021) (xy 43.883432 -181.646508)
			(xy 43.925812 -181.688888) (xy 43.962299 -181.736438) (xy 43.992266 -181.788344) (xy 44.015202 -181.843717)
			(xy 44.030715 -181.90161) (xy 44.038538 -181.961032) (xy 44.039028 -181.991) (xy 44.038538 -182.020968)
			(xy 44.030715 -182.08039) (xy 44.015202 -182.138283) (xy 43.992266 -182.193656) (xy 43.962299 -182.245562)
			(xy 43.925812 -182.293112) (xy 43.883432 -182.335492) (xy 43.835882 -182.371979) (xy 43.783976 -182.401946)
			(xy 43.728603 -182.424882) (xy 43.67071 -182.440395) (xy 43.611288 -182.448218) (xy 43.551352 -182.448218)
			(xy 43.49193 -182.440395) (xy 43.434037 -182.424882) (xy 43.378664 -182.401946) (xy 43.326758 -182.371979)
			(xy 43.279208 -182.335492) (xy 43.236828 -182.293112) (xy 43.200341 -182.245562) (xy 43.170374 -182.193656)
			(xy 43.147438 -182.138283) (xy 43.131925 -182.08039) (xy 43.124102 -182.020968) (xy 31.971653 -182.020968)
			(xy 31.916333 -182.043882) (xy 31.85844 -182.059395) (xy 31.799018 -182.067218) (xy 31.739082 -182.067218)
			(xy 31.67966 -182.059395) (xy 31.621767 -182.043882) (xy 31.566394 -182.020946) (xy 31.514488 -181.990979)
			(xy 31.466938 -181.954492) (xy 31.424558 -181.912112) (xy 31.388071 -181.864562) (xy 31.358104 -181.812656)
			(xy 31.335168 -181.757283) (xy 31.319655 -181.69939) (xy 31.311832 -181.639968) (xy 2.896108 -181.639968)
			(xy 2.896108 -182.942738) (xy 2.897124 -182.95239) (xy 2.898756 -182.959632) (xy 2.905604 -182.972794)
			(xy 2.910586 -182.978298) (xy 3.096256 -183.163968) (xy 16.840182 -183.163968) (xy 16.840182 -183.104032)
			(xy 16.848005 -183.04461) (xy 16.863518 -182.986717) (xy 16.886454 -182.931344) (xy 16.916421 -182.879438)
			(xy 16.952908 -182.831888) (xy 16.995288 -182.789508) (xy 17.042838 -182.753021) (xy 17.094744 -182.723054)
			(xy 17.150117 -182.700118) (xy 17.20801 -182.684605) (xy 17.267432 -182.676782) (xy 17.327368 -182.676782)
			(xy 17.38679 -182.684605) (xy 17.444683 -182.700118) (xy 17.500056 -182.723054) (xy 17.551962 -182.753021)
			(xy 17.599512 -182.789508) (xy 17.641892 -182.831888) (xy 17.678379 -182.879438) (xy 17.708346 -182.931344)
			(xy 17.731282 -182.986717) (xy 17.746795 -183.04461) (xy 17.754618 -183.104032) (xy 17.755108 -183.134)
			(xy 17.754618 -183.163968) (xy 17.746795 -183.22339) (xy 17.736717 -183.261) (xy 18.433032 -183.261)
			(xy 18.437103 -183.205378) (xy 18.449229 -183.150941) (xy 18.469152 -183.09885) (xy 18.496448 -183.050215)
			(xy 18.530534 -183.006072) (xy 18.570683 -182.967363) (xy 18.616041 -182.934912) (xy 18.665641 -182.909411)
			(xy 18.718425 -182.891404) (xy 18.773268 -182.881274) (xy 18.829002 -182.879237) (xy 18.835936 -182.88)
			(xy 45.712632 -182.88) (xy 45.716703 -182.824378) (xy 45.728829 -182.769941) (xy 45.748752 -182.71785)
			(xy 45.776048 -182.669215) (xy 45.810134 -182.625072) (xy 45.850283 -182.586363) (xy 45.895641 -182.553912)
			(xy 45.945241 -182.528411) (xy 45.998025 -182.510404) (xy 46.052868 -182.500274) (xy 46.108602 -182.498237)
			(xy 46.164039 -182.504337) (xy 46.217996 -182.518443) (xy 46.269325 -182.540255) (xy 46.316931 -182.569309)
			(xy 46.359799 -182.604984) (xy 46.397016 -182.646521) (xy 46.427789 -182.693034) (xy 46.451461 -182.743531)
			(xy 46.467529 -182.796938) (xy 46.475649 -182.852114) (xy 46.476158 -182.88) (xy 46.475649 -182.907886)
			(xy 46.467529 -182.963062) (xy 46.451461 -183.016469) (xy 46.427789 -183.066966) (xy 46.397016 -183.113479)
			(xy 46.359799 -183.155016) (xy 46.316931 -183.190691) (xy 46.269325 -183.219745) (xy 46.217996 -183.241557)
			(xy 46.164039 -183.255663) (xy 46.108602 -183.261763) (xy 46.052868 -183.259726) (xy 45.998025 -183.249596)
			(xy 45.945241 -183.231589) (xy 45.895641 -183.206088) (xy 45.850283 -183.173637) (xy 45.810134 -183.134928)
			(xy 45.776048 -183.090785) (xy 45.748752 -183.04215) (xy 45.728829 -182.990059) (xy 45.716703 -182.935622)
			(xy 45.712632 -182.88) (xy 18.835936 -182.88) (xy 18.884439 -182.885337) (xy 18.938396 -182.899443)
			(xy 18.989725 -182.921255) (xy 19.037331 -182.950309) (xy 19.080199 -182.985984) (xy 19.117416 -183.027521)
			(xy 19.148189 -183.074034) (xy 19.171861 -183.124531) (xy 19.187929 -183.177938) (xy 19.196049 -183.233114)
			(xy 19.196558 -183.261) (xy 19.196049 -183.288886) (xy 19.187929 -183.344062) (xy 19.171861 -183.397469)
			(xy 19.148189 -183.447966) (xy 19.117416 -183.494479) (xy 19.080199 -183.536016) (xy 19.037331 -183.571691)
			(xy 18.989725 -183.600745) (xy 18.938396 -183.622557) (xy 18.884439 -183.636663) (xy 18.829002 -183.642763)
			(xy 18.773268 -183.640726) (xy 18.718425 -183.630596) (xy 18.665641 -183.612589) (xy 18.616041 -183.587088)
			(xy 18.570683 -183.554637) (xy 18.530534 -183.515928) (xy 18.496448 -183.471785) (xy 18.469152 -183.42315)
			(xy 18.449229 -183.371059) (xy 18.437103 -183.316622) (xy 18.433032 -183.261) (xy 17.736717 -183.261)
			(xy 17.731282 -183.281283) (xy 17.708346 -183.336656) (xy 17.678379 -183.388562) (xy 17.641892 -183.436112)
			(xy 17.599512 -183.478492) (xy 17.551962 -183.514979) (xy 17.500056 -183.544946) (xy 17.444683 -183.567882)
			(xy 17.38679 -183.583395) (xy 17.327368 -183.591218) (xy 17.267432 -183.591218) (xy 17.20801 -183.583395)
			(xy 17.150117 -183.567882) (xy 17.094744 -183.544946) (xy 17.042838 -183.514979) (xy 16.995288 -183.478492)
			(xy 16.952908 -183.436112) (xy 16.916421 -183.388562) (xy 16.886454 -183.336656) (xy 16.863518 -183.281283)
			(xy 16.848005 -183.22339) (xy 16.840182 -183.163968) (xy 3.096256 -183.163968) (xy 3.166364 -183.234076)
			(xy 3.200616 -183.26898) (xy 3.264142 -183.343341) (xy 3.321638 -183.422457) (xy 3.372748 -183.505842)
			(xy 3.417157 -183.592979) (xy 3.454591 -183.683333) (xy 3.484821 -183.776345) (xy 3.507658 -183.871443)
			(xy 3.522963 -183.96804) (xy 3.53064 -184.065539) (xy 3.531108 -184.11444) (xy 3.531108 -184.531)
			(xy 18.433032 -184.531) (xy 18.437103 -184.475378) (xy 18.449229 -184.420941) (xy 18.469152 -184.36885)
			(xy 18.496448 -184.320215) (xy 18.530534 -184.276072) (xy 18.570683 -184.237363) (xy 18.616041 -184.204912)
			(xy 18.665641 -184.179411) (xy 18.718425 -184.161404) (xy 18.773268 -184.151274) (xy 18.829002 -184.149237)
			(xy 18.884439 -184.155337) (xy 18.938396 -184.169443) (xy 18.989725 -184.191255) (xy 19.037331 -184.220309)
			(xy 19.080199 -184.255984) (xy 19.117416 -184.297521) (xy 19.134757 -184.323732) (xy 32.071292 -184.323732)
			(xy 32.071292 -184.263796) (xy 32.079115 -184.204374) (xy 32.094628 -184.146481) (xy 32.117564 -184.091108)
			(xy 32.147531 -184.039202) (xy 32.184018 -183.991652) (xy 32.226398 -183.949272) (xy 32.273948 -183.912785)
			(xy 32.325854 -183.882818) (xy 32.381227 -183.859882) (xy 32.43912 -183.844369) (xy 32.498542 -183.836546)
			(xy 32.558478 -183.836546) (xy 32.6179 -183.844369) (xy 32.675793 -183.859882) (xy 32.731166 -183.882818)
			(xy 32.783072 -183.912785) (xy 32.830622 -183.949272) (xy 32.873002 -183.991652) (xy 32.909489 -184.039202)
			(xy 32.939456 -184.091108) (xy 32.962392 -184.146481) (xy 32.977905 -184.204374) (xy 32.98138 -184.230768)
			(xy 47.878982 -184.230768) (xy 47.878982 -184.170832) (xy 47.886805 -184.11141) (xy 47.902318 -184.053517)
			(xy 47.925254 -183.998144) (xy 47.955221 -183.946238) (xy 47.991708 -183.898688) (xy 48.034088 -183.856308)
			(xy 48.081638 -183.819821) (xy 48.133544 -183.789854) (xy 48.188917 -183.766918) (xy 48.24681 -183.751405)
			(xy 48.306232 -183.743582) (xy 48.366168 -183.743582) (xy 48.42559 -183.751405) (xy 48.483483 -183.766918)
			(xy 48.538856 -183.789854) (xy 48.590762 -183.819821) (xy 48.638312 -183.856308) (xy 48.680692 -183.898688)
			(xy 48.717179 -183.946238) (xy 48.747146 -183.998144) (xy 48.770082 -184.053517) (xy 48.785595 -184.11141)
			(xy 48.793418 -184.170832) (xy 48.793908 -184.2008) (xy 48.793418 -184.230768) (xy 48.785595 -184.29019)
			(xy 48.770082 -184.348083) (xy 48.747146 -184.403456) (xy 48.717179 -184.455362) (xy 48.680692 -184.502912)
			(xy 48.638312 -184.545292) (xy 48.590762 -184.581779) (xy 48.538856 -184.611746) (xy 48.483483 -184.634682)
			(xy 48.42559 -184.650195) (xy 48.366168 -184.658018) (xy 48.306232 -184.658018) (xy 48.24681 -184.650195)
			(xy 48.188917 -184.634682) (xy 48.133544 -184.611746) (xy 48.081638 -184.581779) (xy 48.034088 -184.545292)
			(xy 47.991708 -184.502912) (xy 47.955221 -184.455362) (xy 47.925254 -184.403456) (xy 47.902318 -184.348083)
			(xy 47.886805 -184.29019) (xy 47.878982 -184.230768) (xy 32.98138 -184.230768) (xy 32.985728 -184.263796)
			(xy 32.986218 -184.293764) (xy 32.985728 -184.323732) (xy 32.977905 -184.383154) (xy 32.962392 -184.441047)
			(xy 32.939456 -184.49642) (xy 32.909489 -184.548326) (xy 32.873002 -184.595876) (xy 32.830622 -184.638256)
			(xy 32.783072 -184.674743) (xy 32.731166 -184.70471) (xy 32.675793 -184.727646) (xy 32.6179 -184.743159)
			(xy 32.558478 -184.750982) (xy 32.498542 -184.750982) (xy 32.43912 -184.743159) (xy 32.381227 -184.727646)
			(xy 32.325854 -184.70471) (xy 32.273948 -184.674743) (xy 32.226398 -184.638256) (xy 32.184018 -184.595876)
			(xy 32.147531 -184.548326) (xy 32.117564 -184.49642) (xy 32.094628 -184.441047) (xy 32.079115 -184.383154)
			(xy 32.071292 -184.323732) (xy 19.134757 -184.323732) (xy 19.148189 -184.344034) (xy 19.171861 -184.394531)
			(xy 19.187929 -184.447938) (xy 19.196049 -184.503114) (xy 19.196558 -184.531) (xy 19.196049 -184.558886)
			(xy 19.187929 -184.614062) (xy 19.171861 -184.667469) (xy 19.148189 -184.717966) (xy 19.117416 -184.764479)
			(xy 19.080199 -184.806016) (xy 19.037331 -184.841691) (xy 18.989725 -184.870745) (xy 18.938396 -184.892557)
			(xy 18.884439 -184.906663) (xy 18.829002 -184.912763) (xy 18.773268 -184.910726) (xy 18.718425 -184.900596)
			(xy 18.665641 -184.882589) (xy 18.616041 -184.857088) (xy 18.570683 -184.824637) (xy 18.530534 -184.785928)
			(xy 18.496448 -184.741785) (xy 18.469152 -184.69315) (xy 18.449229 -184.641059) (xy 18.437103 -184.586622)
			(xy 18.433032 -184.531) (xy 3.531108 -184.531) (xy 3.531108 -185.015886) (xy 3.531108 -185.017156)
			(xy 3.531821 -185.027066) (xy 3.539792 -185.045244) (xy 3.554056 -185.059047) (xy 3.563112 -185.06313)
			(xy 3.563366 -185.06313) (xy 3.577648 -185.068968) (xy 34.213782 -185.068968) (xy 34.213782 -185.009032)
			(xy 34.221605 -184.94961) (xy 34.237118 -184.891717) (xy 34.260054 -184.836344) (xy 34.290021 -184.784438)
			(xy 34.326508 -184.736888) (xy 34.368888 -184.694508) (xy 34.416438 -184.658021) (xy 34.468344 -184.628054)
			(xy 34.523717 -184.605118) (xy 34.58161 -184.589605) (xy 34.641032 -184.581782) (xy 34.700968 -184.581782)
			(xy 34.76039 -184.589605) (xy 34.818283 -184.605118) (xy 34.873656 -184.628054) (xy 34.925562 -184.658021)
			(xy 34.973112 -184.694508) (xy 35.015492 -184.736888) (xy 35.051979 -184.784438) (xy 35.081946 -184.836344)
			(xy 35.104882 -184.891717) (xy 35.120395 -184.94961) (xy 35.128218 -185.009032) (xy 35.128708 -185.039)
			(xy 35.128218 -185.068968) (xy 35.120395 -185.12839) (xy 35.104882 -185.186283) (xy 35.10087 -185.195968)
			(xy 36.626782 -185.195968) (xy 36.626782 -185.136032) (xy 36.634605 -185.07661) (xy 36.650118 -185.018717)
			(xy 36.673054 -184.963344) (xy 36.703021 -184.911438) (xy 36.739508 -184.863888) (xy 36.781888 -184.821508)
			(xy 36.829438 -184.785021) (xy 36.881344 -184.755054) (xy 36.936717 -184.732118) (xy 36.99461 -184.716605)
			(xy 37.054032 -184.708782) (xy 37.113968 -184.708782) (xy 37.17339 -184.716605) (xy 37.231283 -184.732118)
			(xy 37.286656 -184.755054) (xy 37.338562 -184.785021) (xy 37.386112 -184.821508) (xy 37.428492 -184.863888)
			(xy 37.464979 -184.911438) (xy 37.494946 -184.963344) (xy 37.517882 -185.018717) (xy 37.533395 -185.07661)
			(xy 37.541218 -185.136032) (xy 37.541708 -185.166) (xy 37.541218 -185.195968) (xy 37.533395 -185.25539)
			(xy 37.517882 -185.313283) (xy 37.494946 -185.368656) (xy 37.465303 -185.42) (xy 47.126396 -185.42)
			(xy 47.130467 -185.364378) (xy 47.142593 -185.309941) (xy 47.162516 -185.25785) (xy 47.189812 -185.209215)
			(xy 47.223898 -185.165072) (xy 47.264047 -185.126363) (xy 47.309405 -185.093912) (xy 47.359005 -185.068411)
			(xy 47.411789 -185.050404) (xy 47.466632 -185.040274) (xy 47.522366 -185.038237) (xy 47.577803 -185.044337)
			(xy 47.63176 -185.058443) (xy 47.683089 -185.080255) (xy 47.730695 -185.109309) (xy 47.773563 -185.144984)
			(xy 47.81078 -185.186521) (xy 47.841553 -185.233034) (xy 47.865225 -185.283531) (xy 47.881293 -185.336938)
			(xy 47.889413 -185.392114) (xy 47.889922 -185.42) (xy 47.889413 -185.447886) (xy 47.881293 -185.503062)
			(xy 47.865225 -185.556469) (xy 47.841553 -185.606966) (xy 47.81078 -185.653479) (xy 47.773563 -185.695016)
			(xy 47.730695 -185.730691) (xy 47.683089 -185.759745) (xy 47.63176 -185.781557) (xy 47.577803 -185.795663)
			(xy 47.522366 -185.801763) (xy 47.466632 -185.799726) (xy 47.411789 -185.789596) (xy 47.359005 -185.771589)
			(xy 47.309405 -185.746088) (xy 47.264047 -185.713637) (xy 47.223898 -185.674928) (xy 47.189812 -185.630785)
			(xy 47.162516 -185.58215) (xy 47.142593 -185.530059) (xy 47.130467 -185.475622) (xy 47.126396 -185.42)
			(xy 37.465303 -185.42) (xy 37.464979 -185.420562) (xy 37.428492 -185.468112) (xy 37.386112 -185.510492)
			(xy 37.338562 -185.546979) (xy 37.286656 -185.576946) (xy 37.231283 -185.599882) (xy 37.17339 -185.615395)
			(xy 37.113968 -185.623218) (xy 37.054032 -185.623218) (xy 36.99461 -185.615395) (xy 36.936717 -185.599882)
			(xy 36.881344 -185.576946) (xy 36.829438 -185.546979) (xy 36.781888 -185.510492) (xy 36.739508 -185.468112)
			(xy 36.703021 -185.420562) (xy 36.673054 -185.368656) (xy 36.650118 -185.313283) (xy 36.634605 -185.25539)
			(xy 36.626782 -185.195968) (xy 35.10087 -185.195968) (xy 35.081946 -185.241656) (xy 35.051979 -185.293562)
			(xy 35.015492 -185.341112) (xy 34.973112 -185.383492) (xy 34.925562 -185.419979) (xy 34.873656 -185.449946)
			(xy 34.818283 -185.472882) (xy 34.76039 -185.488395) (xy 34.700968 -185.496218) (xy 34.641032 -185.496218)
			(xy 34.58161 -185.488395) (xy 34.523717 -185.472882) (xy 34.468344 -185.449946) (xy 34.416438 -185.419979)
			(xy 34.368888 -185.383492) (xy 34.326508 -185.341112) (xy 34.290021 -185.293562) (xy 34.260054 -185.241656)
			(xy 34.237118 -185.186283) (xy 34.221605 -185.12839) (xy 34.213782 -185.068968) (xy 3.577648 -185.068968)
			(xy 3.591604 -185.074673) (xy 3.645 -185.104174) (xy 3.694005 -185.140506) (xy 3.737749 -185.183025)
			(xy 3.775459 -185.230977) (xy 3.806465 -185.283514) (xy 3.830219 -185.339703) (xy 3.846298 -185.39855)
			(xy 3.854419 -185.45901) (xy 3.854438 -185.520014) (xy 3.846353 -185.58048) (xy 3.830309 -185.639336)
			(xy 3.806589 -185.69554) (xy 3.775615 -185.748095) (xy 3.737934 -185.79607) (xy 3.694215 -185.838615)
			(xy 3.645232 -185.874977) (xy 3.591854 -185.90451) (xy 3.56362 -185.916062) (xy 3.563112 -185.916062)
			(xy 3.556132 -185.919144) (xy 3.544245 -185.928697) (xy 3.539744 -185.934858) (xy 3.535426 -185.940954)
			(xy 3.531108 -185.955432) (xy 3.531108 -186.055) (xy 6.348982 -186.055) (xy 6.353053 -185.999378)
			(xy 6.365179 -185.944941) (xy 6.385102 -185.89285) (xy 6.412398 -185.844215) (xy 6.446484 -185.800072)
			(xy 6.486633 -185.761363) (xy 6.531991 -185.728912) (xy 6.581591 -185.703411) (xy 6.634375 -185.685404)
			(xy 6.689218 -185.675274) (xy 6.744952 -185.673237) (xy 6.800389 -185.679337) (xy 6.854346 -185.693443)
			(xy 6.905675 -185.715255) (xy 6.953281 -185.744309) (xy 6.996149 -185.779984) (xy 7.033366 -185.821521)
			(xy 7.064139 -185.868034) (xy 7.087811 -185.918531) (xy 7.099676 -185.957968) (xy 18.357832 -185.957968)
			(xy 18.357832 -185.898032) (xy 18.365655 -185.83861) (xy 18.381168 -185.780717) (xy 18.404104 -185.725344)
			(xy 18.434071 -185.673438) (xy 18.470558 -185.625888) (xy 18.512938 -185.583508) (xy 18.560488 -185.547021)
			(xy 18.612394 -185.517054) (xy 18.667767 -185.494118) (xy 18.72566 -185.478605) (xy 18.785082 -185.470782)
			(xy 18.845018 -185.470782) (xy 18.90444 -185.478605) (xy 18.962333 -185.494118) (xy 19.017706 -185.517054)
			(xy 19.069612 -185.547021) (xy 19.117162 -185.583508) (xy 19.159542 -185.625888) (xy 19.196029 -185.673438)
			(xy 19.196353 -185.674) (xy 23.239982 -185.674) (xy 23.244053 -185.618378) (xy 23.256179 -185.563941)
			(xy 23.276102 -185.51185) (xy 23.303398 -185.463215) (xy 23.337484 -185.419072) (xy 23.377633 -185.380363)
			(xy 23.422991 -185.347912) (xy 23.472591 -185.322411) (xy 23.525375 -185.304404) (xy 23.580218 -185.294274)
			(xy 23.635952 -185.292237) (xy 23.691389 -185.298337) (xy 23.745346 -185.312443) (xy 23.796675 -185.334255)
			(xy 23.844281 -185.363309) (xy 23.887149 -185.398984) (xy 23.924366 -185.440521) (xy 23.955139 -185.487034)
			(xy 23.978811 -185.537531) (xy 23.994879 -185.590938) (xy 24.002999 -185.646114) (xy 24.003508 -185.674)
			(xy 24.002999 -185.701886) (xy 23.994879 -185.757062) (xy 23.978811 -185.810469) (xy 23.955139 -185.860966)
			(xy 23.924366 -185.907479) (xy 23.887149 -185.949016) (xy 23.844281 -185.984691) (xy 23.796675 -186.013745)
			(xy 23.745346 -186.035557) (xy 23.691389 -186.049663) (xy 23.635952 -186.055763) (xy 23.580218 -186.053726)
			(xy 23.525375 -186.043596) (xy 23.472591 -186.025589) (xy 23.422991 -186.000088) (xy 23.377633 -185.967637)
			(xy 23.337484 -185.928928) (xy 23.303398 -185.884785) (xy 23.276102 -185.83615) (xy 23.256179 -185.784059)
			(xy 23.244053 -185.729622) (xy 23.239982 -185.674) (xy 19.196353 -185.674) (xy 19.225996 -185.725344)
			(xy 19.248932 -185.780717) (xy 19.264445 -185.83861) (xy 19.272268 -185.898032) (xy 19.272758 -185.928)
			(xy 19.272268 -185.957968) (xy 19.264445 -186.01739) (xy 19.248932 -186.075283) (xy 19.225996 -186.130656)
			(xy 19.196029 -186.182562) (xy 19.159542 -186.230112) (xy 19.117162 -186.272492) (xy 19.069612 -186.308979)
			(xy 19.017706 -186.338946) (xy 18.962333 -186.361882) (xy 18.90444 -186.377395) (xy 18.845018 -186.385218)
			(xy 18.785082 -186.385218) (xy 18.72566 -186.377395) (xy 18.667767 -186.361882) (xy 18.612394 -186.338946)
			(xy 18.560488 -186.308979) (xy 18.512938 -186.272492) (xy 18.470558 -186.230112) (xy 18.434071 -186.182562)
			(xy 18.404104 -186.130656) (xy 18.381168 -186.075283) (xy 18.365655 -186.01739) (xy 18.357832 -185.957968)
			(xy 7.099676 -185.957968) (xy 7.103879 -185.971938) (xy 7.111999 -186.027114) (xy 7.112508 -186.055)
			(xy 7.111999 -186.082886) (xy 7.103879 -186.138062) (xy 7.087811 -186.191469) (xy 7.064139 -186.241966)
			(xy 7.033366 -186.288479) (xy 6.996149 -186.330016) (xy 6.953281 -186.365691) (xy 6.905675 -186.394745)
			(xy 6.854346 -186.416557) (xy 6.800389 -186.430663) (xy 6.744952 -186.436763) (xy 6.689218 -186.434726)
			(xy 6.634375 -186.424596) (xy 6.581591 -186.406589) (xy 6.531991 -186.381088) (xy 6.486633 -186.348637)
			(xy 6.446484 -186.309928) (xy 6.412398 -186.265785) (xy 6.385102 -186.21715) (xy 6.365179 -186.165059)
			(xy 6.353053 -186.110622) (xy 6.348982 -186.055) (xy 3.531108 -186.055) (xy 3.531108 -186.592968)
			(xy 16.197562 -186.592968) (xy 16.197562 -186.533032) (xy 16.205385 -186.47361) (xy 16.220898 -186.415717)
			(xy 16.243834 -186.360344) (xy 16.273801 -186.308438) (xy 16.310288 -186.260888) (xy 16.352668 -186.218508)
			(xy 16.400218 -186.182021) (xy 16.452124 -186.152054) (xy 16.507497 -186.129118) (xy 16.56539 -186.113605)
			(xy 16.624812 -186.105782) (xy 16.684748 -186.105782) (xy 16.74417 -186.113605) (xy 16.802063 -186.129118)
			(xy 16.857436 -186.152054) (xy 16.909342 -186.182021) (xy 16.956892 -186.218508) (xy 16.999272 -186.260888)
			(xy 17.035759 -186.308438) (xy 17.065726 -186.360344) (xy 17.088662 -186.415717) (xy 17.102127 -186.465968)
			(xy 29.768782 -186.465968) (xy 29.768782 -186.406032) (xy 29.776605 -186.34661) (xy 29.792118 -186.288717)
			(xy 29.815054 -186.233344) (xy 29.845021 -186.181438) (xy 29.881508 -186.133888) (xy 29.923888 -186.091508)
			(xy 29.971438 -186.055021) (xy 30.023344 -186.025054) (xy 30.078717 -186.002118) (xy 30.13661 -185.986605)
			(xy 30.196032 -185.978782) (xy 30.255968 -185.978782) (xy 30.31539 -185.986605) (xy 30.373283 -186.002118)
			(xy 30.428656 -186.025054) (xy 30.480562 -186.055021) (xy 30.528112 -186.091508) (xy 30.570492 -186.133888)
			(xy 30.606979 -186.181438) (xy 30.624605 -186.211968) (xy 48.45861 -186.211968) (xy 48.45861 -186.152032)
			(xy 48.466433 -186.09261) (xy 48.481946 -186.034717) (xy 48.504882 -185.979344) (xy 48.534849 -185.927438)
			(xy 48.571336 -185.879888) (xy 48.613716 -185.837508) (xy 48.661266 -185.801021) (xy 48.713172 -185.771054)
			(xy 48.768545 -185.748118) (xy 48.826438 -185.732605) (xy 48.88586 -185.724782) (xy 48.945796 -185.724782)
			(xy 49.005218 -185.732605) (xy 49.063111 -185.748118) (xy 49.118484 -185.771054) (xy 49.17039 -185.801021)
			(xy 49.21794 -185.837508) (xy 49.26032 -185.879888) (xy 49.296807 -185.927438) (xy 49.326774 -185.979344)
			(xy 49.34971 -186.034717) (xy 49.365223 -186.09261) (xy 49.373046 -186.152032) (xy 49.373536 -186.182)
			(xy 49.373046 -186.211968) (xy 49.365223 -186.27139) (xy 49.34971 -186.329283) (xy 49.326774 -186.384656)
			(xy 49.296807 -186.436562) (xy 49.26032 -186.484112) (xy 49.21794 -186.526492) (xy 49.17039 -186.562979)
			(xy 49.118484 -186.592946) (xy 49.063111 -186.615882) (xy 49.005218 -186.631395) (xy 48.945796 -186.639218)
			(xy 48.88586 -186.639218) (xy 48.826438 -186.631395) (xy 48.768545 -186.615882) (xy 48.713172 -186.592946)
			(xy 48.661266 -186.562979) (xy 48.613716 -186.526492) (xy 48.571336 -186.484112) (xy 48.534849 -186.436562)
			(xy 48.504882 -186.384656) (xy 48.481946 -186.329283) (xy 48.466433 -186.27139) (xy 48.45861 -186.211968)
			(xy 30.624605 -186.211968) (xy 30.636946 -186.233344) (xy 30.659882 -186.288717) (xy 30.675395 -186.34661)
			(xy 30.683218 -186.406032) (xy 30.683708 -186.436) (xy 30.683218 -186.465968) (xy 30.675395 -186.52539)
			(xy 30.659882 -186.583283) (xy 30.636946 -186.638656) (xy 30.606979 -186.690562) (xy 30.570492 -186.738112)
			(xy 30.528112 -186.780492) (xy 30.480562 -186.816979) (xy 30.428656 -186.846946) (xy 30.373283 -186.869882)
			(xy 30.31539 -186.885395) (xy 30.255968 -186.893218) (xy 30.196032 -186.893218) (xy 30.13661 -186.885395)
			(xy 30.078717 -186.869882) (xy 30.023344 -186.846946) (xy 29.971438 -186.816979) (xy 29.923888 -186.780492)
			(xy 29.881508 -186.738112) (xy 29.845021 -186.690562) (xy 29.815054 -186.638656) (xy 29.792118 -186.583283)
			(xy 29.776605 -186.52539) (xy 29.768782 -186.465968) (xy 17.102127 -186.465968) (xy 17.104175 -186.47361)
			(xy 17.111998 -186.533032) (xy 17.112488 -186.563) (xy 17.111998 -186.592968) (xy 17.104175 -186.65239)
			(xy 17.088662 -186.710283) (xy 17.065726 -186.765656) (xy 17.035759 -186.817562) (xy 16.999272 -186.865112)
			(xy 16.956892 -186.907492) (xy 16.909342 -186.943979) (xy 16.857436 -186.973946) (xy 16.802063 -186.996882)
			(xy 16.74417 -187.012395) (xy 16.684748 -187.020218) (xy 16.624812 -187.020218) (xy 16.56539 -187.012395)
			(xy 16.507497 -186.996882) (xy 16.452124 -186.973946) (xy 16.400218 -186.943979) (xy 16.352668 -186.907492)
			(xy 16.310288 -186.865112) (xy 16.273801 -186.817562) (xy 16.243834 -186.765656) (xy 16.220898 -186.710283)
			(xy 16.205385 -186.65239) (xy 16.197562 -186.592968) (xy 3.531108 -186.592968) (xy 3.531108 -187.274704)
			(xy 3.977114 -187.274704) (xy 3.977114 -187.214768) (xy 3.984937 -187.155346) (xy 4.00045 -187.097453)
			(xy 4.023386 -187.04208) (xy 4.053353 -186.990174) (xy 4.08984 -186.942624) (xy 4.13222 -186.900244)
			(xy 4.17977 -186.863757) (xy 4.231676 -186.83379) (xy 4.287049 -186.810854) (xy 4.344942 -186.795341)
			(xy 4.404364 -186.787518) (xy 4.4643 -186.787518) (xy 4.523722 -186.795341) (xy 4.581615 -186.810854)
			(xy 4.636988 -186.83379) (xy 4.688894 -186.863757) (xy 4.736444 -186.900244) (xy 4.778824 -186.942624)
			(xy 4.815311 -186.990174) (xy 4.845278 -187.04208) (xy 4.868214 -187.097453) (xy 4.883727 -187.155346)
			(xy 4.89155 -187.214768) (xy 4.89204 -187.244736) (xy 4.89155 -187.274704) (xy 4.883727 -187.334126)
			(xy 4.868214 -187.392019) (xy 4.845278 -187.447392) (xy 4.825316 -187.481968) (xy 23.171132 -187.481968)
			(xy 23.171132 -187.422032) (xy 23.178955 -187.36261) (xy 23.194468 -187.304717) (xy 23.217404 -187.249344)
			(xy 23.247371 -187.197438) (xy 23.283858 -187.149888) (xy 23.326238 -187.107508) (xy 23.373788 -187.071021)
			(xy 23.425694 -187.041054) (xy 23.481067 -187.018118) (xy 23.53896 -187.002605) (xy 23.598382 -186.994782)
			(xy 23.658318 -186.994782) (xy 23.71774 -187.002605) (xy 23.775633 -187.018118) (xy 23.812537 -187.033404)
			(xy 32.050464 -187.033404) (xy 32.050464 -186.973468) (xy 32.058287 -186.914046) (xy 32.0738 -186.856153)
			(xy 32.096736 -186.80078) (xy 32.126703 -186.748874) (xy 32.16319 -186.701324) (xy 32.20557 -186.658944)
			(xy 32.25312 -186.622457) (xy 32.305026 -186.59249) (xy 32.360399 -186.569554) (xy 32.418292 -186.554041)
			(xy 32.477714 -186.546218) (xy 32.53765 -186.546218) (xy 32.597072 -186.554041) (xy 32.654965 -186.569554)
			(xy 32.710338 -186.59249) (xy 32.762244 -186.622457) (xy 32.809794 -186.658944) (xy 32.852174 -186.701324)
			(xy 32.888661 -186.748874) (xy 32.918628 -186.80078) (xy 32.941564 -186.856153) (xy 32.951558 -186.89345)
			(xy 43.125626 -186.89345) (xy 43.125626 -186.833514) (xy 43.133449 -186.774092) (xy 43.148962 -186.716199)
			(xy 43.171898 -186.660826) (xy 43.201865 -186.60892) (xy 43.238352 -186.56137) (xy 43.280732 -186.51899)
			(xy 43.328282 -186.482503) (xy 43.380188 -186.452536) (xy 43.435561 -186.4296) (xy 43.493454 -186.414087)
			(xy 43.552876 -186.406264) (xy 43.612812 -186.406264) (xy 43.672234 -186.414087) (xy 43.730127 -186.4296)
			(xy 43.7855 -186.452536) (xy 43.837406 -186.482503) (xy 43.884956 -186.51899) (xy 43.927336 -186.56137)
			(xy 43.963823 -186.60892) (xy 43.99379 -186.660826) (xy 44.016726 -186.716199) (xy 44.032239 -186.774092)
			(xy 44.040062 -186.833514) (xy 44.040552 -186.863482) (xy 44.040062 -186.89345) (xy 44.032239 -186.952872)
			(xy 44.016726 -187.010765) (xy 43.99379 -187.066138) (xy 43.963823 -187.118044) (xy 43.927336 -187.165594)
			(xy 43.884956 -187.207974) (xy 43.837406 -187.244461) (xy 43.7855 -187.274428) (xy 43.730127 -187.297364)
			(xy 43.672234 -187.312877) (xy 43.612812 -187.3207) (xy 43.552876 -187.3207) (xy 43.493454 -187.312877)
			(xy 43.435561 -187.297364) (xy 43.380188 -187.274428) (xy 43.328282 -187.244461) (xy 43.280732 -187.207974)
			(xy 43.238352 -187.165594) (xy 43.201865 -187.118044) (xy 43.171898 -187.066138) (xy 43.148962 -187.010765)
			(xy 43.133449 -186.952872) (xy 43.125626 -186.89345) (xy 32.951558 -186.89345) (xy 32.957077 -186.914046)
			(xy 32.9649 -186.973468) (xy 32.96539 -187.003436) (xy 32.9649 -187.033404) (xy 32.957077 -187.092826)
			(xy 32.941564 -187.150719) (xy 32.918628 -187.206092) (xy 32.888661 -187.257998) (xy 32.852174 -187.305548)
			(xy 32.809794 -187.347928) (xy 32.762244 -187.384415) (xy 32.710338 -187.414382) (xy 32.654965 -187.437318)
			(xy 32.600173 -187.452) (xy 46.461932 -187.452) (xy 46.466003 -187.396378) (xy 46.478129 -187.341941)
			(xy 46.498052 -187.28985) (xy 46.525348 -187.241215) (xy 46.559434 -187.197072) (xy 46.599583 -187.158363)
			(xy 46.644941 -187.125912) (xy 46.694541 -187.100411) (xy 46.747325 -187.082404) (xy 46.802168 -187.072274)
			(xy 46.857902 -187.070237) (xy 46.913339 -187.076337) (xy 46.967296 -187.090443) (xy 47.018625 -187.112255)
			(xy 47.066231 -187.141309) (xy 47.109099 -187.176984) (xy 47.146316 -187.218521) (xy 47.177089 -187.265034)
			(xy 47.200761 -187.315531) (xy 47.216829 -187.368938) (xy 47.224949 -187.424114) (xy 47.225458 -187.452)
			(xy 47.224949 -187.479886) (xy 47.216829 -187.535062) (xy 47.200761 -187.588469) (xy 47.177089 -187.638966)
			(xy 47.146316 -187.685479) (xy 47.109099 -187.727016) (xy 47.066231 -187.762691) (xy 47.018625 -187.791745)
			(xy 46.967296 -187.813557) (xy 46.913339 -187.827663) (xy 46.857902 -187.833763) (xy 46.802168 -187.831726)
			(xy 46.747325 -187.821596) (xy 46.694541 -187.803589) (xy 46.644941 -187.778088) (xy 46.599583 -187.745637)
			(xy 46.559434 -187.706928) (xy 46.525348 -187.662785) (xy 46.498052 -187.61415) (xy 46.478129 -187.562059)
			(xy 46.466003 -187.507622) (xy 46.461932 -187.452) (xy 32.600173 -187.452) (xy 32.597072 -187.452831)
			(xy 32.53765 -187.460654) (xy 32.477714 -187.460654) (xy 32.418292 -187.452831) (xy 32.360399 -187.437318)
			(xy 32.305026 -187.414382) (xy 32.25312 -187.384415) (xy 32.20557 -187.347928) (xy 32.16319 -187.305548)
			(xy 32.126703 -187.257998) (xy 32.096736 -187.206092) (xy 32.0738 -187.150719) (xy 32.058287 -187.092826)
			(xy 32.050464 -187.033404) (xy 23.812537 -187.033404) (xy 23.831006 -187.041054) (xy 23.882912 -187.071021)
			(xy 23.930462 -187.107508) (xy 23.972842 -187.149888) (xy 24.009329 -187.197438) (xy 24.039296 -187.249344)
			(xy 24.062232 -187.304717) (xy 24.077745 -187.36261) (xy 24.085568 -187.422032) (xy 24.086058 -187.452)
			(xy 24.085568 -187.481968) (xy 24.077745 -187.54139) (xy 24.062232 -187.599283) (xy 24.039296 -187.654656)
			(xy 24.009329 -187.706562) (xy 23.972842 -187.754112) (xy 23.930462 -187.796492) (xy 23.882912 -187.832979)
			(xy 23.831006 -187.862946) (xy 23.775633 -187.885882) (xy 23.71774 -187.901395) (xy 23.658318 -187.909218)
			(xy 23.598382 -187.909218) (xy 23.53896 -187.901395) (xy 23.481067 -187.885882) (xy 23.425694 -187.862946)
			(xy 23.373788 -187.832979) (xy 23.326238 -187.796492) (xy 23.283858 -187.754112) (xy 23.247371 -187.706562)
			(xy 23.217404 -187.654656) (xy 23.194468 -187.599283) (xy 23.178955 -187.54139) (xy 23.171132 -187.481968)
			(xy 4.825316 -187.481968) (xy 4.815311 -187.499298) (xy 4.778824 -187.546848) (xy 4.736444 -187.589228)
			(xy 4.688894 -187.625715) (xy 4.636988 -187.655682) (xy 4.581615 -187.678618) (xy 4.523722 -187.694131)
			(xy 4.4643 -187.701954) (xy 4.404364 -187.701954) (xy 4.344942 -187.694131) (xy 4.287049 -187.678618)
			(xy 4.231676 -187.655682) (xy 4.17977 -187.625715) (xy 4.13222 -187.589228) (xy 4.08984 -187.546848)
			(xy 4.053353 -187.499298) (xy 4.023386 -187.447392) (xy 4.00045 -187.392019) (xy 3.984937 -187.334126)
			(xy 3.977114 -187.274704) (xy 3.531108 -187.274704) (xy 3.531108 -188.116968) (xy 14.43023 -188.116968)
			(xy 14.43023 -188.057032) (xy 14.438053 -187.99761) (xy 14.453566 -187.939717) (xy 14.476502 -187.884344)
			(xy 14.506469 -187.832438) (xy 14.542956 -187.784888) (xy 14.585336 -187.742508) (xy 14.632886 -187.706021)
			(xy 14.684792 -187.676054) (xy 14.740165 -187.653118) (xy 14.798058 -187.637605) (xy 14.85748 -187.629782)
			(xy 14.917416 -187.629782) (xy 14.976838 -187.637605) (xy 15.034731 -187.653118) (xy 15.090104 -187.676054)
			(xy 15.14201 -187.706021) (xy 15.18956 -187.742508) (xy 15.23194 -187.784888) (xy 15.268427 -187.832438)
			(xy 15.298394 -187.884344) (xy 15.32133 -187.939717) (xy 15.325063 -187.95365) (xy 19.931632 -187.95365)
			(xy 19.935703 -187.898028) (xy 19.947829 -187.843591) (xy 19.967752 -187.7915) (xy 19.995048 -187.742865)
			(xy 20.029134 -187.698722) (xy 20.069283 -187.660013) (xy 20.114641 -187.627562) (xy 20.164241 -187.602061)
			(xy 20.217025 -187.584054) (xy 20.271868 -187.573924) (xy 20.327602 -187.571887) (xy 20.383039 -187.577987)
			(xy 20.436996 -187.592093) (xy 20.488325 -187.613905) (xy 20.535931 -187.642959) (xy 20.578799 -187.678634)
			(xy 20.616016 -187.720171) (xy 20.646789 -187.766684) (xy 20.670461 -187.817181) (xy 20.686529 -187.870588)
			(xy 20.694649 -187.925764) (xy 20.695158 -187.95365) (xy 20.694649 -187.981536) (xy 20.686529 -188.036712)
			(xy 20.670461 -188.090119) (xy 20.646789 -188.140616) (xy 20.616016 -188.187129) (xy 20.578799 -188.228666)
			(xy 20.535931 -188.264341) (xy 20.488325 -188.293395) (xy 20.436996 -188.315207) (xy 20.383039 -188.329313)
			(xy 20.327602 -188.335413) (xy 20.271868 -188.333376) (xy 20.217025 -188.323246) (xy 20.164241 -188.305239)
			(xy 20.114641 -188.279738) (xy 20.069283 -188.247287) (xy 20.029134 -188.208578) (xy 19.995048 -188.164435)
			(xy 19.967752 -188.1158) (xy 19.947829 -188.063709) (xy 19.935703 -188.009272) (xy 19.931632 -187.95365)
			(xy 15.325063 -187.95365) (xy 15.336843 -187.99761) (xy 15.344666 -188.057032) (xy 15.345156 -188.087)
			(xy 15.344666 -188.116968) (xy 15.336843 -188.17639) (xy 15.32133 -188.234283) (xy 15.298394 -188.289656)
			(xy 15.268427 -188.341562) (xy 15.245863 -188.370968) (xy 28.71646 -188.370968) (xy 28.71646 -188.311032)
			(xy 28.724283 -188.25161) (xy 28.739796 -188.193717) (xy 28.762732 -188.138344) (xy 28.792699 -188.086438)
			(xy 28.829186 -188.038888) (xy 28.871566 -187.996508) (xy 28.919116 -187.960021) (xy 28.971022 -187.930054)
			(xy 29.026395 -187.907118) (xy 29.084288 -187.891605) (xy 29.14371 -187.883782) (xy 29.203646 -187.883782)
			(xy 29.263068 -187.891605) (xy 29.320961 -187.907118) (xy 29.376334 -187.930054) (xy 29.428204 -187.96)
			(xy 45.712632 -187.96) (xy 45.716703 -187.904378) (xy 45.728829 -187.849941) (xy 45.748752 -187.79785)
			(xy 45.776048 -187.749215) (xy 45.810134 -187.705072) (xy 45.850283 -187.666363) (xy 45.895641 -187.633912)
			(xy 45.945241 -187.608411) (xy 45.998025 -187.590404) (xy 46.052868 -187.580274) (xy 46.108602 -187.578237)
			(xy 46.164039 -187.584337) (xy 46.217996 -187.598443) (xy 46.269325 -187.620255) (xy 46.316931 -187.649309)
			(xy 46.359799 -187.684984) (xy 46.397016 -187.726521) (xy 46.427789 -187.773034) (xy 46.451461 -187.823531)
			(xy 46.467529 -187.876938) (xy 46.475649 -187.932114) (xy 46.476158 -187.96) (xy 46.475649 -187.987886)
			(xy 46.467529 -188.043062) (xy 46.451461 -188.096469) (xy 46.427789 -188.146966) (xy 46.397016 -188.193479)
			(xy 46.359799 -188.235016) (xy 46.316931 -188.270691) (xy 46.269325 -188.299745) (xy 46.217996 -188.321557)
			(xy 46.164039 -188.335663) (xy 46.108602 -188.341763) (xy 46.052868 -188.339726) (xy 45.998025 -188.329596)
			(xy 45.945241 -188.311589) (xy 45.895641 -188.286088) (xy 45.850283 -188.253637) (xy 45.810134 -188.214928)
			(xy 45.776048 -188.170785) (xy 45.748752 -188.12215) (xy 45.728829 -188.070059) (xy 45.716703 -188.015622)
			(xy 45.712632 -187.96) (xy 29.428204 -187.96) (xy 29.42824 -187.960021) (xy 29.47579 -187.996508)
			(xy 29.51817 -188.038888) (xy 29.554657 -188.086438) (xy 29.584624 -188.138344) (xy 29.60756 -188.193717)
			(xy 29.623073 -188.25161) (xy 29.630896 -188.311032) (xy 29.631386 -188.341) (xy 29.630896 -188.370968)
			(xy 29.623073 -188.43039) (xy 29.612995 -188.468) (xy 34.288982 -188.468) (xy 34.293053 -188.412378)
			(xy 34.305179 -188.357941) (xy 34.325102 -188.30585) (xy 34.352398 -188.257215) (xy 34.386484 -188.213072)
			(xy 34.426633 -188.174363) (xy 34.471991 -188.141912) (xy 34.521591 -188.116411) (xy 34.574375 -188.098404)
			(xy 34.629218 -188.088274) (xy 34.684952 -188.086237) (xy 34.740389 -188.092337) (xy 34.794346 -188.106443)
			(xy 34.845675 -188.128255) (xy 34.893281 -188.157309) (xy 34.936149 -188.192984) (xy 34.973366 -188.234521)
			(xy 35.004139 -188.281034) (xy 35.027811 -188.331531) (xy 35.043879 -188.384938) (xy 35.051999 -188.440114)
			(xy 35.052508 -188.468) (xy 35.051999 -188.495886) (xy 35.043879 -188.551062) (xy 35.027811 -188.604469)
			(xy 35.004139 -188.654966) (xy 34.973366 -188.701479) (xy 34.936149 -188.743016) (xy 34.893281 -188.778691)
			(xy 34.845675 -188.807745) (xy 34.794346 -188.829557) (xy 34.740389 -188.843663) (xy 34.684952 -188.849763)
			(xy 34.629218 -188.847726) (xy 34.574375 -188.837596) (xy 34.521591 -188.819589) (xy 34.471991 -188.794088)
			(xy 34.426633 -188.761637) (xy 34.386484 -188.722928) (xy 34.352398 -188.678785) (xy 34.325102 -188.63015)
			(xy 34.305179 -188.578059) (xy 34.293053 -188.523622) (xy 34.288982 -188.468) (xy 29.612995 -188.468)
			(xy 29.60756 -188.488283) (xy 29.584624 -188.543656) (xy 29.554657 -188.595562) (xy 29.51817 -188.643112)
			(xy 29.47579 -188.685492) (xy 29.42824 -188.721979) (xy 29.376334 -188.751946) (xy 29.320961 -188.774882)
			(xy 29.263068 -188.790395) (xy 29.203646 -188.798218) (xy 29.14371 -188.798218) (xy 29.084288 -188.790395)
			(xy 29.026395 -188.774882) (xy 28.971022 -188.751946) (xy 28.919116 -188.721979) (xy 28.871566 -188.685492)
			(xy 28.829186 -188.643112) (xy 28.792699 -188.595562) (xy 28.762732 -188.543656) (xy 28.739796 -188.488283)
			(xy 28.724283 -188.43039) (xy 28.71646 -188.370968) (xy 15.245863 -188.370968) (xy 15.23194 -188.389112)
			(xy 15.18956 -188.431492) (xy 15.14201 -188.467979) (xy 15.090104 -188.497946) (xy 15.034731 -188.520882)
			(xy 14.976838 -188.536395) (xy 14.917416 -188.544218) (xy 14.85748 -188.544218) (xy 14.798058 -188.536395)
			(xy 14.740165 -188.520882) (xy 14.684792 -188.497946) (xy 14.632886 -188.467979) (xy 14.585336 -188.431492)
			(xy 14.542956 -188.389112) (xy 14.506469 -188.341562) (xy 14.476502 -188.289656) (xy 14.453566 -188.234283)
			(xy 14.438053 -188.17639) (xy 14.43023 -188.116968) (xy 3.531108 -188.116968) (xy 3.531108 -188.838586)
			(xy 3.532124 -188.848746) (xy 3.535172 -188.863732) (xy 3.53568 -188.864748) (xy 3.53695 -188.867542)
			(xy 3.539877 -188.872733) (xy 3.5477 -188.881716) (xy 3.552444 -188.885322) (xy 3.619246 -188.933074)
			(xy 3.624072 -188.936122) (xy 3.633716 -188.940921) (xy 3.655159 -188.942779) (xy 3.665474 -188.939678)
			(xy 3.665728 -188.939678) (xy 3.701495 -188.928316) (xy 3.775528 -188.916061) (xy 3.813048 -188.915294)
			(xy 3.820414 -188.915294) (xy 3.850067 -188.916238) (xy 3.908769 -188.924844) (xy 3.965866 -188.940964)
			(xy 4.020402 -188.964327) (xy 4.071461 -188.994541) (xy 4.118188 -189.0311) (xy 4.159799 -189.07339)
			(xy 4.195596 -189.120703) (xy 4.224979 -189.172246) (xy 4.247455 -189.227153) (xy 4.262647 -189.284504)
			(xy 4.270301 -189.343337) (xy 4.270756 -189.373002) (xy 4.270266 -189.40297) (xy 4.262442 -189.462392)
			(xy 4.24693 -189.520284) (xy 4.223994 -189.575657) (xy 4.194026 -189.627562) (xy 4.157539 -189.675112)
			(xy 4.115159 -189.717492) (xy 4.067609 -189.753978) (xy 4.015704 -189.783945) (xy 3.960331 -189.806881)
			(xy 3.902438 -189.822393) (xy 3.843016 -189.830216) (xy 3.813048 -189.83071) (xy 3.812794 -189.83071)
			(xy 3.776214 -189.830018) (xy 3.703982 -189.81841) (xy 3.66903 -189.807596) (xy 3.66141 -189.805564)
			(xy 3.64871 -189.803532) (xy 3.64236 -189.80404) (xy 3.6361 -189.804957) (xy 3.624281 -189.809458)
			(xy 3.618992 -189.81293) (xy 3.55219 -189.860936) (xy 3.548888 -189.863476) (xy 3.544771 -189.867181)
			(xy 3.538102 -189.876021) (xy 3.53568 -189.881002) (xy 3.53441 -189.883796) (xy 3.532847 -189.888204)
			(xy 3.531181 -189.897407) (xy 3.531108 -189.902084) (xy 3.531108 -190.597028) (xy 3.532124 -190.607188)
			(xy 3.533593 -190.613463) (xy 3.539244 -190.62504) (xy 3.5433 -190.630048) (xy 3.543554 -190.630302)
			(xy 3.550158 -190.637922) (xy 3.556762 -190.644526) (xy 3.565144 -190.648082) (xy 3.56983 -190.649886)
			(xy 3.579682 -190.651816) (xy 3.584702 -190.651892) (xy 4.289298 -190.651892) (xy 4.29895 -190.650876)
			(xy 4.306194 -190.649249) (xy 4.319364 -190.642409) (xy 4.324858 -190.637414) (xy 4.580636 -190.381636)
			(xy 4.61554 -190.347384) (xy 4.689901 -190.283858) (xy 4.769017 -190.226362) (xy 4.852402 -190.175252)
			(xy 4.939539 -190.130843) (xy 5.029893 -190.093409) (xy 5.122905 -190.063179) (xy 5.218003 -190.040342)
			(xy 5.3146 -190.025037) (xy 5.412099 -190.01736) (xy 5.461 -190.016892) (xy 14.29258 -190.016892)
			(xy 14.341481 -190.017359) (xy 14.438982 -190.025033) (xy 14.53558 -190.040334) (xy 14.630679 -190.063169)
			(xy 14.723693 -190.093397) (xy 14.814048 -190.130831) (xy 14.901186 -190.17524) (xy 14.984571 -190.22635)
			(xy 15.063688 -190.283847) (xy 15.138048 -190.347375) (xy 15.172944 -190.381636) (xy 15.390622 -190.599314)
			(xy 15.396121 -190.604301) (xy 15.409288 -190.611144) (xy 15.41653 -190.612776) (xy 15.426182 -190.613792)
			(xy 19.025616 -190.613792) (xy 19.037488 -190.613105) (xy 19.058682 -190.602384) (xy 19.066256 -190.593218)
			(xy 19.118834 -190.522606) (xy 19.122136 -190.518288) (xy 19.125438 -190.500762) (xy 19.124676 -190.488824)
			(xy 19.122898 -190.482982) (xy 19.115297 -190.456124) (xy 19.107134 -190.400908) (xy 19.106642 -190.373)
			(xy 19.107114 -190.34636) (xy 19.114542 -190.293602) (xy 19.12924 -190.24239) (xy 19.150922 -190.193722)
			(xy 19.179166 -190.148545) (xy 19.213421 -190.107738) (xy 19.23288 -190.089536) (xy 19.237198 -190.085472)
			(xy 19.243802 -190.076328) (xy 19.245834 -190.070994) (xy 19.247856 -190.065578) (xy 19.249658 -190.054162)
			(xy 19.24939 -190.048388) (xy 19.24685 -190.015876) (xy 19.243294 -189.96787) (xy 19.24271 -189.961908)
			(xy 19.239127 -189.95048) (xy 19.236182 -189.945264) (xy 19.230594 -189.935866) (xy 19.220688 -189.929262)
			(xy 19.198498 -189.914044) (xy 19.158223 -189.878366) (xy 19.123359 -189.837385) (xy 19.094597 -189.791912)
			(xy 19.072507 -189.74285) (xy 19.057528 -189.691172) (xy 19.049956 -189.637903) (xy 19.049492 -189.611)
			(xy 19.049978 -189.583749) (xy 19.057734 -189.529801) (xy 19.073089 -189.477506) (xy 19.095731 -189.427929)
			(xy 19.125197 -189.382079) (xy 19.160888 -189.340888) (xy 19.202079 -189.305197) (xy 19.247929 -189.275731)
			(xy 19.297506 -189.253089) (xy 19.349801 -189.237734) (xy 19.403749 -189.229978) (xy 19.458251 -189.229978)
			(xy 19.458404 -189.23) (xy 23.239982 -189.23) (xy 23.244053 -189.174378) (xy 23.256179 -189.119941)
			(xy 23.276102 -189.06785) (xy 23.303398 -189.019215) (xy 23.337484 -188.975072) (xy 23.377633 -188.936363)
			(xy 23.422991 -188.903912) (xy 23.472591 -188.878411) (xy 23.525375 -188.860404) (xy 23.580218 -188.850274)
			(xy 23.635952 -188.848237) (xy 23.691389 -188.854337) (xy 23.745346 -188.868443) (xy 23.770114 -188.878968)
			(xy 43.103782 -188.878968) (xy 43.103782 -188.819032) (xy 43.111605 -188.75961) (xy 43.127118 -188.701717)
			(xy 43.150054 -188.646344) (xy 43.180021 -188.594438) (xy 43.216508 -188.546888) (xy 43.258888 -188.504508)
			(xy 43.306438 -188.468021) (xy 43.358344 -188.438054) (xy 43.413717 -188.415118) (xy 43.47161 -188.399605)
			(xy 43.531032 -188.391782) (xy 43.590968 -188.391782) (xy 43.65039 -188.399605) (xy 43.708283 -188.415118)
			(xy 43.763656 -188.438054) (xy 43.815562 -188.468021) (xy 43.863112 -188.504508) (xy 43.905492 -188.546888)
			(xy 43.941979 -188.594438) (xy 43.971946 -188.646344) (xy 43.994882 -188.701717) (xy 44.010395 -188.75961)
			(xy 44.018218 -188.819032) (xy 44.018708 -188.849) (xy 44.018218 -188.878968) (xy 44.010395 -188.93839)
			(xy 43.994882 -188.996283) (xy 43.971946 -189.051656) (xy 43.941979 -189.103562) (xy 43.905492 -189.151112)
			(xy 43.863112 -189.193492) (xy 43.815562 -189.229979) (xy 43.763656 -189.259946) (xy 43.708283 -189.282882)
			(xy 43.65039 -189.298395) (xy 43.590968 -189.306218) (xy 43.531032 -189.306218) (xy 43.47161 -189.298395)
			(xy 43.413717 -189.282882) (xy 43.358344 -189.259946) (xy 43.306438 -189.229979) (xy 43.258888 -189.193492)
			(xy 43.216508 -189.151112) (xy 43.180021 -189.103562) (xy 43.150054 -189.051656) (xy 43.127118 -188.996283)
			(xy 43.111605 -188.93839) (xy 43.103782 -188.878968) (xy 23.770114 -188.878968) (xy 23.796675 -188.890255)
			(xy 23.844281 -188.919309) (xy 23.887149 -188.954984) (xy 23.924366 -188.996521) (xy 23.955139 -189.043034)
			(xy 23.978811 -189.093531) (xy 23.994879 -189.146938) (xy 24.002999 -189.202114) (xy 24.003508 -189.23)
			(xy 24.002999 -189.257886) (xy 23.994879 -189.313062) (xy 23.978811 -189.366469) (xy 23.955139 -189.416966)
			(xy 23.924366 -189.463479) (xy 23.887149 -189.505016) (xy 23.844281 -189.540691) (xy 23.796675 -189.569745)
			(xy 23.745346 -189.591557) (xy 23.691389 -189.605663) (xy 23.635952 -189.611763) (xy 23.580218 -189.609726)
			(xy 23.525375 -189.599596) (xy 23.472591 -189.581589) (xy 23.422991 -189.556088) (xy 23.377633 -189.523637)
			(xy 23.337484 -189.484928) (xy 23.303398 -189.440785) (xy 23.276102 -189.39215) (xy 23.256179 -189.340059)
			(xy 23.244053 -189.285622) (xy 23.239982 -189.23) (xy 19.458404 -189.23) (xy 19.512199 -189.237734)
			(xy 19.564494 -189.253089) (xy 19.614071 -189.275731) (xy 19.659921 -189.305197) (xy 19.701112 -189.340888)
			(xy 19.736803 -189.382079) (xy 19.766269 -189.427929) (xy 19.788911 -189.477506) (xy 19.804266 -189.529801)
			(xy 19.812022 -189.583749) (xy 19.812508 -189.611) (xy 19.812037 -189.63764) (xy 19.804609 -189.6904)
			(xy 19.789913 -189.741613) (xy 19.778173 -189.767968) (xy 45.637432 -189.767968) (xy 45.637432 -189.708032)
			(xy 45.645255 -189.64861) (xy 45.660768 -189.590717) (xy 45.683704 -189.535344) (xy 45.713671 -189.483438)
			(xy 45.750158 -189.435888) (xy 45.792538 -189.393508) (xy 45.840088 -189.357021) (xy 45.891994 -189.327054)
			(xy 45.947367 -189.304118) (xy 46.00526 -189.288605) (xy 46.064682 -189.280782) (xy 46.124618 -189.280782)
			(xy 46.18404 -189.288605) (xy 46.241933 -189.304118) (xy 46.297306 -189.327054) (xy 46.349212 -189.357021)
			(xy 46.396762 -189.393508) (xy 46.439142 -189.435888) (xy 46.475629 -189.483438) (xy 46.505596 -189.535344)
			(xy 46.528532 -189.590717) (xy 46.544045 -189.64861) (xy 46.551868 -189.708032) (xy 46.552358 -189.738)
			(xy 46.551868 -189.767968) (xy 46.544045 -189.82739) (xy 46.528532 -189.885283) (xy 46.505596 -189.940656)
			(xy 46.475629 -189.992562) (xy 46.439142 -190.040112) (xy 46.396762 -190.082492) (xy 46.349212 -190.118979)
			(xy 46.297306 -190.148946) (xy 46.241933 -190.171882) (xy 46.18404 -190.187395) (xy 46.124618 -190.195218)
			(xy 46.064682 -190.195218) (xy 46.00526 -190.187395) (xy 45.947367 -190.171882) (xy 45.891994 -190.148946)
			(xy 45.840088 -190.118979) (xy 45.792538 -190.082492) (xy 45.750158 -190.040112) (xy 45.713671 -189.992562)
			(xy 45.683704 -189.940656) (xy 45.660768 -189.885283) (xy 45.645255 -189.82739) (xy 45.637432 -189.767968)
			(xy 19.778173 -189.767968) (xy 19.768233 -189.790283) (xy 19.739992 -189.835462) (xy 19.705739 -189.876273)
			(xy 19.68627 -189.894464) (xy 19.681952 -189.898528) (xy 19.675348 -189.907672) (xy 19.673316 -189.913006)
			(xy 19.671296 -189.918422) (xy 19.669495 -189.929838) (xy 19.66976 -189.935612) (xy 19.6723 -189.968124)
			(xy 19.675856 -190.01613) (xy 19.676441 -190.022092) (xy 19.680027 -190.033518) (xy 19.682968 -190.038736)
			(xy 19.688556 -190.048134) (xy 19.698462 -190.054738) (xy 19.720649 -190.069958) (xy 19.760919 -190.105638)
			(xy 19.795779 -190.146621) (xy 19.824537 -190.192093) (xy 19.846624 -190.241154) (xy 19.861601 -190.292831)
			(xy 19.864078 -190.310262) (xy 30.488126 -190.310262) (xy 30.492197 -190.25464) (xy 30.504323 -190.200203)
			(xy 30.524246 -190.148112) (xy 30.551542 -190.099477) (xy 30.585628 -190.055334) (xy 30.625777 -190.016625)
			(xy 30.671135 -189.984174) (xy 30.720735 -189.958673) (xy 30.773519 -189.940666) (xy 30.828362 -189.930536)
			(xy 30.884096 -189.928499) (xy 30.939533 -189.934599) (xy 30.99349 -189.948705) (xy 31.044819 -189.970517)
			(xy 31.092425 -189.999571) (xy 31.135293 -190.035246) (xy 31.17251 -190.076783) (xy 31.203283 -190.123296)
			(xy 31.226955 -190.173793) (xy 31.243023 -190.2272) (xy 31.251143 -190.282376) (xy 31.251652 -190.310262)
			(xy 31.251143 -190.338148) (xy 31.249939 -190.346326) (xy 31.38219 -190.346326) (xy 31.38219 -190.28639)
			(xy 31.390013 -190.226968) (xy 31.405526 -190.169075) (xy 31.428462 -190.113702) (xy 31.458429 -190.061796)
			(xy 31.494916 -190.014246) (xy 31.537296 -189.971866) (xy 31.584846 -189.935379) (xy 31.636752 -189.905412)
			(xy 31.692125 -189.882476) (xy 31.750018 -189.866963) (xy 31.80944 -189.85914) (xy 31.869376 -189.85914)
			(xy 31.928798 -189.866963) (xy 31.986691 -189.882476) (xy 32.042064 -189.905412) (xy 32.09397 -189.935379)
			(xy 32.14152 -189.971866) (xy 32.1839 -190.014246) (xy 32.220387 -190.061796) (xy 32.250354 -190.113702)
			(xy 32.27329 -190.169075) (xy 32.288803 -190.226968) (xy 32.296626 -190.28639) (xy 32.297116 -190.316358)
			(xy 32.296626 -190.346326) (xy 32.288803 -190.405748) (xy 32.27329 -190.463641) (xy 32.250354 -190.519014)
			(xy 32.220387 -190.57092) (xy 32.1839 -190.61847) (xy 32.14152 -190.66085) (xy 32.09397 -190.697337)
			(xy 32.042064 -190.727304) (xy 31.986691 -190.75024) (xy 31.928798 -190.765753) (xy 31.869376 -190.773576)
			(xy 31.80944 -190.773576) (xy 31.750018 -190.765753) (xy 31.692125 -190.75024) (xy 31.636752 -190.727304)
			(xy 31.584846 -190.697337) (xy 31.537296 -190.66085) (xy 31.494916 -190.61847) (xy 31.458429 -190.57092)
			(xy 31.428462 -190.519014) (xy 31.405526 -190.463641) (xy 31.390013 -190.405748) (xy 31.38219 -190.346326)
			(xy 31.249939 -190.346326) (xy 31.243023 -190.393324) (xy 31.226955 -190.446731) (xy 31.203283 -190.497228)
			(xy 31.17251 -190.543741) (xy 31.135293 -190.585278) (xy 31.092425 -190.620953) (xy 31.044819 -190.650007)
			(xy 30.99349 -190.671819) (xy 30.939533 -190.685925) (xy 30.884096 -190.692025) (xy 30.828362 -190.689988)
			(xy 30.773519 -190.679858) (xy 30.720735 -190.661851) (xy 30.671135 -190.63635) (xy 30.625777 -190.603899)
			(xy 30.585628 -190.56519) (xy 30.551542 -190.521047) (xy 30.524246 -190.472412) (xy 30.504323 -190.420321)
			(xy 30.492197 -190.365884) (xy 30.488126 -190.310262) (xy 19.864078 -190.310262) (xy 19.869172 -190.346099)
			(xy 19.869658 -190.373) (xy 19.869129 -190.400905) (xy 19.860969 -190.456117) (xy 19.853402 -190.482982)
			(xy 19.851624 -190.488824) (xy 19.850862 -190.500762) (xy 19.854164 -190.518288) (xy 19.857466 -190.522606)
			(xy 19.910044 -190.593218) (xy 19.917603 -190.602409) (xy 19.938802 -190.613154) (xy 19.950684 -190.613792)
			(xy 20.409154 -190.613792) (xy 20.456271 -190.61425) (xy 20.550234 -190.621398) (xy 20.643387 -190.635625)
			(xy 20.7352 -190.656851) (xy 20.825146 -190.684954) (xy 20.912711 -190.719774) (xy 20.955254 -190.74003)
			(xy 20.960334 -190.74257) (xy 20.976844 -190.746634) (xy 20.988782 -190.747904) (xy 24.07539 -190.747904)
			(xy 24.085461 -190.748326) (xy 24.104068 -190.756038) (xy 24.111458 -190.76289) (xy 24.229568 -190.881)
			(xy 43.305982 -190.881) (xy 43.310053 -190.825378) (xy 43.322179 -190.770941) (xy 43.342102 -190.71885)
			(xy 43.369398 -190.670215) (xy 43.403484 -190.626072) (xy 43.443633 -190.587363) (xy 43.488991 -190.554912)
			(xy 43.538591 -190.529411) (xy 43.591375 -190.511404) (xy 43.646218 -190.501274) (xy 43.701952 -190.499237)
			(xy 43.757389 -190.505337) (xy 43.811346 -190.519443) (xy 43.862675 -190.541255) (xy 43.910281 -190.570309)
			(xy 43.953149 -190.605984) (xy 43.990366 -190.647521) (xy 44.021139 -190.694034) (xy 44.044811 -190.744531)
			(xy 44.060879 -190.797938) (xy 44.068999 -190.853114) (xy 44.069508 -190.881) (xy 44.068999 -190.908886)
			(xy 44.060879 -190.964062) (xy 44.044811 -191.017469) (xy 44.021139 -191.067966) (xy 43.990366 -191.114479)
			(xy 43.953149 -191.156016) (xy 43.910281 -191.191691) (xy 43.862675 -191.220745) (xy 43.811346 -191.242557)
			(xy 43.757389 -191.256663) (xy 43.701952 -191.262763) (xy 43.646218 -191.260726) (xy 43.591375 -191.250596)
			(xy 43.538591 -191.232589) (xy 43.488991 -191.207088) (xy 43.443633 -191.174637) (xy 43.403484 -191.135928)
			(xy 43.369398 -191.091785) (xy 43.342102 -191.04315) (xy 43.322179 -190.991059) (xy 43.310053 -190.936622)
			(xy 43.305982 -190.881) (xy 24.229568 -190.881) (xy 25.10409 -191.755522) (xy 25.109588 -191.760512)
			(xy 25.122753 -191.767362) (xy 25.129998 -191.768984) (xy 25.13965 -191.77) (xy 38.29177 -191.77)
			(xy 38.300152 -191.766952) (xy 38.325269 -191.758326) (xy 38.377222 -191.747316) (xy 38.4302 -191.743622)
			(xy 38.483178 -191.747316) (xy 38.535131 -191.758326) (xy 38.560248 -191.766952) (xy 38.56863 -191.77)
			(xy 38.586918 -191.77) (xy 38.596987 -191.770427) (xy 38.615586 -191.778146) (xy 38.622986 -191.784986)
			(xy 38.65626 -191.81826) (xy 38.659054 -191.820546) (xy 38.680403 -191.837152) (xy 38.718648 -191.875397)
			(xy 38.735254 -191.896746) (xy 38.73754 -191.89954) (xy 38.989 -192.151) (xy 42.055032 -192.151)
			(xy 42.059103 -192.095378) (xy 42.071229 -192.040941) (xy 42.091152 -191.98885) (xy 42.118448 -191.940215)
			(xy 42.152534 -191.896072) (xy 42.192683 -191.857363) (xy 42.238041 -191.824912) (xy 42.287641 -191.799411)
			(xy 42.340425 -191.781404) (xy 42.395268 -191.771274) (xy 42.451002 -191.769237) (xy 42.506439 -191.775337)
			(xy 42.560396 -191.789443) (xy 42.611725 -191.811255) (xy 42.659331 -191.840309) (xy 42.702199 -191.875984)
			(xy 42.739416 -191.917521) (xy 42.770189 -191.964034) (xy 42.793861 -192.014531) (xy 42.809929 -192.067938)
			(xy 42.818049 -192.123114) (xy 42.818558 -192.151) (xy 42.818049 -192.178886) (xy 42.809929 -192.234062)
			(xy 42.793861 -192.287469) (xy 42.770189 -192.337966) (xy 42.739416 -192.384479) (xy 42.702199 -192.426016)
			(xy 42.659331 -192.461691) (xy 42.611725 -192.490745) (xy 42.560396 -192.512557) (xy 42.506439 -192.526663)
			(xy 42.451002 -192.532763) (xy 42.395268 -192.530726) (xy 42.340425 -192.520596) (xy 42.287641 -192.502589)
			(xy 42.238041 -192.477088) (xy 42.192683 -192.444637) (xy 42.152534 -192.405928) (xy 42.118448 -192.361785)
			(xy 42.091152 -192.31315) (xy 42.071229 -192.261059) (xy 42.059103 -192.206622) (xy 42.055032 -192.151)
			(xy 38.989 -192.151) (xy 39.863522 -193.025522) (xy 39.869021 -193.030509) (xy 39.882188 -193.037351)
			(xy 39.88943 -193.038984) (xy 39.899082 -193.04) (xy 49.041558 -193.04)
		)
		(stroke
			(width 0)
			(type solid)
		)
		(fill yes)
		(layer "B.Cu")
		(net "P3V3_AUX")
	)
	(gr_poly
		(pts
			(xy -3.999992 -336.492088) (xy -3.944185 -336.491566) (xy -3.832883 -336.483225) (xy -3.722516 -336.46659)
			(xy -3.6137 -336.441753) (xy -3.507045 -336.408854) (xy -3.403146 -336.368077) (xy -3.302586 -336.31965)
			(xy -3.205925 -336.263842) (xy -3.113705 -336.200968) (xy -3.026442 -336.131378) (xy -2.944623 -336.055461)
			(xy -2.868706 -335.973642) (xy -2.799116 -335.886379) (xy -2.736242 -335.794159) (xy -2.680434 -335.697498)
			(xy -2.632007 -335.596938) (xy -2.59123 -335.493039) (xy -2.558331 -335.386384) (xy -2.533494 -335.277568)
			(xy -2.516859 -335.167201) (xy -2.508518 -335.055899) (xy -2.507996 -335.000092) (xy -2.507996 -154.399996)
			(xy -2.508518 -154.344189) (xy -2.516859 -154.232887) (xy -2.533494 -154.12252) (xy -2.558331 -154.013704)
			(xy -2.59123 -153.907049) (xy -2.632007 -153.80315) (xy -2.680434 -153.70259) (xy -2.736242 -153.605929)
			(xy -2.799116 -153.513709) (xy -2.868706 -153.426446) (xy -2.944623 -153.344627) (xy -3.026442 -153.26871)
			(xy -3.113705 -153.19912) (xy -3.205925 -153.136246) (xy -3.302586 -153.080438) (xy -3.403146 -153.032011)
			(xy -3.507045 -152.991234) (xy -3.6137 -152.958335) (xy -3.722516 -152.933498) (xy -3.832883 -152.916863)
			(xy -3.944185 -152.908522) (xy -3.999992 -152.908) (xy -17.78 -152.908) (xy -17.835807 -152.908522)
			(xy -17.947109 -152.916863) (xy -18.057476 -152.933498) (xy -18.166292 -152.958335) (xy -18.272947 -152.991234)
			(xy -18.376846 -153.032011) (xy -18.477406 -153.080438) (xy -18.574067 -153.136246) (xy -18.666287 -153.19912)
			(xy -18.75355 -153.26871) (xy -18.835369 -153.344627) (xy -18.911286 -153.426446) (xy -18.980876 -153.513709)
			(xy -19.04375 -153.605929) (xy -19.099558 -153.70259) (xy -19.147985 -153.80315) (xy -19.188762 -153.907049)
			(xy -19.221661 -154.013704) (xy -19.246498 -154.12252) (xy -19.263133 -154.232887) (xy -19.271474 -154.344189)
			(xy -19.271996 -154.399996) (xy -19.271996 -157.46456) (xy -16.875771 -157.46456) (xy -16.875771 -157.33542)
			(xy -16.867821 -157.206525) (xy -16.851951 -157.078365) (xy -16.828222 -156.951424) (xy -16.796723 -156.826185)
			(xy -16.757574 -156.703122) (xy -16.710923 -156.582703) (xy -16.656948 -156.465384) (xy -16.595853 -156.35161)
			(xy -16.52787 -156.241813) (xy -16.453256 -156.13641) (xy -16.372295 -156.0358) (xy -16.285295 -155.940365)
			(xy -16.192584 -155.850466) (xy -16.094514 -155.766445) (xy -15.991459 -155.688621) (xy -15.883808 -155.617289)
			(xy -15.771969 -155.552719) (xy -15.656368 -155.495157) (xy -15.537443 -155.44482) (xy -15.415644 -155.4019)
			(xy -15.291434 -155.366559) (xy -15.165285 -155.338932) (xy -15.037673 -155.319123) (xy -14.909084 -155.307207)
			(xy -14.780006 -155.303231) (xy -14.650928 -155.307207) (xy -14.522339 -155.319123) (xy -14.394727 -155.338932)
			(xy -14.268578 -155.366559) (xy -14.144368 -155.4019) (xy -14.022569 -155.44482) (xy -13.903644 -155.495157)
			(xy -13.788043 -155.552719) (xy -13.676204 -155.617289) (xy -13.568553 -155.688621) (xy -13.465498 -155.766445)
			(xy -13.367428 -155.850466) (xy -13.274717 -155.940365) (xy -13.187717 -156.0358) (xy -13.106756 -156.13641)
			(xy -13.032142 -156.241813) (xy -12.964159 -156.35161) (xy -12.903064 -156.465384) (xy -12.849089 -156.582703)
			(xy -12.802438 -156.703122) (xy -12.763289 -156.826185) (xy -12.73179 -156.951424) (xy -12.708061 -157.078365)
			(xy -12.692191 -157.206525) (xy -12.684241 -157.33542) (xy -12.683744 -157.39999) (xy -12.684241 -157.46456)
			(xy -12.692191 -157.593455) (xy -12.708061 -157.721615) (xy -12.73179 -157.848556) (xy -12.763289 -157.973795)
			(xy -12.802438 -158.096858) (xy -12.849089 -158.217277) (xy -12.903064 -158.334596) (xy -12.964159 -158.44837)
			(xy -13.032142 -158.558167) (xy -13.106756 -158.66357) (xy -13.187717 -158.76418) (xy -13.274717 -158.859615)
			(xy -13.367428 -158.949514) (xy -13.465498 -159.033535) (xy -13.568553 -159.111359) (xy -13.676204 -159.182691)
			(xy -13.788043 -159.247261) (xy -13.903644 -159.304823) (xy -14.022569 -159.35516) (xy -14.144368 -159.39808)
			(xy -14.268578 -159.433421) (xy -14.394727 -159.461048) (xy -14.522339 -159.480857) (xy -14.650928 -159.492773)
			(xy -14.780006 -159.49675) (xy -14.909084 -159.492773) (xy -15.037673 -159.480857) (xy -15.165285 -159.461048)
			(xy -15.291434 -159.433421) (xy -15.415644 -159.39808) (xy -15.537443 -159.35516) (xy -15.656368 -159.304823)
			(xy -15.771969 -159.247261) (xy -15.883808 -159.182691) (xy -15.991459 -159.111359) (xy -16.094514 -159.033535)
			(xy -16.192584 -158.949514) (xy -16.285295 -158.859615) (xy -16.372295 -158.76418) (xy -16.453256 -158.66357)
			(xy -16.52787 -158.558167) (xy -16.595853 -158.44837) (xy -16.656948 -158.334596) (xy -16.710923 -158.217277)
			(xy -16.757574 -158.096858) (xy -16.796723 -157.973795) (xy -16.828222 -157.848556) (xy -16.851951 -157.721615)
			(xy -16.867821 -157.593455) (xy -16.875771 -157.46456) (xy -19.271996 -157.46456) (xy -19.271996 -332.064668)
			(xy -16.875771 -332.064668) (xy -16.875771 -331.935528) (xy -16.867821 -331.806633) (xy -16.851951 -331.678473)
			(xy -16.828222 -331.551532) (xy -16.796723 -331.426293) (xy -16.757574 -331.30323) (xy -16.710923 -331.182811)
			(xy -16.656948 -331.065492) (xy -16.595853 -330.951718) (xy -16.52787 -330.841921) (xy -16.453256 -330.736518)
			(xy -16.372295 -330.635908) (xy -16.285295 -330.540473) (xy -16.192584 -330.450574) (xy -16.094514 -330.366553)
			(xy -15.991459 -330.288729) (xy -15.883808 -330.217397) (xy -15.771969 -330.152827) (xy -15.656368 -330.095265)
			(xy -15.537443 -330.044928) (xy -15.415644 -330.002008) (xy -15.291434 -329.966667) (xy -15.165285 -329.93904)
			(xy -15.037673 -329.919231) (xy -14.909084 -329.907315) (xy -14.780006 -329.903339) (xy -14.650928 -329.907315)
			(xy -14.522339 -329.919231) (xy -14.394727 -329.93904) (xy -14.268578 -329.966667) (xy -14.144368 -330.002008)
			(xy -14.022569 -330.044928) (xy -13.903644 -330.095265) (xy -13.788043 -330.152827) (xy -13.676204 -330.217397)
			(xy -13.568553 -330.288729) (xy -13.465498 -330.366553) (xy -13.367428 -330.450574) (xy -13.274717 -330.540473)
			(xy -13.187717 -330.635908) (xy -13.106756 -330.736518) (xy -13.032142 -330.841921) (xy -12.964159 -330.951718)
			(xy -12.903064 -331.065492) (xy -12.849089 -331.182811) (xy -12.802438 -331.30323) (xy -12.763289 -331.426293)
			(xy -12.73179 -331.551532) (xy -12.708061 -331.678473) (xy -12.692191 -331.806633) (xy -12.684241 -331.935528)
			(xy -12.683744 -332.000098) (xy -12.684241 -332.064668) (xy -12.692191 -332.193563) (xy -12.708061 -332.321723)
			(xy -12.73179 -332.448664) (xy -12.763289 -332.573903) (xy -12.802438 -332.696966) (xy -12.849089 -332.817385)
			(xy -12.903064 -332.934704) (xy -12.964159 -333.048478) (xy -13.032142 -333.158275) (xy -13.106756 -333.263678)
			(xy -13.187717 -333.364288) (xy -13.274717 -333.459723) (xy -13.367428 -333.549622) (xy -13.465498 -333.633643)
			(xy -13.568553 -333.711467) (xy -13.676204 -333.782799) (xy -13.788043 -333.847369) (xy -13.903644 -333.904931)
			(xy -14.022569 -333.955268) (xy -14.144368 -333.998188) (xy -14.268578 -334.033529) (xy -14.394727 -334.061156)
			(xy -14.522339 -334.080965) (xy -14.650928 -334.092881) (xy -14.780006 -334.096858) (xy -14.909084 -334.092881)
			(xy -15.037673 -334.080965) (xy -15.165285 -334.061156) (xy -15.291434 -334.033529) (xy -15.415644 -333.998188)
			(xy -15.537443 -333.955268) (xy -15.656368 -333.904931) (xy -15.771969 -333.847369) (xy -15.883808 -333.782799)
			(xy -15.991459 -333.711467) (xy -16.094514 -333.633643) (xy -16.192584 -333.549622) (xy -16.285295 -333.459723)
			(xy -16.372295 -333.364288) (xy -16.453256 -333.263678) (xy -16.52787 -333.158275) (xy -16.595853 -333.048478)
			(xy -16.656948 -332.934704) (xy -16.710923 -332.817385) (xy -16.757574 -332.696966) (xy -16.796723 -332.573903)
			(xy -16.828222 -332.448664) (xy -16.851951 -332.321723) (xy -16.867821 -332.193563) (xy -16.875771 -332.064668)
			(xy -19.271996 -332.064668) (xy -19.271996 -335.000092) (xy -19.271474 -335.055899) (xy -19.263133 -335.167201)
			(xy -19.246498 -335.277568) (xy -19.221661 -335.386384) (xy -19.188762 -335.493039) (xy -19.147985 -335.596938)
			(xy -19.099558 -335.697498) (xy -19.04375 -335.794159) (xy -18.980876 -335.886379) (xy -18.911286 -335.973642)
			(xy -18.835369 -336.055461) (xy -18.75355 -336.131378) (xy -18.666287 -336.200968) (xy -18.574067 -336.263842)
			(xy -18.477406 -336.31965) (xy -18.376846 -336.368077) (xy -18.272947 -336.408854) (xy -18.166292 -336.441753)
			(xy -18.057476 -336.46659) (xy -17.947109 -336.483225) (xy -17.835807 -336.491566) (xy -17.78 -336.492088)
		)
		(stroke
			(width 0)
			(type solid)
		)
		(fill yes)
		(layer "In1.Cu")
		(net "GND2")
	)
	(gr_poly
		(pts
			(xy 47.69993 -336.491072) (xy 47.783018 -336.490577) (xy 47.949007 -336.482669) (xy 48.114431 -336.466871)
			(xy 48.278917 -336.44322) (xy 48.44209 -336.41177) (xy 48.603583 -336.372591) (xy 48.763028 -336.325772)
			(xy 48.920065 -336.27142) (xy 49.074338 -336.209657) (xy 49.225497 -336.140624) (xy 49.373201 -336.064476)
			(xy 49.517114 -335.981387) (xy 49.65691 -335.891544) (xy 49.792273 -335.795151) (xy 49.922897 -335.692427)
			(xy 50.048484 -335.583603) (xy 50.168752 -335.468928) (xy 50.283426 -335.348659) (xy 50.392248 -335.223071)
			(xy 50.494972 -335.092446) (xy 50.591363 -334.957082) (xy 50.681205 -334.817285) (xy 50.764293 -334.673371)
			(xy 50.840439 -334.525667) (xy 50.909471 -334.374507) (xy 50.971232 -334.220233) (xy 51.025583 -334.063196)
			(xy 51.0724 -333.90375) (xy 51.111577 -333.742257) (xy 51.143026 -333.579083) (xy 51.166675 -333.414598)
			(xy 51.182471 -333.249173) (xy 51.190378 -333.083184) (xy 51.190906 -333.000096) (xy 51.190906 -3.999992)
			(xy 51.190412 -3.916903) (xy 51.182504 -3.750913) (xy 51.166708 -3.585487) (xy 51.143058 -3.421001)
			(xy 51.111608 -3.257825) (xy 51.07243 -3.096332) (xy 51.025612 -2.936885) (xy 50.971261 -2.779846)
			(xy 50.909499 -2.625572) (xy 50.840466 -2.474411) (xy 50.764319 -2.326706) (xy 50.68123 -2.182791)
			(xy 50.591387 -2.042993) (xy 50.494995 -1.907628) (xy 50.39227 -1.777003) (xy 50.283447 -1.651413)
			(xy 50.168771 -1.531144) (xy 50.048503 -1.416468) (xy 49.922914 -1.307644) (xy 49.79229 -1.204919)
			(xy 49.656925 -1.108525) (xy 49.517128 -1.018682) (xy 49.373214 -0.935592) (xy 49.225509 -0.859444)
			(xy 49.074349 -0.79041) (xy 48.920074 -0.728647) (xy 48.763036 -0.674294) (xy 48.60359 -0.627476)
			(xy 48.442096 -0.588297) (xy 48.278921 -0.556846) (xy 48.114435 -0.533195) (xy 47.949009 -0.517397)
			(xy 47.783019 -0.509489) (xy 47.69993 -0.509016) (xy 36.971986 -0.509016) (xy 36.961917 -0.509442)
			(xy 36.943318 -0.517162) (xy 36.935918 -0.524002) (xy 35.763962 -1.695958) (xy 35.757118 -1.703357)
			(xy 35.749395 -1.721956) (xy 35.748976 -1.732026) (xy 35.748976 -4.50957) (xy 43.243235 -4.50957)
			(xy 43.243235 -4.38043) (xy 43.251185 -4.251535) (xy 43.267055 -4.123375) (xy 43.290784 -3.996434)
			(xy 43.322283 -3.871195) (xy 43.361432 -3.748132) (xy 43.408083 -3.627713) (xy 43.462058 -3.510394)
			(xy 43.523153 -3.39662) (xy 43.591136 -3.286823) (xy 43.66575 -3.18142) (xy 43.746711 -3.08081) (xy 43.833711 -2.985375)
			(xy 43.926422 -2.895476) (xy 44.024492 -2.811455) (xy 44.127547 -2.733631) (xy 44.235198 -2.662299)
			(xy 44.347037 -2.597729) (xy 44.462638 -2.540167) (xy 44.581563 -2.48983) (xy 44.703362 -2.44691)
			(xy 44.827572 -2.411569) (xy 44.953721 -2.383942) (xy 45.081333 -2.364133) (xy 45.209922 -2.352217)
			(xy 45.339 -2.348241) (xy 45.468078 -2.352217) (xy 45.596667 -2.364133) (xy 45.724279 -2.383942)
			(xy 45.850428 -2.411569) (xy 45.974638 -2.44691) (xy 46.096437 -2.48983) (xy 46.215362 -2.540167)
			(xy 46.330963 -2.597729) (xy 46.442802 -2.662299) (xy 46.550453 -2.733631) (xy 46.653508 -2.811455)
			(xy 46.751578 -2.895476) (xy 46.844289 -2.985375) (xy 46.931289 -3.08081) (xy 47.01225 -3.18142)
			(xy 47.086864 -3.286823) (xy 47.154847 -3.39662) (xy 47.215942 -3.510394) (xy 47.269917 -3.627713)
			(xy 47.316568 -3.748132) (xy 47.355717 -3.871195) (xy 47.387216 -3.996434) (xy 47.410945 -4.123375)
			(xy 47.426815 -4.251535) (xy 47.434765 -4.38043) (xy 47.435262 -4.445) (xy 47.434765 -4.50957) (xy 47.426815 -4.638465)
			(xy 47.410945 -4.766625) (xy 47.387216 -4.893566) (xy 47.355717 -5.018805) (xy 47.316568 -5.141868)
			(xy 47.269917 -5.262287) (xy 47.215942 -5.379606) (xy 47.154847 -5.49338) (xy 47.086864 -5.603177)
			(xy 47.01225 -5.70858) (xy 46.931289 -5.80919) (xy 46.844289 -5.904625) (xy 46.751578 -5.994524)
			(xy 46.653508 -6.078545) (xy 46.550453 -6.156369) (xy 46.442802 -6.227701) (xy 46.330963 -6.292271)
			(xy 46.215362 -6.349833) (xy 46.096437 -6.40017) (xy 45.974638 -6.44309) (xy 45.850428 -6.478431)
			(xy 45.724279 -6.506058) (xy 45.596667 -6.525867) (xy 45.468078 -6.537783) (xy 45.339 -6.54176) (xy 45.209922 -6.537783)
			(xy 45.081333 -6.525867) (xy 44.953721 -6.506058) (xy 44.827572 -6.478431) (xy 44.703362 -6.44309)
			(xy 44.581563 -6.40017) (xy 44.462638 -6.349833) (xy 44.347037 -6.292271) (xy 44.235198 -6.227701)
			(xy 44.127547 -6.156369) (xy 44.024492 -6.078545) (xy 43.926422 -5.994524) (xy 43.833711 -5.904625)
			(xy 43.746711 -5.80919) (xy 43.66575 -5.70858) (xy 43.591136 -5.603177) (xy 43.523153 -5.49338) (xy 43.462058 -5.379606)
			(xy 43.408083 -5.262287) (xy 43.361432 -5.141868) (xy 43.322283 -5.018805) (xy 43.290784 -4.893566)
			(xy 43.267055 -4.766625) (xy 43.251185 -4.638465) (xy 43.243235 -4.50957) (xy 35.748976 -4.50957)
			(xy 35.748976 -10.999978) (xy 35.748474 -11.058341) (xy 35.7405 -11.174794) (xy 35.724598 -11.290431)
			(xy 35.700842 -11.404713) (xy 35.669343 -11.517108) (xy 35.630247 -11.627092) (xy 35.583738 -11.734151)
			(xy 35.530031 -11.837787) (xy 35.469378 -11.937517) (xy 35.40206 -12.032875) (xy 35.328392 -12.123417)
			(xy 35.248718 -12.208721) (xy 35.163408 -12.28839) (xy 35.07286 -12.362051) (xy 34.977497 -12.429361)
			(xy 34.877763 -12.490008) (xy 34.774123 -12.543707) (xy 34.66706 -12.590208) (xy 34.557073 -12.629295)
			(xy 34.444676 -12.660786) (xy 34.330392 -12.684533) (xy 34.214753 -12.700427) (xy 34.0983 -12.708392)
			(xy 33.981574 -12.708392) (xy 33.865121 -12.700427) (xy 33.749482 -12.684533) (xy 33.635198 -12.660786)
			(xy 33.522801 -12.629295) (xy 33.412814 -12.590208) (xy 33.305751 -12.543707) (xy 33.202111 -12.490008)
			(xy 33.102377 -12.429361) (xy 33.007014 -12.362051) (xy 32.916466 -12.28839) (xy 32.831156 -12.208721)
			(xy 32.751482 -12.123417) (xy 32.677814 -12.032875) (xy 32.610496 -11.937517) (xy 32.549843 -11.837787)
			(xy 32.496136 -11.734151) (xy 32.449627 -11.627092) (xy 32.410531 -11.517108) (xy 32.379032 -11.404713)
			(xy 32.355276 -11.290431) (xy 32.339374 -11.174794) (xy 32.3314 -11.058341) (xy 32.330898 -10.999978)
			(xy 32.330898 -8.20039) (xy 32.330408 -8.190384) (xy 32.322747 -8.171896) (xy 32.308594 -8.157747)
			(xy 32.290104 -8.15009) (xy 32.280098 -8.14959) (xy 28.029916 -8.14959) (xy 28.019892 -8.150007)
			(xy 28.001368 -8.157673) (xy 27.987188 -8.171846) (xy 27.979512 -8.190366) (xy 27.979116 -8.20039)
			(xy 27.979116 -9.148826) (xy 27.979678 -9.160453) (xy 27.989853 -9.181364) (xy 27.998674 -9.188958)
			(xy 28.071572 -9.2456) (xy 28.094432 -9.250426) (xy 28.105862 -9.247378) (xy 28.141979 -9.238548)
			(xy 28.215307 -9.226221) (xy 28.289409 -9.22006) (xy 28.326588 -9.219692) (xy 28.372984 -9.220276)
			(xy 28.465275 -9.229908) (xy 28.55606 -9.2491) (xy 28.644353 -9.277643) (xy 28.687014 -9.295892)
			(xy 28.696956 -9.299698) (xy 28.71822 -9.299698) (xy 28.728162 -9.295892) (xy 28.770827 -9.277654)
			(xy 28.85912 -9.249114) (xy 28.949904 -9.229917) (xy 29.042192 -9.220271) (xy 29.088588 -9.219692)
			(xy 29.129692 -9.220152) (xy 29.211548 -9.227736) (xy 29.292355 -9.24284) (xy 29.371425 -9.265336)
			(xy 29.448081 -9.295032) (xy 29.52167 -9.331674) (xy 29.591564 -9.37495) (xy 29.657167 -9.42449)
			(xy 29.717919 -9.479872) (xy 29.773302 -9.540624) (xy 29.822843 -9.606226) (xy 29.86612 -9.67612)
			(xy 29.902763 -9.749708) (xy 29.93246 -9.826364) (xy 29.954957 -9.905433) (xy 29.970063 -9.98624)
			(xy 29.977648 -10.068096) (xy 29.978096 -10.1092) (xy 29.977694 -10.147483) (xy 29.971139 -10.223769)
			(xy 29.958059 -10.29921) (xy 29.938551 -10.373249) (xy 29.926026 -10.409428) (xy 29.923376 -10.417865)
			(xy 29.923376 -10.435535) (xy 29.926026 -10.443972) (xy 29.938561 -10.480148) (xy 29.958088 -10.554185)
			(xy 29.97117 -10.629627) (xy 29.977709 -10.705916) (xy 29.978096 -10.7442) (xy 29.977694 -10.782483)
			(xy 29.971139 -10.858769) (xy 29.958059 -10.93421) (xy 29.938551 -11.008249) (xy 29.926026 -11.044428)
			(xy 29.923376 -11.052865) (xy 29.923376 -11.070535) (xy 29.926026 -11.078972) (xy 29.938561 -11.115148)
			(xy 29.958088 -11.189185) (xy 29.97117 -11.264627) (xy 29.977709 -11.340916) (xy 29.978096 -11.3792)
			(xy 29.977694 -11.417483) (xy 29.971139 -11.493769) (xy 29.958059 -11.56921) (xy 29.938551 -11.643249)
			(xy 29.926026 -11.679428) (xy 29.923376 -11.687865) (xy 29.923376 -11.705535) (xy 29.926026 -11.713972)
			(xy 29.938561 -11.750148) (xy 29.958088 -11.824185) (xy 29.97117 -11.899627) (xy 29.977709 -11.975916)
			(xy 29.978096 -12.0142) (xy 29.977694 -12.052483) (xy 29.971139 -12.128769) (xy 29.958059 -12.20421)
			(xy 29.938551 -12.278249) (xy 29.926026 -12.314428) (xy 29.923376 -12.322865) (xy 29.923376 -12.340535)
			(xy 29.926026 -12.348972) (xy 29.938561 -12.385148) (xy 29.958088 -12.459185) (xy 29.97117 -12.534627)
			(xy 29.977709 -12.610916) (xy 29.978096 -12.6492) (xy 29.977694 -12.687483) (xy 29.971139 -12.763769)
			(xy 29.958059 -12.83921) (xy 29.938551 -12.913249) (xy 29.926026 -12.949428) (xy 29.923376 -12.957865)
			(xy 29.923376 -12.975535) (xy 29.926026 -12.983972) (xy 29.938561 -13.020148) (xy 29.958088 -13.094185)
			(xy 29.97117 -13.169627) (xy 29.977709 -13.245916) (xy 29.978096 -13.2842) (xy 29.977636 -13.325303)
			(xy 29.970051 -13.407158) (xy 29.954945 -13.487964) (xy 29.932448 -13.567032) (xy 29.902752 -13.643687)
			(xy 29.866109 -13.717274) (xy 29.822833 -13.787167) (xy 29.773293 -13.852768) (xy 29.717911 -13.913519)
			(xy 29.657159 -13.9689) (xy 29.591557 -14.01844) (xy 29.521664 -14.061715) (xy 29.448076 -14.098357)
			(xy 29.371421 -14.128052) (xy 29.292353 -14.150548) (xy 29.211546 -14.165652) (xy 29.129691 -14.173236)
			(xy 29.088588 -14.173708) (xy 29.042192 -14.173123) (xy 28.949902 -14.163488) (xy 28.859118 -14.144294)
			(xy 28.770826 -14.115749) (xy 28.728162 -14.097508) (xy 28.71822 -14.093702) (xy 28.696956 -14.093702)
			(xy 28.687014 -14.097508) (xy 28.644349 -14.115745) (xy 28.556055 -14.144282) (xy 28.465272 -14.163477)
			(xy 28.372983 -14.173121) (xy 28.326588 -14.173708) (xy 28.285486 -14.173233) (xy 28.203632 -14.165647)
			(xy 28.122828 -14.150541) (xy 28.043762 -14.128044) (xy 27.967109 -14.098347) (xy 27.893523 -14.061705)
			(xy 27.823632 -14.01843) (xy 27.758032 -13.96889) (xy 27.697283 -13.913509) (xy 27.641902 -13.852759)
			(xy 27.592364 -13.787158) (xy 27.549089 -13.717266) (xy 27.512448 -13.64368) (xy 27.482752 -13.567027)
			(xy 27.460256 -13.48796) (xy 27.445151 -13.407156) (xy 27.437567 -13.325302) (xy 27.43708 -13.2842)
			(xy 27.437482 -13.245917) (xy 27.444037 -13.169631) (xy 27.457117 -13.09419) (xy 27.476624 -13.02015)
			(xy 27.48915 -12.983972) (xy 27.491801 -12.975535) (xy 27.491801 -12.957865) (xy 27.48915 -12.949428)
			(xy 27.476615 -12.913252) (xy 27.457089 -12.839215) (xy 27.444007 -12.763773) (xy 27.437468 -12.687484)
			(xy 27.43708 -12.6492) (xy 27.437482 -12.610917) (xy 27.444037 -12.534631) (xy 27.457117 -12.45919)
			(xy 27.476624 -12.38515) (xy 27.48915 -12.348972) (xy 27.491801 -12.340535) (xy 27.491801 -12.322865)
			(xy 27.48915 -12.314428) (xy 27.476615 -12.278252) (xy 27.457089 -12.204215) (xy 27.444007 -12.128773)
			(xy 27.437468 -12.052484) (xy 27.43708 -12.0142) (xy 27.437162 -11.996528) (xy 27.438561 -11.961211)
			(xy 27.439874 -11.943588) (xy 27.440636 -11.931142) (xy 27.431492 -11.909044) (xy 27.35072 -11.839448)
			(xy 27.327352 -11.833606) (xy 27.315414 -11.8364) (xy 27.267275 -11.846965) (xy 27.169368 -11.858292)
			(xy 27.120088 -11.859006) (xy 27.077912 -11.858505) (xy 26.993966 -11.850235) (xy 26.911236 -11.833778)
			(xy 26.830516 -11.80929) (xy 26.752586 -11.777009) (xy 26.678195 -11.737245) (xy 26.608059 -11.69038)
			(xy 26.542856 -11.636866) (xy 26.483211 -11.577219) (xy 26.4297 -11.512013) (xy 26.382838 -11.441876)
			(xy 26.343076 -11.367484) (xy 26.310798 -11.289552) (xy 26.286314 -11.208831) (xy 26.26986 -11.1261)
			(xy 26.261594 -11.042154) (xy 26.26106 -10.999978) (xy 26.26106 -8.20039) (xy 26.260638 -8.190373)
			(xy 26.252965 -8.171866) (xy 26.238792 -8.157707) (xy 26.220277 -8.150052) (xy 26.21026 -8.14959)
			(xy 19.419824 -8.14959) (xy 19.409799 -8.150005) (xy 19.391272 -8.157671) (xy 19.37709 -8.171843)
			(xy 19.369412 -8.190365) (xy 19.369024 -8.20039) (xy 19.369024 -10.999978) (xy 19.368522 -11.058341)
			(xy 19.360548 -11.174794) (xy 19.344646 -11.290431) (xy 19.32089 -11.404713) (xy 19.289391 -11.517108)
			(xy 19.250295 -11.627092) (xy 19.203786 -11.734151) (xy 19.150079 -11.837787) (xy 19.089426 -11.937517)
			(xy 19.022108 -12.032875) (xy 18.94844 -12.123417) (xy 18.868766 -12.208721) (xy 18.783456 -12.28839)
			(xy 18.692908 -12.362051) (xy 18.597545 -12.429361) (xy 18.497811 -12.490008) (xy 18.394171 -12.543707)
			(xy 18.287108 -12.590208) (xy 18.177121 -12.629295) (xy 18.064724 -12.660786) (xy 17.95044 -12.684533)
			(xy 17.834801 -12.700427) (xy 17.718348 -12.708392) (xy 17.601622 -12.708392) (xy 17.485169 -12.700427)
			(xy 17.36953 -12.684533) (xy 17.255246 -12.660786) (xy 17.142849 -12.629295) (xy 17.032862 -12.590208)
			(xy 16.925799 -12.543707) (xy 16.822159 -12.490008) (xy 16.722425 -12.429361) (xy 16.627062 -12.362051)
			(xy 16.536514 -12.28839) (xy 16.451204 -12.208721) (xy 16.37153 -12.123417) (xy 16.297862 -12.032875)
			(xy 16.230544 -11.937517) (xy 16.169891 -11.837787) (xy 16.116184 -11.734151) (xy 16.069675 -11.627092)
			(xy 16.030579 -11.517108) (xy 15.99908 -11.404713) (xy 15.975324 -11.290431) (xy 15.959422 -11.174794)
			(xy 15.951448 -11.058341) (xy 15.950946 -10.999978) (xy 15.950946 -1.732026) (xy 15.950508 -1.721963)
			(xy 15.942769 -1.703383) (xy 15.93596 -1.695958) (xy 14.764004 -0.524002) (xy 14.756606 -0.517155)
			(xy 14.738008 -0.509418) (xy 14.727936 -0.509016) (xy 3.999992 -0.509016) (xy 3.916903 -0.509503)
			(xy 3.750913 -0.51741) (xy 3.585487 -0.533206) (xy 3.421 -0.556855) (xy 3.257825 -0.588305) (xy 3.096331 -0.627483)
			(xy 2.936884 -0.674301) (xy 2.779845 -0.728652) (xy 2.625571 -0.790414) (xy 2.474409 -0.859447) (xy 2.326704 -0.935595)
			(xy 2.18279 -1.018684) (xy 2.042992 -1.108526) (xy 1.907627 -1.204919) (xy 1.777002 -1.307644) (xy 1.651413 -1.416467)
			(xy 1.531144 -1.531144) (xy 1.416467 -1.651413) (xy 1.307644 -1.777002) (xy 1.204919 -1.907627) (xy 1.108526 -2.042992)
			(xy 1.018684 -2.18279) (xy 0.935595 -2.326704) (xy 0.859447 -2.474409) (xy 0.790414 -2.625571) (xy 0.728652 -2.779845)
			(xy 0.674301 -2.936884) (xy 0.627483 -3.096331) (xy 0.588305 -3.257825) (xy 0.556855 -3.421) (xy 0.533206 -3.585487)
			(xy 0.51741 -3.750913) (xy 0.509503 -3.916903) (xy 0.509016 -3.999992) (xy 0.509016 -4.50957) (xy 9.080235 -4.50957)
			(xy 9.080235 -4.38043) (xy 9.088185 -4.251535) (xy 9.104055 -4.123375) (xy 9.127784 -3.996434) (xy 9.159283 -3.871195)
			(xy 9.198432 -3.748132) (xy 9.245083 -3.627713) (xy 9.299058 -3.510394) (xy 9.360153 -3.39662) (xy 9.428136 -3.286823)
			(xy 9.50275 -3.18142) (xy 9.583711 -3.08081) (xy 9.670711 -2.985375) (xy 9.763422 -2.895476) (xy 9.861492 -2.811455)
			(xy 9.964547 -2.733631) (xy 10.072198 -2.662299) (xy 10.184037 -2.597729) (xy 10.299638 -2.540167)
			(xy 10.418563 -2.48983) (xy 10.540362 -2.44691) (xy 10.664572 -2.411569) (xy 10.790721 -2.383942)
			(xy 10.918333 -2.364133) (xy 11.046922 -2.352217) (xy 11.176 -2.348241) (xy 11.305078 -2.352217)
			(xy 11.433667 -2.364133) (xy 11.561279 -2.383942) (xy 11.687428 -2.411569) (xy 11.811638 -2.44691)
			(xy 11.933437 -2.48983) (xy 12.052362 -2.540167) (xy 12.167963 -2.597729) (xy 12.279802 -2.662299)
			(xy 12.387453 -2.733631) (xy 12.490508 -2.811455) (xy 12.588578 -2.895476) (xy 12.681289 -2.985375)
			(xy 12.768289 -3.08081) (xy 12.84925 -3.18142) (xy 12.923864 -3.286823) (xy 12.991847 -3.39662) (xy 13.052942 -3.510394)
			(xy 13.106917 -3.627713) (xy 13.153568 -3.748132) (xy 13.192717 -3.871195) (xy 13.224216 -3.996434)
			(xy 13.247945 -4.123375) (xy 13.263815 -4.251535) (xy 13.271765 -4.38043) (xy 13.272262 -4.445) (xy 13.271765 -4.50957)
			(xy 13.263815 -4.638465) (xy 13.247945 -4.766625) (xy 13.224216 -4.893566) (xy 13.192717 -5.018805)
			(xy 13.153568 -5.141868) (xy 13.106917 -5.262287) (xy 13.052942 -5.379606) (xy 12.991847 -5.49338)
			(xy 12.923864 -5.603177) (xy 12.84925 -5.70858) (xy 12.768289 -5.80919) (xy 12.681289 -5.904625)
			(xy 12.588578 -5.994524) (xy 12.490508 -6.078545) (xy 12.387453 -6.156369) (xy 12.279802 -6.227701)
			(xy 12.167963 -6.292271) (xy 12.052362 -6.349833) (xy 11.933437 -6.40017) (xy 11.811638 -6.44309)
			(xy 11.687428 -6.478431) (xy 11.561279 -6.506058) (xy 11.433667 -6.525867) (xy 11.305078 -6.537783)
			(xy 11.176 -6.54176) (xy 11.046922 -6.537783) (xy 10.918333 -6.525867) (xy 10.790721 -6.506058) (xy 10.664572 -6.478431)
			(xy 10.540362 -6.44309) (xy 10.418563 -6.40017) (xy 10.299638 -6.349833) (xy 10.184037 -6.292271)
			(xy 10.072198 -6.227701) (xy 9.964547 -6.156369) (xy 9.861492 -6.078545) (xy 9.763422 -5.994524)
			(xy 9.670711 -5.904625) (xy 9.583711 -5.80919) (xy 9.50275 -5.70858) (xy 9.428136 -5.603177) (xy 9.360153 -5.49338)
			(xy 9.299058 -5.379606) (xy 9.245083 -5.262287) (xy 9.198432 -5.141868) (xy 9.159283 -5.018805) (xy 9.127784 -4.893566)
			(xy 9.104055 -4.766625) (xy 9.088185 -4.638465) (xy 9.080235 -4.50957) (xy 0.509016 -4.50957) (xy 0.509016 -11.218361)
			(xy 1.015742 -11.218361) (xy 1.015742 -11.133639) (xy 1.023795 -11.049302) (xy 1.039829 -10.966112)
			(xy 1.063697 -10.884822) (xy 1.095185 -10.80617) (xy 1.134007 -10.730867) (xy 1.17981 -10.659595)
			(xy 1.232181 -10.592999) (xy 1.290646 -10.531684) (xy 1.354674 -10.476203) (xy 1.423686 -10.42706)
			(xy 1.497056 -10.3847) (xy 1.574121 -10.349505) (xy 1.654183 -10.321796) (xy 1.736516 -10.301822)
			(xy 1.820375 -10.289765) (xy 1.905 -10.285734) (xy 1.989625 -10.289765) (xy 2.073484 -10.301822)
			(xy 2.155817 -10.321796) (xy 2.235879 -10.349505) (xy 2.312944 -10.3847) (xy 2.386314 -10.42706)
			(xy 2.455326 -10.476203) (xy 2.494343 -10.510012) (xy 6.441451 -10.510012) (xy 6.445429 -10.410019)
			(xy 6.457339 -10.310659) (xy 6.477106 -10.212558) (xy 6.504605 -10.116339) (xy 6.539661 -10.022608)
			(xy 6.582053 -9.931959) (xy 6.631514 -9.844965) (xy 6.68773 -9.762175) (xy 6.750346 -9.684113) (xy 6.818965 -9.611273)
			(xy 6.893156 -9.544115) (xy 6.972447 -9.483063) (xy 7.056338 -9.428505) (xy 7.144299 -9.380784) (xy 7.235773 -9.340202)
			(xy 7.330182 -9.307016) (xy 7.426929 -9.281436) (xy 7.525403 -9.263623) (xy 7.624981 -9.253691) (xy 7.725033 -9.251701)
			(xy 7.824927 -9.257667) (xy 7.924031 -9.271551) (xy 8.021719 -9.293264) (xy 8.117373 -9.32267) (xy 8.210388 -9.359583)
			(xy 8.300176 -9.403769) (xy 8.38617 -9.45495) (xy 8.467826 -9.5128) (xy 8.544627 -9.576956) (xy 8.616089 -9.64701)
			(xy 8.681759 -9.722521) (xy 8.741221 -9.803011) (xy 8.794101 -9.88797) (xy 8.840064 -9.976862) (xy 8.878819 -10.069125)
			(xy 8.910121 -10.164175) (xy 8.933773 -10.261412) (xy 8.949624 -10.360221) (xy 8.957574 -10.459976)
			(xy 8.958072 -10.510012) (xy 8.957574 -10.560048) (xy 8.949624 -10.659803) (xy 8.933773 -10.758612)
			(xy 8.910121 -10.855849) (xy 8.878819 -10.950899) (xy 8.840064 -11.043162) (xy 8.794101 -11.132054)
			(xy 8.741221 -11.217013) (xy 8.681759 -11.297503) (xy 8.616089 -11.373014) (xy 8.544627 -11.443068)
			(xy 8.467826 -11.507224) (xy 8.38617 -11.565074) (xy 8.300176 -11.616255) (xy 8.210388 -11.660441)
			(xy 8.117373 -11.697354) (xy 8.021719 -11.72676) (xy 7.924031 -11.748473) (xy 7.824927 -11.762357)
			(xy 7.725033 -11.768323) (xy 7.624981 -11.766333) (xy 7.525403 -11.756401) (xy 7.426929 -11.738588)
			(xy 7.330182 -11.713008) (xy 7.235773 -11.679822) (xy 7.144299 -11.63924) (xy 7.056338 -11.591519)
			(xy 6.972447 -11.536961) (xy 6.893156 -11.475909) (xy 6.818965 -11.408751) (xy 6.750346 -11.335911)
			(xy 6.68773 -11.257849) (xy 6.631514 -11.175059) (xy 6.582053 -11.088065) (xy 6.539661 -10.997416)
			(xy 6.504605 -10.903685) (xy 6.477106 -10.807466) (xy 6.457339 -10.709365) (xy 6.445429 -10.610005)
			(xy 6.441451 -10.510012) (xy 2.494343 -10.510012) (xy 2.519354 -10.531684) (xy 2.577819 -10.592999)
			(xy 2.63019 -10.659595) (xy 2.675993 -10.730867) (xy 2.714815 -10.80617) (xy 2.746303 -10.884822)
			(xy 2.770171 -10.966112) (xy 2.786205 -11.049302) (xy 2.794258 -11.133639) (xy 2.794762 -11.176)
			(xy 2.794258 -11.218361) (xy 2.786205 -11.302698) (xy 2.770171 -11.385888) (xy 2.746303 -11.467178)
			(xy 2.714815 -11.54583) (xy 2.675993 -11.621133) (xy 2.63019 -11.692405) (xy 2.577819 -11.759001)
			(xy 2.519354 -11.820316) (xy 2.455326 -11.875797) (xy 2.386314 -11.92494) (xy 2.312944 -11.9673)
			(xy 2.235879 -12.002495) (xy 2.155817 -12.030204) (xy 2.073484 -12.050178) (xy 1.989625 -12.062235)
			(xy 1.905 -12.066267) (xy 1.820375 -12.062235) (xy 1.736516 -12.050178) (xy 1.654183 -12.030204)
			(xy 1.574121 -12.002495) (xy 1.497056 -11.9673) (xy 1.423686 -11.92494) (xy 1.354674 -11.875797)
			(xy 1.290646 -11.820316) (xy 1.232181 -11.759001) (xy 1.17981 -11.692405) (xy 1.134007 -11.621133)
			(xy 1.095185 -11.54583) (xy 1.063697 -11.467178) (xy 1.039829 -11.385888) (xy 1.023795 -11.302698)
			(xy 1.015742 -11.218361) (xy 0.509016 -11.218361) (xy 0.509016 -15.155361) (xy 30.479742 -15.155361)
			(xy 30.479742 -15.070639) (xy 30.487795 -14.986302) (xy 30.503829 -14.903112) (xy 30.527697 -14.821822)
			(xy 30.559185 -14.74317) (xy 30.598007 -14.667867) (xy 30.64381 -14.596595) (xy 30.696181 -14.529999)
			(xy 30.754646 -14.468684) (xy 30.818674 -14.413203) (xy 30.887686 -14.36406) (xy 30.961056 -14.3217)
			(xy 31.038121 -14.286505) (xy 31.118183 -14.258796) (xy 31.200516 -14.238822) (xy 31.284375 -14.226765)
			(xy 31.369 -14.222734) (xy 31.453625 -14.226765) (xy 31.537484 -14.238822) (xy 31.619817 -14.258796)
			(xy 31.699879 -14.286505) (xy 31.776944 -14.3217) (xy 31.850314 -14.36406) (xy 31.919326 -14.413203)
			(xy 31.983354 -14.468684) (xy 32.041819 -14.529999) (xy 32.09419 -14.596595) (xy 32.139993 -14.667867)
			(xy 32.178815 -14.74317) (xy 32.210303 -14.821822) (xy 32.234171 -14.903112) (xy 32.250205 -14.986302)
			(xy 32.258258 -15.070639) (xy 32.258762 -15.113) (xy 32.258258 -15.155361) (xy 32.250205 -15.239698)
			(xy 32.250147 -15.24) (xy 34.036 -15.24) (xy 34.036407 -15.20171) (xy 34.043019 -15.125417) (xy 34.056169 -15.049975)
			(xy 34.075759 -14.975944) (xy 34.088324 -14.939772) (xy 34.090976 -14.931335) (xy 34.090976 -14.913665)
			(xy 34.088324 -14.905228) (xy 34.075746 -14.869061) (xy 34.05616 -14.795028) (xy 34.043015 -14.719584)
			(xy 34.03641 -14.64329) (xy 34.036 -14.605) (xy 34.036474 -14.563921) (xy 34.044055 -14.482113) (xy 34.059151 -14.401354)
			(xy 34.081635 -14.322332) (xy 34.111314 -14.245722) (xy 34.147935 -14.172177) (xy 34.191185 -14.102325)
			(xy 34.240697 -14.036762) (xy 34.296046 -13.976046) (xy 34.356762 -13.920697) (xy 34.422325 -13.871185)
			(xy 34.492177 -13.827935) (xy 34.565722 -13.791314) (xy 34.642332 -13.761635) (xy 34.721354 -13.739151)
			(xy 34.802113 -13.724055) (xy 34.883921 -13.716474) (xy 34.925 -13.716) (xy 34.96329 -13.716407)
			(xy 35.039583 -13.723019) (xy 35.115025 -13.736169) (xy 35.189056 -13.755759) (xy 35.225228 -13.768324)
			(xy 35.233665 -13.770975) (xy 35.251335 -13.770975) (xy 35.259772 -13.768324) (xy 35.308032 -13.752322)
			(xy 35.316056 -13.749639) (xy 35.329831 -13.739831) (xy 35.339639 -13.726056) (xy 35.342322 -13.718032)
			(xy 35.354371 -13.679091) (xy 35.384539 -13.603362) (xy 35.421514 -13.530711) (xy 35.464983 -13.461751)
			(xy 35.514583 -13.397059) (xy 35.569896 -13.337179) (xy 35.630458 -13.282614) (xy 35.695761 -13.233823)
			(xy 35.765257 -13.191213) (xy 35.838361 -13.155145) (xy 35.91446 -13.125919) (xy 35.992914 -13.103783)
			(xy 36.073066 -13.088921) (xy 36.154241 -13.081459) (xy 36.195 -13.081) (xy 36.23329 -13.081407)
			(xy 36.309583 -13.088019) (xy 36.385025 -13.101169) (xy 36.459056 -13.120759) (xy 36.495228 -13.133324)
			(xy 36.503665 -13.135975) (xy 36.521335 -13.135975) (xy 36.529772 -13.133324) (xy 36.565939 -13.120746)
			(xy 36.639972 -13.10116) (xy 36.715416 -13.088015) (xy 36.79171 -13.08141) (xy 36.83 -13.081) (xy 36.86829 -13.081407)
			(xy 36.944583 -13.088019) (xy 37.020025 -13.101169) (xy 37.094056 -13.120759) (xy 37.130228 -13.133324)
			(xy 37.138665 -13.135975) (xy 37.156335 -13.135975) (xy 37.164772 -13.133324) (xy 37.200939 -13.120746)
			(xy 37.274972 -13.10116) (xy 37.350416 -13.088015) (xy 37.42671 -13.08141) (xy 37.465 -13.081) (xy 37.506079 -13.081474)
			(xy 37.587887 -13.089055) (xy 37.668646 -13.104151) (xy 37.747668 -13.126635) (xy 37.824278 -13.156314)
			(xy 37.897823 -13.192935) (xy 37.967675 -13.236185) (xy 38.033238 -13.285697) (xy 38.093954 -13.341046)
			(xy 38.149303 -13.401762) (xy 38.198815 -13.467325) (xy 38.242065 -13.537177) (xy 38.278686 -13.610722)
			(xy 38.308365 -13.687332) (xy 38.330849 -13.766354) (xy 38.345945 -13.847113) (xy 38.353526 -13.928921)
			(xy 38.354 -13.97) (xy 38.353593 -14.00829) (xy 38.346981 -14.084583) (xy 38.333831 -14.160025) (xy 38.314241 -14.234056)
			(xy 38.301676 -14.270228) (xy 38.299024 -14.278665) (xy 38.299024 -14.296335) (xy 38.301676 -14.304772)
			(xy 38.314254 -14.340939) (xy 38.33384 -14.414972) (xy 38.346985 -14.490416) (xy 38.35359 -14.56671)
			(xy 38.354 -14.605) (xy 38.353593 -14.64329) (xy 38.346981 -14.719583) (xy 38.333831 -14.795025)
			(xy 38.314241 -14.869056) (xy 38.301676 -14.905228) (xy 38.299024 -14.913665) (xy 38.299024 -14.931335)
			(xy 38.301676 -14.939772) (xy 38.314254 -14.975939) (xy 38.33384 -15.049972) (xy 38.346985 -15.125416)
			(xy 38.35359 -15.20171) (xy 38.354 -15.24) (xy 38.353526 -15.281079) (xy 38.345945 -15.362887) (xy 38.330849 -15.443646)
			(xy 38.308365 -15.522668) (xy 38.278686 -15.599278) (xy 38.242065 -15.672823) (xy 38.198815 -15.742675)
			(xy 38.149303 -15.808238) (xy 38.093954 -15.868954) (xy 38.033238 -15.924303) (xy 37.967675 -15.973815)
			(xy 37.897823 -16.017065) (xy 37.824278 -16.053686) (xy 37.747668 -16.083365) (xy 37.668646 -16.105849)
			(xy 37.587887 -16.120945) (xy 37.506079 -16.128526) (xy 37.465 -16.129) (xy 37.42671 -16.128593)
			(xy 37.350417 -16.121981) (xy 37.274975 -16.108831) (xy 37.200944 -16.089241) (xy 37.164772 -16.076676)
			(xy 37.156335 -16.074025) (xy 37.138665 -16.074025) (xy 37.130228 -16.076676) (xy 37.094061 -16.089254)
			(xy 37.020028 -16.10884) (xy 36.944584 -16.121985) (xy 36.86829 -16.12859) (xy 36.83 -16.129) (xy 36.79171 -16.128593)
			(xy 36.715417 -16.121981) (xy 36.639975 -16.108831) (xy 36.565944 -16.089241) (xy 36.529772 -16.076676)
			(xy 36.521335 -16.074025) (xy 36.503665 -16.074025) (xy 36.495228 -16.076676) (xy 36.459061 -16.089254)
			(xy 36.385028 -16.10884) (xy 36.309584 -16.121985) (xy 36.23329 -16.12859) (xy 36.195 -16.129) (xy 36.15671 -16.128593)
			(xy 36.080417 -16.121981) (xy 36.004975 -16.108831) (xy 35.930944 -16.089241) (xy 35.894772 -16.076676)
			(xy 35.886335 -16.074025) (xy 35.868665 -16.074025) (xy 35.860228 -16.076676) (xy 35.824061 -16.089254)
			(xy 35.750028 -16.10884) (xy 35.674584 -16.121985) (xy 35.59829 -16.12859) (xy 35.56 -16.129) (xy 35.52171 -16.128593)
			(xy 35.445417 -16.121981) (xy 35.369975 -16.108831) (xy 35.295944 -16.089241) (xy 35.259772 -16.076676)
			(xy 35.251335 -16.074025) (xy 35.233665 -16.074025) (xy 35.225228 -16.076676) (xy 35.189061 -16.089254)
			(xy 35.115028 -16.10884) (xy 35.039584 -16.121985) (xy 34.96329 -16.12859) (xy 34.925 -16.129) (xy 34.883921 -16.128526)
			(xy 34.802113 -16.120945) (xy 34.721354 -16.105849) (xy 34.642332 -16.083365) (xy 34.565722 -16.053686)
			(xy 34.492177 -16.017065) (xy 34.422325 -15.973815) (xy 34.356762 -15.924303) (xy 34.296046 -15.868954)
			(xy 34.240697 -15.808238) (xy 34.191185 -15.742675) (xy 34.147935 -15.672823) (xy 34.111314 -15.599278)
			(xy 34.081635 -15.522668) (xy 34.059151 -15.443646) (xy 34.044055 -15.362887) (xy 34.036474 -15.281079)
			(xy 34.036 -15.24) (xy 32.250147 -15.24) (xy 32.234171 -15.322888) (xy 32.210303 -15.404178) (xy 32.178815 -15.48283)
			(xy 32.139993 -15.558133) (xy 32.09419 -15.629405) (xy 32.041819 -15.696001) (xy 31.983354 -15.757316)
			(xy 31.919326 -15.812797) (xy 31.850314 -15.86194) (xy 31.776944 -15.9043) (xy 31.699879 -15.939495)
			(xy 31.619817 -15.967204) (xy 31.537484 -15.987178) (xy 31.453625 -15.999235) (xy 31.369 -16.003267)
			(xy 31.284375 -15.999235) (xy 31.200516 -15.987178) (xy 31.118183 -15.967204) (xy 31.038121 -15.939495)
			(xy 30.961056 -15.9043) (xy 30.887686 -15.86194) (xy 30.818674 -15.812797) (xy 30.754646 -15.757316)
			(xy 30.696181 -15.696001) (xy 30.64381 -15.629405) (xy 30.598007 -15.558133) (xy 30.559185 -15.48283)
			(xy 30.527697 -15.404178) (xy 30.503829 -15.322888) (xy 30.487795 -15.239698) (xy 30.479742 -15.155361)
			(xy 0.509016 -15.155361) (xy 0.509016 -16.409924) (xy 43.677851 -16.409924) (xy 43.681826 -16.307474)
			(xy 43.693729 -16.205641) (xy 43.713487 -16.105036) (xy 43.740982 -16.006265) (xy 43.776048 -15.909921)
			(xy 43.818474 -15.816585) (xy 43.868006 -15.726817) (xy 43.924346 -15.641157) (xy 43.987154 -15.560121)
			(xy 44.056052 -15.484195) (xy 44.130628 -15.413837) (xy 44.210431 -15.349469) (xy 44.294982 -15.29148)
			(xy 44.383773 -15.240216) (xy 44.476269 -15.195988) (xy 44.571914 -15.15906) (xy 44.670134 -15.129655)
			(xy 44.770337 -15.10795) (xy 44.87192 -15.094074) (xy 44.974274 -15.088113) (xy 45.076781 -15.090101)
			(xy 45.178826 -15.100027) (xy 45.279795 -15.11783) (xy 45.379081 -15.143405) (xy 45.476086 -15.176596)
			(xy 45.570228 -15.217205) (xy 45.66094 -15.264987) (xy 45.747676 -15.319655) (xy 45.829915 -15.380879)
			(xy 45.907162 -15.448293) (xy 45.978953 -15.52149) (xy 46.044856 -15.60003) (xy 46.104475 -15.68344)
			(xy 46.15745 -15.77122) (xy 46.203464 -15.862842) (xy 46.24224 -15.957753) (xy 46.273544 -16.055384)
			(xy 46.297188 -16.155147) (xy 46.31303 -16.256442) (xy 46.320975 -16.358661) (xy 46.321472 -16.409924)
			(xy 46.320975 -16.461187) (xy 46.31303 -16.563406) (xy 46.297188 -16.664701) (xy 46.273544 -16.764464)
			(xy 46.24224 -16.862095) (xy 46.203464 -16.957006) (xy 46.15745 -17.048628) (xy 46.104475 -17.136408)
			(xy 46.044856 -17.219818) (xy 45.978953 -17.298358) (xy 45.907162 -17.371555) (xy 45.829915 -17.438969)
			(xy 45.747676 -17.500193) (xy 45.66094 -17.554861) (xy 45.570228 -17.602643) (xy 45.476086 -17.643252)
			(xy 45.379081 -17.676443) (xy 45.279795 -17.702018) (xy 45.178826 -17.719821) (xy 45.076781 -17.729747)
			(xy 44.974274 -17.731735) (xy 44.87192 -17.725774) (xy 44.770337 -17.711898) (xy 44.670134 -17.690193)
			(xy 44.571914 -17.660788) (xy 44.476269 -17.62386) (xy 44.383773 -17.579632) (xy 44.294982 -17.528368)
			(xy 44.210431 -17.470379) (xy 44.130628 -17.406011) (xy 44.056052 -17.335653) (xy 43.987154 -17.259727)
			(xy 43.924346 -17.178691) (xy 43.868006 -17.093031) (xy 43.818474 -17.003263) (xy 43.776048 -16.909927)
			(xy 43.740982 -16.813583) (xy 43.713487 -16.714812) (xy 43.693729 -16.614207) (xy 43.681826 -16.512374)
			(xy 43.677851 -16.409924) (xy 0.509016 -16.409924) (xy 0.509016 -18.796) (xy 19.557492 -18.796) (xy 19.557996 -18.753652)
			(xy 19.566047 -18.669338) (xy 19.582076 -18.586172) (xy 19.605937 -18.504905) (xy 19.637416 -18.426275)
			(xy 19.676227 -18.350994) (xy 19.722017 -18.279742) (xy 19.774373 -18.213166) (xy 19.832821 -18.151868)
			(xy 19.896831 -18.096403) (xy 19.965823 -18.047274) (xy 20.039173 -18.004925) (xy 20.116216 -17.969741)
			(xy 20.196255 -17.942039) (xy 20.278564 -17.922071) (xy 20.362399 -17.910018) (xy 20.447 -17.905988)
			(xy 20.531601 -17.910018) (xy 20.615436 -17.922071) (xy 20.697745 -17.942039) (xy 20.777784 -17.969741)
			(xy 20.854827 -18.004925) (xy 20.928177 -18.047274) (xy 20.997169 -18.096403) (xy 21.061179 -18.151868)
			(xy 21.119627 -18.213166) (xy 21.171983 -18.279742) (xy 21.217773 -18.350994) (xy 21.248152 -18.40992)
			(xy 41.677855 -18.40992) (xy 41.68183 -18.30747) (xy 41.693733 -18.205637) (xy 41.713491 -18.105032)
			(xy 41.740986 -18.006261) (xy 41.776052 -17.909917) (xy 41.818478 -17.816581) (xy 41.86801 -17.726813)
			(xy 41.92435 -17.641153) (xy 41.987158 -17.560117) (xy 42.056056 -17.484191) (xy 42.130632 -17.413833)
			(xy 42.210435 -17.349465) (xy 42.294986 -17.291476) (xy 42.383777 -17.240212) (xy 42.476273 -17.195984)
			(xy 42.571918 -17.159056) (xy 42.670138 -17.129651) (xy 42.770341 -17.107946) (xy 42.871924 -17.09407)
			(xy 42.974278 -17.088109) (xy 43.076785 -17.090097) (xy 43.17883 -17.100023) (xy 43.279799 -17.117826)
			(xy 43.379085 -17.143401) (xy 43.47609 -17.176592) (xy 43.570232 -17.217201) (xy 43.660944 -17.264983)
			(xy 43.74768 -17.319651) (xy 43.829919 -17.380875) (xy 43.907166 -17.448289) (xy 43.978957 -17.521486)
			(xy 44.04486 -17.600026) (xy 44.104479 -17.683436) (xy 44.157454 -17.771216) (xy 44.203468 -17.862838)
			(xy 44.242244 -17.957749) (xy 44.273548 -18.05538) (xy 44.297192 -18.155143) (xy 44.313034 -18.256438)
			(xy 44.320979 -18.358657) (xy 44.321476 -18.40992) (xy 44.320979 -18.461183) (xy 44.313034 -18.563402)
			(xy 44.297192 -18.664697) (xy 44.273548 -18.76446) (xy 44.242244 -18.862091) (xy 44.203468 -18.957002)
			(xy 44.157454 -19.048624) (xy 44.104479 -19.136404) (xy 44.04486 -19.219814) (xy 43.978957 -19.298354)
			(xy 43.907166 -19.371551) (xy 43.829919 -19.438965) (xy 43.74768 -19.500189) (xy 43.660944 -19.554857)
			(xy 43.570232 -19.602639) (xy 43.47609 -19.643248) (xy 43.379085 -19.676439) (xy 43.279799 -19.702014)
			(xy 43.17883 -19.719817) (xy 43.076785 -19.729743) (xy 42.974278 -19.731731) (xy 42.871924 -19.72577)
			(xy 42.770341 -19.711894) (xy 42.670138 -19.690189) (xy 42.571918 -19.660784) (xy 42.476273 -19.623856)
			(xy 42.383777 -19.579628) (xy 42.294986 -19.528364) (xy 42.210435 -19.470375) (xy 42.130632 -19.406007)
			(xy 42.056056 -19.335649) (xy 41.987158 -19.259723) (xy 41.92435 -19.178687) (xy 41.86801 -19.093027)
			(xy 41.818478 -19.003259) (xy 41.776052 -18.909923) (xy 41.740986 -18.813579) (xy 41.713491 -18.714808)
			(xy 41.693733 -18.614203) (xy 41.68183 -18.51237) (xy 41.677855 -18.40992) (xy 21.248152 -18.40992)
			(xy 21.256584 -18.426275) (xy 21.288063 -18.504905) (xy 21.311924 -18.586172) (xy 21.327953 -18.669338)
			(xy 21.336004 -18.753652) (xy 21.336508 -18.796) (xy 21.335998 -18.838614) (xy 21.327848 -18.92345)
			(xy 21.311625 -19.007119) (xy 21.287475 -19.088853) (xy 21.255621 -19.167904) (xy 21.236432 -19.205956)
			(xy 21.232342 -19.214706) (xy 21.230376 -19.233901) (xy 21.232622 -19.243294) (xy 21.241004 -19.272504)
			(xy 21.244048 -19.281659) (xy 21.255789 -19.296945) (xy 21.263864 -19.302222) (xy 21.299504 -19.32402)
			(xy 21.366961 -19.373318) (xy 21.429494 -19.428728) (xy 21.486552 -19.489761) (xy 21.537632 -19.555879)
			(xy 21.582283 -19.626497) (xy 21.62011 -19.700994) (xy 21.65078 -19.778712) (xy 21.674023 -19.858964)
			(xy 21.689633 -19.941043) (xy 21.697472 -20.024225) (xy 21.69795 -20.066) (xy 21.697446 -20.108324)
			(xy 21.6894 -20.19259) (xy 21.67338 -20.275709) (xy 21.649532 -20.356928) (xy 21.618071 -20.435513)
			(xy 21.579283 -20.510752) (xy 21.533519 -20.581963) (xy 21.481192 -20.648501) (xy 21.422778 -20.709764)
			(xy 21.358805 -20.765197) (xy 21.289852 -20.814298) (xy 21.216544 -20.856623) (xy 21.139545 -20.891787)
			(xy 21.059552 -20.919473) (xy 20.97729 -20.93943) (xy 20.893503 -20.951476) (xy 20.80895 -20.955504)
			(xy 20.724397 -20.951476) (xy 20.64061 -20.93943) (xy 20.558348 -20.919473) (xy 20.478355 -20.891787)
			(xy 20.401356 -20.856623) (xy 20.328048 -20.814298) (xy 20.259095 -20.765197) (xy 20.195122 -20.709764)
			(xy 20.136708 -20.648501) (xy 20.084381 -20.581963) (xy 20.038617 -20.510752) (xy 19.999829 -20.435513)
			(xy 19.968368 -20.356928) (xy 19.94452 -20.275709) (xy 19.9285 -20.19259) (xy 19.920454 -20.108324)
			(xy 19.91995 -20.066) (xy 19.920452 -20.023468) (xy 19.928598 -19.938796) (xy 19.944789 -19.855287)
			(xy 19.968876 -19.773705) (xy 20.000638 -19.694794) (xy 20.019772 -19.656806) (xy 20.023813 -19.648041)
			(xy 20.025633 -19.628841) (xy 20.023328 -19.619468) (xy 20.0152 -19.590258) (xy 20.012125 -19.581121)
			(xy 20.000387 -19.565848) (xy 19.99234 -19.56054) (xy 19.956638 -19.538743) (xy 19.889069 -19.489423)
			(xy 19.826429 -19.433977) (xy 19.769272 -19.372894) (xy 19.718102 -19.306715) (xy 19.673372 -19.236024)
			(xy 19.635476 -19.161446) (xy 19.604749 -19.083639) (xy 19.581464 -19.003291) (xy 19.565825 -18.921112)
			(xy 19.557971 -18.837827) (xy 19.557492 -18.796) (xy 0.509016 -18.796) (xy 0.509016 -20.409916) (xy 7.377949 -20.409916)
			(xy 7.381924 -20.307466) (xy 7.393827 -20.205633) (xy 7.413585 -20.105028) (xy 7.44108 -20.006257)
			(xy 7.476146 -19.909913) (xy 7.518572 -19.816577) (xy 7.568104 -19.726809) (xy 7.624444 -19.641149)
			(xy 7.687252 -19.560113) (xy 7.75615 -19.484187) (xy 7.830726 -19.413829) (xy 7.910529 -19.349461)
			(xy 7.99508 -19.291472) (xy 8.083871 -19.240208) (xy 8.176367 -19.19598) (xy 8.272012 -19.159052)
			(xy 8.370232 -19.129647) (xy 8.470435 -19.107942) (xy 8.572018 -19.094066) (xy 8.674372 -19.088105)
			(xy 8.776879 -19.090093) (xy 8.878924 -19.100019) (xy 8.979893 -19.117822) (xy 9.079179 -19.143397)
			(xy 9.176184 -19.176588) (xy 9.270326 -19.217197) (xy 9.361038 -19.264979) (xy 9.447774 -19.319647)
			(xy 9.530013 -19.380871) (xy 9.60726 -19.448285) (xy 9.679051 -19.521482) (xy 9.744954 -19.600022)
			(xy 9.804573 -19.683432) (xy 9.857548 -19.771212) (xy 9.903562 -19.862834) (xy 9.942338 -19.957745)
			(xy 9.973642 -20.055376) (xy 9.997286 -20.155139) (xy 10.013128 -20.256434) (xy 10.021073 -20.358653)
			(xy 10.02157 -20.409916) (xy 10.021073 -20.461179) (xy 10.013128 -20.563398) (xy 9.997286 -20.664693)
			(xy 9.973642 -20.764456) (xy 9.942338 -20.862087) (xy 9.903562 -20.956998) (xy 9.857548 -21.04862)
			(xy 9.804573 -21.1364) (xy 9.744954 -21.21981) (xy 9.679051 -21.29835) (xy 9.60726 -21.371547) (xy 9.530013 -21.438961)
			(xy 9.447774 -21.500185) (xy 9.361038 -21.554853) (xy 9.270326 -21.602635) (xy 9.176184 -21.643244)
			(xy 9.079179 -21.676435) (xy 8.979893 -21.70201) (xy 8.878924 -21.719813) (xy 8.776879 -21.729739)
			(xy 8.674372 -21.731727) (xy 8.572018 -21.725766) (xy 8.470435 -21.71189) (xy 8.370232 -21.690185)
			(xy 8.272012 -21.66078) (xy 8.176367 -21.623852) (xy 8.083871 -21.579624) (xy 7.99508 -21.52836)
			(xy 7.910529 -21.470371) (xy 7.830726 -21.406003) (xy 7.75615 -21.335645) (xy 7.687252 -21.259719)
			(xy 7.624444 -21.178683) (xy 7.568104 -21.093023) (xy 7.518572 -21.003255) (xy 7.476146 -20.909919)
			(xy 7.44108 -20.813575) (xy 7.413585 -20.714804) (xy 7.393827 -20.614199) (xy 7.381924 -20.512366)
			(xy 7.377949 -20.409916) (xy 0.509016 -20.409916) (xy 0.509016 -22.409912) (xy 5.377953 -22.409912)
			(xy 5.381928 -22.307462) (xy 5.393831 -22.205629) (xy 5.413589 -22.105024) (xy 5.441084 -22.006253)
			(xy 5.47615 -21.909909) (xy 5.518576 -21.816573) (xy 5.568108 -21.726805) (xy 5.624448 -21.641145)
			(xy 5.687256 -21.560109) (xy 5.756154 -21.484183) (xy 5.83073 -21.413825) (xy 5.910533 -21.349457)
			(xy 5.995084 -21.291468) (xy 6.083875 -21.240204) (xy 6.176371 -21.195976) (xy 6.272016 -21.159048)
			(xy 6.370236 -21.129643) (xy 6.470439 -21.107938) (xy 6.572022 -21.094062) (xy 6.674376 -21.088101)
			(xy 6.776883 -21.090089) (xy 6.878928 -21.100015) (xy 6.979897 -21.117818) (xy 7.079183 -21.143393)
			(xy 7.176188 -21.176584) (xy 7.27033 -21.217193) (xy 7.361042 -21.264975) (xy 7.447778 -21.319643)
			(xy 7.530017 -21.380867) (xy 7.607264 -21.448281) (xy 7.679055 -21.521478) (xy 7.744958 -21.600018)
			(xy 7.804577 -21.683428) (xy 7.857552 -21.771208) (xy 7.903566 -21.86283) (xy 7.942342 -21.957741)
			(xy 7.973646 -22.055372) (xy 7.99729 -22.155135) (xy 8.013132 -22.25643) (xy 8.021077 -22.358649)
			(xy 8.021574 -22.409912) (xy 8.021077 -22.461175) (xy 8.013132 -22.563394) (xy 7.99729 -22.664689)
			(xy 7.973646 -22.764452) (xy 7.942342 -22.862083) (xy 7.903566 -22.956994) (xy 7.857552 -23.048616)
			(xy 7.804577 -23.136396) (xy 7.744958 -23.219806) (xy 7.679055 -23.298346) (xy 7.607264 -23.371543)
			(xy 7.530017 -23.438957) (xy 7.447778 -23.500181) (xy 7.361042 -23.554849) (xy 7.27033 -23.602631)
			(xy 7.176188 -23.64324) (xy 7.079183 -23.676431) (xy 6.979897 -23.702006) (xy 6.878928 -23.719809)
			(xy 6.776883 -23.729735) (xy 6.674376 -23.731723) (xy 6.572022 -23.725762) (xy 6.470439 -23.711886)
			(xy 6.370236 -23.690181) (xy 6.272016 -23.660776) (xy 6.176371 -23.623848) (xy 6.083875 -23.57962)
			(xy 5.995084 -23.528356) (xy 5.910533 -23.470367) (xy 5.83073 -23.405999) (xy 5.756154 -23.335641)
			(xy 5.687256 -23.259715) (xy 5.624448 -23.178679) (xy 5.568108 -23.093019) (xy 5.518576 -23.003251)
			(xy 5.47615 -22.909915) (xy 5.441084 -22.813571) (xy 5.413589 -22.7148) (xy 5.393831 -22.614195)
			(xy 5.381928 -22.512362) (xy 5.377953 -22.409912) (xy 0.509016 -22.409912) (xy 0.509016 -25.908)
			(xy 30.225492 -25.908) (xy 30.226006 -25.864322) (xy 30.234576 -25.777387) (xy 30.251624 -25.69171)
			(xy 30.276986 -25.608116) (xy 30.310417 -25.52741) (xy 30.351597 -25.450369) (xy 30.400127 -25.377733)
			(xy 30.455542 -25.310203) (xy 30.517308 -25.248429) (xy 30.58483 -25.193004) (xy 30.657459 -25.144463)
			(xy 30.734494 -25.103272) (xy 30.77464 -25.086056) (xy 30.783677 -25.081783) (xy 30.797795 -25.06766)
			(xy 30.802072 -25.058624) (xy 30.819293 -25.018567) (xy 30.8605 -24.941721) (xy 30.909032 -24.869278)
			(xy 30.964423 -24.801934) (xy 31.026142 -24.740338) (xy 31.093595 -24.68508) (xy 31.166134 -24.636692)
			(xy 31.243063 -24.595638) (xy 31.323641 -24.562314) (xy 31.407095 -24.537039) (xy 31.492622 -24.520056)
			(xy 31.579401 -24.511528) (xy 31.623 -24.511) (xy 31.664079 -24.511474) (xy 31.745887 -24.519055)
			(xy 31.826646 -24.534151) (xy 31.905668 -24.556635) (xy 31.982278 -24.586314) (xy 32.055823 -24.622935)
			(xy 32.125675 -24.666185) (xy 32.191238 -24.715697) (xy 32.251954 -24.771046) (xy 32.307303 -24.831762)
			(xy 32.356815 -24.897325) (xy 32.400065 -24.967177) (xy 32.436686 -25.040722) (xy 32.466365 -25.117332)
			(xy 32.474522 -25.146) (xy 32.764988 -25.146) (xy 32.769018 -25.061399) (xy 32.781071 -24.977564)
			(xy 32.801039 -24.895255) (xy 32.828741 -24.815216) (xy 32.863925 -24.738173) (xy 32.906274 -24.664823)
			(xy 32.955403 -24.595831) (xy 33.010868 -24.531821) (xy 33.072166 -24.473373) (xy 33.138742 -24.421017)
			(xy 33.209994 -24.375227) (xy 33.285275 -24.336416) (xy 33.363905 -24.304937) (xy 33.445172 -24.281076)
			(xy 33.528338 -24.265047) (xy 33.612652 -24.256996) (xy 33.655 -24.256492) (xy 33.698026 -24.256951)
			(xy 33.783677 -24.265259) (xy 33.868126 -24.281797) (xy 33.950583 -24.306411) (xy 34.030279 -24.338871)
			(xy 34.106469 -24.378873) (xy 34.178441 -24.426044) (xy 34.245523 -24.479944) (xy 34.307088 -24.540067)
			(xy 34.36256 -24.605854) (xy 34.411422 -24.676689) (xy 34.453217 -24.75191) (xy 34.470848 -24.791162)
			(xy 34.475674 -24.802084) (xy 34.4932 -24.81707) (xy 34.5948 -24.84247) (xy 34.61766 -24.837644)
			(xy 34.627058 -24.830024) (xy 34.660727 -24.804016) (xy 34.732174 -24.757818) (xy 34.807707 -24.718656)
			(xy 34.886635 -24.686888) (xy 34.968237 -24.662804) (xy 35.051766 -24.646624) (xy 35.136459 -24.638498)
			(xy 35.179 -24.638) (xy 35.221324 -24.638504) (xy 35.30559 -24.64655) (xy 35.388709 -24.66257) (xy 35.469928 -24.686418)
			(xy 35.548513 -24.717879) (xy 35.623752 -24.756667) (xy 35.694963 -24.802431) (xy 35.761501 -24.854758)
			(xy 35.822764 -24.913172) (xy 35.878197 -24.977145) (xy 35.927298 -25.046098) (xy 35.969623 -25.119406)
			(xy 36.004787 -25.196405) (xy 36.032473 -25.276398) (xy 36.05243 -25.35866) (xy 36.064476 -25.442447)
			(xy 36.068504 -25.527) (xy 36.064476 -25.611553) (xy 36.05243 -25.69534) (xy 36.032473 -25.777602)
			(xy 36.004787 -25.857595) (xy 35.969623 -25.934594) (xy 35.927298 -26.007902) (xy 35.878197 -26.076855)
			(xy 35.822764 -26.140828) (xy 35.761501 -26.199242) (xy 35.694963 -26.251569) (xy 35.623752 -26.297333)
			(xy 35.548513 -26.336121) (xy 35.469928 -26.367582) (xy 35.388709 -26.39143) (xy 35.30559 -26.40745)
			(xy 35.221324 -26.415496) (xy 35.179 -26.416) (xy 35.136021 -26.415519) (xy 35.050463 -26.40724)
			(xy 34.966104 -26.39074) (xy 34.883732 -26.366173) (xy 34.804116 -26.333768) (xy 34.728 -26.293829)
			(xy 34.656096 -26.246728) (xy 34.589074 -26.192906) (xy 34.527562 -26.132865) (xy 34.472133 -26.067165)
			(xy 34.423306 -25.996422) (xy 34.381536 -25.921295) (xy 34.363914 -25.882092) (xy 34.359088 -25.87117)
			(xy 34.341562 -25.85593) (xy 34.239962 -25.830784) (xy 34.217102 -25.83561) (xy 34.207704 -25.842976)
			(xy 34.17402 -25.869073) (xy 34.102487 -25.915385) (xy 34.026854 -25.954645) (xy 33.947814 -25.986494)
			(xy 33.866091 -26.010639) (xy 33.782433 -26.02686) (xy 33.697608 -26.035008) (xy 33.655 -26.035508)
			(xy 33.612652 -26.035004) (xy 33.528338 -26.026953) (xy 33.445172 -26.010924) (xy 33.363905 -25.987063)
			(xy 33.285275 -25.955584) (xy 33.209994 -25.916773) (xy 33.138742 -25.870983) (xy 33.072166 -25.818627)
			(xy 33.010868 -25.760179) (xy 32.955403 -25.696169) (xy 32.906274 -25.627177) (xy 32.863925 -25.553827)
			(xy 32.828741 -25.476784) (xy 32.801039 -25.396745) (xy 32.781071 -25.314436) (xy 32.769018 -25.230601)
			(xy 32.764988 -25.146) (xy 32.474522 -25.146) (xy 32.488849 -25.196354) (xy 32.503945 -25.277113)
			(xy 32.511526 -25.358921) (xy 32.512 -25.4) (xy 32.511475 -25.443596) (xy 32.502923 -25.530367) (xy 32.485921 -25.615886)
			(xy 32.460633 -25.69933) (xy 32.4273 -25.779899) (xy 32.386243 -25.856819) (xy 32.337855 -25.929353)
			(xy 32.282603 -25.996803) (xy 32.221015 -26.058523) (xy 32.153683 -26.11392) (xy 32.081253 -26.162463)
			(xy 32.00442 -26.203684) (xy 31.964376 -26.220928) (xy 31.955346 -26.225212) (xy 31.941224 -26.239328)
			(xy 31.936944 -26.24836) (xy 31.919697 -26.288493) (xy 31.878517 -26.365534) (xy 31.829985 -26.438168)
			(xy 31.774566 -26.505696) (xy 31.712796 -26.567466) (xy 31.645269 -26.622884) (xy 31.572635 -26.671417)
			(xy 31.495593 -26.712596) (xy 31.414886 -26.746026) (xy 31.331292 -26.771384) (xy 31.245614 -26.788427)
			(xy 31.158678 -26.796989) (xy 31.115 -26.797508) (xy 31.073898 -26.797033) (xy 30.992043 -26.789448)
			(xy 30.911238 -26.774343) (xy 30.832171 -26.751847) (xy 30.755517 -26.722151) (xy 30.68193 -26.685509)
			(xy 30.612038 -26.642234) (xy 30.546437 -26.592694) (xy 30.485687 -26.537313) (xy 30.430306 -26.476563)
			(xy 30.380766 -26.410962) (xy 30.337491 -26.34107) (xy 30.300849 -26.267483) (xy 30.271153 -26.190829)
			(xy 30.248657 -26.111762) (xy 30.233552 -26.030957) (xy 30.225967 -25.949102) (xy 30.225492 -25.908)
			(xy 0.509016 -25.908) (xy 0.509016 -28.309824) (xy 42.741353 -28.309824) (xy 42.745331 -28.209831)
			(xy 42.757241 -28.110471) (xy 42.777008 -28.01237) (xy 42.804507 -27.916151) (xy 42.839563 -27.82242)
			(xy 42.881955 -27.731771) (xy 42.931416 -27.644777) (xy 42.987632 -27.561987) (xy 43.050248 -27.483925)
			(xy 43.118867 -27.411085) (xy 43.193058 -27.343927) (xy 43.272349 -27.282875) (xy 43.35624 -27.228317)
			(xy 43.444201 -27.180596) (xy 43.535675 -27.140014) (xy 43.630084 -27.106828) (xy 43.726831 -27.081248)
			(xy 43.825305 -27.063435) (xy 43.924883 -27.053503) (xy 44.024935 -27.051513) (xy 44.124829 -27.057479)
			(xy 44.223933 -27.071363) (xy 44.321621 -27.093076) (xy 44.417275 -27.122482) (xy 44.51029 -27.159395)
			(xy 44.600078 -27.203581) (xy 44.686072 -27.254762) (xy 44.767728 -27.312612) (xy 44.844529 -27.376768)
			(xy 44.915991 -27.446822) (xy 44.981661 -27.522333) (xy 45.041123 -27.602823) (xy 45.094003 -27.687782)
			(xy 45.139966 -27.776674) (xy 45.178721 -27.868937) (xy 45.210023 -27.963987) (xy 45.233675 -28.061224)
			(xy 45.249526 -28.160033) (xy 45.257476 -28.259788) (xy 45.257974 -28.309824) (xy 45.257476 -28.35986)
			(xy 45.249526 -28.459615) (xy 45.233675 -28.558424) (xy 45.210023 -28.655661) (xy 45.178721 -28.750711)
			(xy 45.139966 -28.842974) (xy 45.094003 -28.931866) (xy 45.041123 -29.016825) (xy 44.981661 -29.097315)
			(xy 44.915991 -29.172826) (xy 44.844529 -29.24288) (xy 44.767728 -29.307036) (xy 44.686072 -29.364886)
			(xy 44.600078 -29.416067) (xy 44.51029 -29.460253) (xy 44.417275 -29.497166) (xy 44.321621 -29.526572)
			(xy 44.223933 -29.548285) (xy 44.124829 -29.562169) (xy 44.024935 -29.568135) (xy 43.924883 -29.566145)
			(xy 43.825305 -29.556213) (xy 43.726831 -29.5384) (xy 43.630084 -29.51282) (xy 43.535675 -29.479634)
			(xy 43.444201 -29.439052) (xy 43.35624 -29.391331) (xy 43.272349 -29.336773) (xy 43.193058 -29.275721)
			(xy 43.118867 -29.208563) (xy 43.050248 -29.135723) (xy 42.987632 -29.057661) (xy 42.931416 -28.974871)
			(xy 42.881955 -28.887877) (xy 42.839563 -28.797228) (xy 42.804507 -28.703497) (xy 42.777008 -28.607278)
			(xy 42.757241 -28.509177) (xy 42.745331 -28.409817) (xy 42.741353 -28.309824) (xy 0.509016 -28.309824)
			(xy 0.509016 -29.591) (xy 18.60296 -29.591) (xy 18.603452 -29.54989) (xy 18.61104 -29.468022) (xy 18.62615 -29.387203)
			(xy 18.648654 -29.308123) (xy 18.678359 -29.231458) (xy 18.715013 -29.15786) (xy 18.758302 -29.08796)
			(xy 18.807857 -29.022353) (xy 18.863255 -28.961598) (xy 18.924023 -28.906215) (xy 18.989643 -28.856677)
			(xy 19.059554 -28.813405) (xy 19.133161 -28.77677) (xy 19.209834 -28.747083) (xy 19.288919 -28.724599)
			(xy 19.369742 -28.709509) (xy 19.451612 -28.701942) (xy 19.492722 -28.701492) (xy 19.535817 -28.702062)
			(xy 19.621603 -28.710407) (xy 19.706179 -28.727008) (xy 19.788755 -28.751708) (xy 19.868555 -28.784277)
			(xy 19.944833 -28.824408) (xy 20.016872 -28.871727) (xy 20.083999 -28.92579) (xy 20.145585 -28.986089)
			(xy 20.201052 -29.052061) (xy 20.24988 -29.123086) (xy 20.291612 -29.1985) (xy 20.325857 -29.277596)
			(xy 20.339558 -29.318458) (xy 20.341332 -29.323554) (xy 20.346708 -29.332908) (xy 20.350226 -29.337)
			(xy 20.377137 -29.367587) (xy 20.425884 -29.432869) (xy 20.468455 -29.502338) (xy 20.50449 -29.57541)
			(xy 20.533689 -29.651473) (xy 20.555805 -29.729888) (xy 20.570655 -29.809998) (xy 20.578112 -29.891131)
			(xy 20.578572 -29.931868) (xy 20.578109 -29.972948) (xy 20.570531 -30.054758) (xy 20.555437 -30.135519)
			(xy 20.532954 -30.214543) (xy 20.503276 -30.291156) (xy 20.466656 -30.364703) (xy 20.423405 -30.434557)
			(xy 20.373893 -30.500123) (xy 20.318542 -30.56084) (xy 20.257826 -30.61619) (xy 20.19226 -30.665703)
			(xy 20.122406 -30.708954) (xy 20.048859 -30.745575) (xy 19.972247 -30.775253) (xy 19.893223 -30.797736)
			(xy 19.812462 -30.812831) (xy 19.730652 -30.820409) (xy 19.689572 -30.820868) (xy 19.646602 -30.820396)
			(xy 19.561064 -30.812107) (xy 19.476725 -30.795599) (xy 19.394373 -30.771028) (xy 19.314778 -30.738621)
			(xy 19.238683 -30.698683) (xy 19.166799 -30.651585) (xy 19.099796 -30.597768) (xy 19.038302 -30.537735)
			(xy 18.98289 -30.472046) (xy 18.934078 -30.401315) (xy 18.892321 -30.326202) (xy 18.85801 -30.247409)
			(xy 18.84426 -30.206696) (xy 18.84248 -30.20166) (xy 18.837097 -30.192438) (xy 18.833592 -30.188408)
			(xy 18.806416 -30.157771) (xy 18.757208 -30.092301) (xy 18.714226 -30.022586) (xy 18.677834 -29.949215)
			(xy 18.64834 -29.872809) (xy 18.625993 -29.794016) (xy 18.610983 -29.713503) (xy 18.603437 -29.63195)
			(xy 18.60296 -29.591) (xy 0.509016 -29.591) (xy 0.509016 -31.599792) (xy 16.256504 -31.599792) (xy 16.256504 -31.515144)
			(xy 16.26455 -31.430878) (xy 16.28057 -31.347759) (xy 16.304418 -31.26654) (xy 16.335879 -31.187955)
			(xy 16.374667 -31.112716) (xy 16.420431 -31.041505) (xy 16.472758 -30.974967) (xy 16.531172 -30.913704)
			(xy 16.595145 -30.858271) (xy 16.664098 -30.80917) (xy 16.737406 -30.766845) (xy 16.814405 -30.731681)
			(xy 16.894398 -30.703995) (xy 16.97666 -30.684038) (xy 17.060447 -30.671992) (xy 17.145 -30.667964)
			(xy 17.229553 -30.671992) (xy 17.31334 -30.684038) (xy 17.395602 -30.703995) (xy 17.475595 -30.731681)
			(xy 17.552594 -30.766845) (xy 17.625902 -30.80917) (xy 17.694855 -30.858271) (xy 17.758828 -30.913704)
			(xy 17.817242 -30.974967) (xy 17.869569 -31.041505) (xy 17.915333 -31.112716) (xy 17.954121 -31.187955)
			(xy 17.985582 -31.26654) (xy 18.00943 -31.347759) (xy 18.02545 -31.430878) (xy 18.033496 -31.515144)
			(xy 18.034 -31.557468) (xy 18.033496 -31.599792) (xy 18.02545 -31.684058) (xy 18.00943 -31.767177)
			(xy 17.985582 -31.848396) (xy 17.954121 -31.926981) (xy 17.915333 -32.00222) (xy 17.869569 -32.073431)
			(xy 17.817242 -32.139969) (xy 17.758828 -32.201232) (xy 17.694855 -32.256665) (xy 17.625902 -32.305766)
			(xy 17.552594 -32.348091) (xy 17.475595 -32.383255) (xy 17.395602 -32.410941) (xy 17.31334 -32.430898)
			(xy 17.229553 -32.442944) (xy 17.145 -32.446972) (xy 17.060447 -32.442944) (xy 16.97666 -32.430898)
			(xy 16.894398 -32.410941) (xy 16.814405 -32.383255) (xy 16.737406 -32.348091) (xy 16.664098 -32.305766)
			(xy 16.595145 -32.256665) (xy 16.531172 -32.201232) (xy 16.472758 -32.139969) (xy 16.420431 -32.073431)
			(xy 16.374667 -32.00222) (xy 16.335879 -31.926981) (xy 16.304418 -31.848396) (xy 16.28057 -31.767177)
			(xy 16.26455 -31.684058) (xy 16.256504 -31.599792) (xy 0.509016 -31.599792) (xy 0.509016 -32.935361)
			(xy 31.495742 -32.935361) (xy 31.495742 -32.850639) (xy 31.503795 -32.766302) (xy 31.519829 -32.683112)
			(xy 31.543697 -32.601822) (xy 31.575185 -32.52317) (xy 31.614007 -32.447867) (xy 31.65981 -32.376595)
			(xy 31.712181 -32.309999) (xy 31.770646 -32.248684) (xy 31.834674 -32.193203) (xy 31.903686 -32.14406)
			(xy 31.977056 -32.1017) (xy 32.054121 -32.066505) (xy 32.134183 -32.038796) (xy 32.216516 -32.018822)
			(xy 32.300375 -32.006765) (xy 32.385 -32.002734) (xy 32.469625 -32.006765) (xy 32.553484 -32.018822)
			(xy 32.635817 -32.038796) (xy 32.715879 -32.066505) (xy 32.792944 -32.1017) (xy 32.866314 -32.14406)
			(xy 32.935326 -32.193203) (xy 32.999354 -32.248684) (xy 33.057819 -32.309999) (xy 33.11019 -32.376595)
			(xy 33.155993 -32.447867) (xy 33.194815 -32.52317) (xy 33.226303 -32.601822) (xy 33.250171 -32.683112)
			(xy 33.266205 -32.766302) (xy 33.274258 -32.850639) (xy 33.274762 -32.893) (xy 33.274258 -32.935361)
			(xy 33.266205 -33.019698) (xy 33.250171 -33.102888) (xy 33.226303 -33.184178) (xy 33.194815 -33.26283)
			(xy 33.155993 -33.338133) (xy 33.11019 -33.409405) (xy 33.057819 -33.476001) (xy 32.999354 -33.537316)
			(xy 32.935326 -33.592797) (xy 32.866314 -33.64194) (xy 32.792944 -33.6843) (xy 32.715879 -33.719495)
			(xy 32.635817 -33.747204) (xy 32.579523 -33.760861) (xy 33.591242 -33.760861) (xy 33.591242 -33.676139)
			(xy 33.599295 -33.591802) (xy 33.615329 -33.508612) (xy 33.639197 -33.427322) (xy 33.670685 -33.34867)
			(xy 33.709507 -33.273367) (xy 33.75531 -33.202095) (xy 33.807681 -33.135499) (xy 33.866146 -33.074184)
			(xy 33.930174 -33.018703) (xy 33.999186 -32.96956) (xy 34.072556 -32.9272) (xy 34.149621 -32.892005)
			(xy 34.229683 -32.864296) (xy 34.312016 -32.844322) (xy 34.395875 -32.832265) (xy 34.4805 -32.828234)
			(xy 34.565125 -32.832265) (xy 34.648984 -32.844322) (xy 34.731317 -32.864296) (xy 34.811379 -32.892005)
			(xy 34.888444 -32.9272) (xy 34.961814 -32.96956) (xy 35.030826 -33.018703) (xy 35.094854 -33.074184)
			(xy 35.153319 -33.135499) (xy 35.20569 -33.202095) (xy 35.251493 -33.273367) (xy 35.290315 -33.34867)
			(xy 35.321803 -33.427322) (xy 35.345671 -33.508612) (xy 35.361705 -33.591802) (xy 35.369758 -33.676139)
			(xy 35.370262 -33.7185) (xy 35.369758 -33.760861) (xy 35.361705 -33.845198) (xy 35.345671 -33.928388)
			(xy 35.321803 -34.009678) (xy 35.290315 -34.08833) (xy 35.251493 -34.163633) (xy 35.20569 -34.234905)
			(xy 35.153319 -34.301501) (xy 35.094854 -34.362816) (xy 35.030826 -34.418297) (xy 34.961814 -34.46744)
			(xy 34.888444 -34.5098) (xy 34.811379 -34.544995) (xy 34.731317 -34.572704) (xy 34.648984 -34.592678)
			(xy 34.565125 -34.604735) (xy 34.4805 -34.608767) (xy 34.395875 -34.604735) (xy 34.312016 -34.592678)
			(xy 34.229683 -34.572704) (xy 34.149621 -34.544995) (xy 34.072556 -34.5098) (xy 33.999186 -34.46744)
			(xy 33.930174 -34.418297) (xy 33.866146 -34.362816) (xy 33.807681 -34.301501) (xy 33.75531 -34.234905)
			(xy 33.709507 -34.163633) (xy 33.670685 -34.08833) (xy 33.639197 -34.009678) (xy 33.615329 -33.928388)
			(xy 33.599295 -33.845198) (xy 33.591242 -33.760861) (xy 32.579523 -33.760861) (xy 32.553484 -33.767178)
			(xy 32.469625 -33.779235) (xy 32.385 -33.783267) (xy 32.300375 -33.779235) (xy 32.216516 -33.767178)
			(xy 32.134183 -33.747204) (xy 32.054121 -33.719495) (xy 31.977056 -33.6843) (xy 31.903686 -33.64194)
			(xy 31.834674 -33.592797) (xy 31.770646 -33.537316) (xy 31.712181 -33.476001) (xy 31.65981 -33.409405)
			(xy 31.614007 -33.338133) (xy 31.575185 -33.26283) (xy 31.543697 -33.184178) (xy 31.519829 -33.102888)
			(xy 31.503795 -33.019698) (xy 31.495742 -32.935361) (xy 0.509016 -32.935361) (xy 0.509016 -33.951361)
			(xy 18.414742 -33.951361) (xy 18.414742 -33.866639) (xy 18.422795 -33.782302) (xy 18.438829 -33.699112)
			(xy 18.462697 -33.617822) (xy 18.494185 -33.53917) (xy 18.533007 -33.463867) (xy 18.57881 -33.392595)
			(xy 18.631181 -33.325999) (xy 18.689646 -33.264684) (xy 18.753674 -33.209203) (xy 18.822686 -33.16006)
			(xy 18.896056 -33.1177) (xy 18.973121 -33.082505) (xy 19.053183 -33.054796) (xy 19.135516 -33.034822)
			(xy 19.219375 -33.022765) (xy 19.304 -33.018734) (xy 19.388625 -33.022765) (xy 19.472484 -33.034822)
			(xy 19.554817 -33.054796) (xy 19.634879 -33.082505) (xy 19.711944 -33.1177) (xy 19.785314 -33.16006)
			(xy 19.854326 -33.209203) (xy 19.918354 -33.264684) (xy 19.976819 -33.325999) (xy 20.02919 -33.392595)
			(xy 20.074993 -33.463867) (xy 20.113815 -33.53917) (xy 20.145303 -33.617822) (xy 20.169171 -33.699112)
			(xy 20.185205 -33.782302) (xy 20.193258 -33.866639) (xy 20.193762 -33.909) (xy 20.193258 -33.951361)
			(xy 20.185205 -34.035698) (xy 20.169171 -34.118888) (xy 20.145303 -34.200178) (xy 20.113815 -34.27883)
			(xy 20.074993 -34.354133) (xy 20.02919 -34.425405) (xy 19.976819 -34.492001) (xy 19.918354 -34.553316)
			(xy 19.854326 -34.608797) (xy 19.785314 -34.65794) (xy 19.711944 -34.7003) (xy 19.634879 -34.735495)
			(xy 19.554817 -34.763204) (xy 19.472484 -34.783178) (xy 19.388625 -34.795235) (xy 19.304 -34.799267)
			(xy 19.219375 -34.795235) (xy 19.135516 -34.783178) (xy 19.053183 -34.763204) (xy 18.973121 -34.735495)
			(xy 18.896056 -34.7003) (xy 18.822686 -34.65794) (xy 18.753674 -34.608797) (xy 18.689646 -34.553316)
			(xy 18.631181 -34.492001) (xy 18.57881 -34.425405) (xy 18.533007 -34.354133) (xy 18.494185 -34.27883)
			(xy 18.462697 -34.200178) (xy 18.438829 -34.118888) (xy 18.422795 -34.035698) (xy 18.414742 -33.951361)
			(xy 0.509016 -33.951361) (xy 0.509016 -38.649656) (xy 10.387584 -38.649656) (xy 10.388004 -38.611367)
			(xy 10.394607 -38.535073) (xy 10.407752 -38.45963) (xy 10.427342 -38.385599) (xy 10.439908 -38.349428)
			(xy 10.442583 -38.340997) (xy 10.442568 -38.323321) (xy 10.439908 -38.314884) (xy 10.427378 -38.278702)
			(xy 10.407801 -38.204671) (xy 10.39465 -38.129232) (xy 10.388022 -38.052944) (xy 10.387584 -38.014656)
			(xy 10.388134 -37.971531) (xy 10.396533 -37.885692) (xy 10.41321 -37.80107) (xy 10.438008 -37.718462)
			(xy 10.453878 -37.67836) (xy 10.457226 -37.668995) (xy 10.45721 -37.649124) (xy 10.453878 -37.639752)
			(xy 10.438017 -37.599647) (xy 10.413234 -37.517036) (xy 10.396554 -37.432416) (xy 10.388133 -37.34658)
			(xy 10.387584 -37.303456) (xy 10.38801 -37.262345) (xy 10.395602 -37.180474) (xy 10.410717 -37.099653)
			(xy 10.433225 -37.020571) (xy 10.462935 -36.943904) (xy 10.499593 -36.870306) (xy 10.542887 -36.800405)
			(xy 10.592446 -36.734797) (xy 10.647848 -36.674043) (xy 10.708621 -36.618661) (xy 10.774244 -36.569123)
			(xy 10.84416 -36.525852) (xy 10.91777 -36.489218) (xy 10.994446 -36.459533) (xy 11.073535 -36.43705)
			(xy 11.154361 -36.421962) (xy 11.236235 -36.414397) (xy 11.277346 -36.413948) (xy 11.323741 -36.414545)
			(xy 11.416029 -36.424185) (xy 11.506813 -36.443377) (xy 11.595107 -36.471912) (xy 11.637772 -36.490148)
			(xy 11.647714 -36.493954) (xy 11.668978 -36.493954) (xy 11.67892 -36.490148) (xy 11.721577 -36.471891)
			(xy 11.809871 -36.44335) (xy 11.900658 -36.42416) (xy 11.99295 -36.414531) (xy 12.039346 -36.413948)
			(xy 12.080453 -36.414426) (xy 12.162316 -36.42201) (xy 12.24313 -36.437114) (xy 12.322206 -36.459608)
			(xy 12.39887 -36.489302) (xy 12.472467 -36.525941) (xy 12.542371 -36.569214) (xy 12.607985 -36.61875)
			(xy 12.668749 -36.674129) (xy 12.724145 -36.734877) (xy 12.7737 -36.800476) (xy 12.816993 -36.870367)
			(xy 12.853654 -36.943954) (xy 12.88337 -37.020609) (xy 12.905887 -37.099679) (xy 12.921014 -37.180489)
			(xy 12.928622 -37.262349) (xy 12.929108 -37.303456) (xy 12.928563 -37.346581) (xy 12.920162 -37.432421)
			(xy 12.903484 -37.517042) (xy 12.878685 -37.59965) (xy 12.862814 -37.639752) (xy 12.859515 -37.64913)
			(xy 12.859499 -37.668989) (xy 12.862814 -37.67836) (xy 12.878678 -37.718463) (xy 12.903461 -37.801075)
			(xy 12.919776 -37.883846) (xy 36.848796 -37.883846) (xy 36.849168 -37.845561) (xy 36.855711 -37.769272)
			(xy 36.868797 -37.69383) (xy 36.888329 -37.619794) (xy 36.900866 -37.583618) (xy 36.903493 -37.575175)
			(xy 36.903508 -37.55751) (xy 36.900866 -37.549074) (xy 36.888354 -37.512891) (xy 36.868843 -37.438853)
			(xy 36.855759 -37.363413) (xy 36.8492 -37.287129) (xy 36.848796 -37.248846) (xy 36.849356 -37.207741)
			(xy 36.856936 -37.125882) (xy 36.872035 -37.045071) (xy 36.894525 -36.965997) (xy 36.924213 -36.889336)
			(xy 36.960847 -36.81574) (xy 37.004115 -36.745837) (xy 37.053646 -36.680225) (xy 37.109019 -36.619461)
			(xy 37.169761 -36.564064) (xy 37.235355 -36.514508) (xy 37.305241 -36.471214) (xy 37.378823 -36.434552)
			(xy 37.455473 -36.404834) (xy 37.534538 -36.382314) (xy 37.615343 -36.367183) (xy 37.697199 -36.359572)
			(xy 37.738304 -36.359084) (xy 37.784706 -36.359709) (xy 37.877004 -36.369399) (xy 37.967789 -36.388654)
			(xy 38.056074 -36.417262) (xy 38.09873 -36.435538) (xy 38.108672 -36.439344) (xy 38.129936 -36.439344)
			(xy 38.139878 -36.435538) (xy 38.182538 -36.417275) (xy 38.270827 -36.388682) (xy 38.36161 -36.369425)
			(xy 38.453903 -36.359713) (xy 38.500304 -36.359084) (xy 38.546706 -36.359709) (xy 38.639004 -36.369399)
			(xy 38.729789 -36.388654) (xy 38.818074 -36.417262) (xy 38.86073 -36.435538) (xy 38.870672 -36.439344)
			(xy 38.891936 -36.439344) (xy 38.901878 -36.435538) (xy 38.944538 -36.417275) (xy 39.032827 -36.388682)
			(xy 39.12361 -36.369425) (xy 39.215903 -36.359713) (xy 39.262304 -36.359084) (xy 39.303414 -36.359549)
			(xy 39.385284 -36.367137) (xy 39.466105 -36.382248) (xy 39.545186 -36.404753) (xy 39.621853 -36.43446)
			(xy 39.695451 -36.471115) (xy 39.765352 -36.514406) (xy 39.83096 -36.563962) (xy 39.891715 -36.619362)
			(xy 39.947097 -36.680133) (xy 39.996636 -36.745754) (xy 40.039907 -36.815668) (xy 40.076541 -36.889276)
			(xy 40.106227 -36.965951) (xy 40.12871 -37.045039) (xy 40.143798 -37.125863) (xy 40.151363 -37.207735)
			(xy 40.151812 -37.248846) (xy 40.151438 -37.287131) (xy 40.144895 -37.36342) (xy 40.131809 -37.438862)
			(xy 40.112279 -37.512898) (xy 40.099742 -37.549074) (xy 40.097068 -37.557505) (xy 40.097083 -37.575181)
			(xy 40.099742 -37.583618) (xy 40.112252 -37.619801) (xy 40.131764 -37.693839) (xy 40.144848 -37.769279)
			(xy 40.151408 -37.845563) (xy 40.151812 -37.883846) (xy 40.151431 -37.924955) (xy 40.143842 -38.006822)
			(xy 40.128733 -38.08764) (xy 40.106233 -38.166719) (xy 40.076534 -38.243386) (xy 40.039888 -38.316985)
			(xy 39.996609 -38.38689) (xy 39.947066 -38.452505) (xy 39.891681 -38.513269) (xy 39.830927 -38.568665)
			(xy 39.765321 -38.61822) (xy 39.695423 -38.661511) (xy 39.62183 -38.69817) (xy 39.545169 -38.727883)
			(xy 39.466094 -38.750397) (xy 39.385279 -38.76552) (xy 39.303413 -38.773124) (xy 39.262304 -38.773608)
			(xy 39.215902 -38.772981) (xy 39.123605 -38.763291) (xy 39.032819 -38.744038) (xy 38.944534 -38.71543)
			(xy 38.901878 -38.697154) (xy 38.891936 -38.693348) (xy 38.870672 -38.693348) (xy 38.86073 -38.697154)
			(xy 38.818068 -38.715414) (xy 38.729781 -38.744008) (xy 38.638998 -38.763266) (xy 38.546705 -38.772979)
			(xy 38.500304 -38.773608) (xy 38.453902 -38.772981) (xy 38.361605 -38.763291) (xy 38.270819 -38.744038)
			(xy 38.182534 -38.71543) (xy 38.139878 -38.697154) (xy 38.129936 -38.693348) (xy 38.108672 -38.693348)
			(xy 38.09873 -38.697154) (xy 38.056068 -38.715414) (xy 37.967781 -38.744008) (xy 37.876998 -38.763266)
			(xy 37.784705 -38.772979) (xy 37.738304 -38.773608) (xy 37.697193 -38.773144) (xy 37.615323 -38.765556)
			(xy 37.534502 -38.750446) (xy 37.455421 -38.727941) (xy 37.378754 -38.698235) (xy 37.305156 -38.66158)
			(xy 37.235254 -38.618289) (xy 37.169646 -38.568732) (xy 37.108891 -38.513332) (xy 37.053508 -38.452562)
			(xy 37.00397 -38.38694) (xy 36.960699 -38.317026) (xy 36.924064 -38.243417) (xy 36.894379 -38.166742)
			(xy 36.871897 -38.087654) (xy 36.856809 -38.006829) (xy 36.849245 -37.924957) (xy 36.848796 -37.883846)
			(xy 12.919776 -37.883846) (xy 12.92014 -37.885695) (xy 12.92856 -37.971532) (xy 12.929108 -38.014656)
			(xy 12.928692 -38.052946) (xy 12.922088 -38.12924) (xy 12.908941 -38.204682) (xy 12.889351 -38.278713)
			(xy 12.876784 -38.314884) (xy 12.874154 -38.323326) (xy 12.874139 -38.340992) (xy 12.876784 -38.349428)
			(xy 12.889317 -38.385609) (xy 12.908893 -38.459641) (xy 12.922043 -38.535079) (xy 12.928671 -38.611368)
			(xy 12.929108 -38.649656) (xy 12.928606 -38.690766) (xy 12.921022 -38.772635) (xy 12.905915 -38.853455)
			(xy 12.883413 -38.932536) (xy 12.85371 -39.009203) (xy 12.817058 -39.082801) (xy 12.77377 -39.152703)
			(xy 12.724216 -39.218311) (xy 12.668818 -39.279066) (xy 12.60805 -39.33445) (xy 12.54243 -39.383989)
			(xy 12.472518 -39.42726) (xy 12.398911 -39.463895) (xy 12.322237 -39.49358) (xy 12.243151 -39.516063)
			(xy 12.162327 -39.531151) (xy 12.080456 -39.538715) (xy 12.039346 -39.539164) (xy 11.992951 -39.538569)
			(xy 11.900663 -39.528928) (xy 11.809879 -39.509736) (xy 11.721585 -39.4812) (xy 11.67892 -39.462964)
			(xy 11.668978 -39.459158) (xy 11.647714 -39.459158) (xy 11.637772 -39.462964) (xy 11.595102 -39.481191)
			(xy 11.506813 -39.50974) (xy 11.41603 -39.528938) (xy 11.323741 -39.538577) (xy 11.277346 -39.539164)
			(xy 11.236239 -39.538691) (xy 11.154376 -39.531107) (xy 11.073562 -39.516002) (xy 10.994486 -39.493507)
			(xy 10.917822 -39.463813) (xy 10.844225 -39.427174) (xy 10.774321 -39.383901) (xy 10.708708 -39.334363)
			(xy 10.647944 -39.278985) (xy 10.592548 -39.218236) (xy 10.542992 -39.152637) (xy 10.499699 -39.082746)
			(xy 10.463039 -39.009158) (xy 10.433323 -38.932503) (xy 10.410805 -38.853433) (xy 10.395678 -38.772623)
			(xy 10.38807 -38.690763) (xy 10.387584 -38.649656) (xy 0.509016 -38.649656) (xy 0.509016 -44.263056)
			(xy 10.409936 -44.263056) (xy 10.410551 -44.216654) (xy 10.420245 -44.124356) (xy 10.439502 -44.033571)
			(xy 10.468113 -43.945286) (xy 10.48639 -43.90263) (xy 10.490221 -43.892696) (xy 10.490205 -43.871425)
			(xy 10.48639 -43.861482) (xy 10.468111 -43.818828) (xy 10.439523 -43.730537) (xy 10.42027 -43.639752)
			(xy 10.410563 -43.547458) (xy 10.409936 -43.501056) (xy 10.410389 -43.459945) (xy 10.417977 -43.378074)
			(xy 10.433088 -43.297253) (xy 10.455593 -43.218172) (xy 10.485301 -43.141504) (xy 10.521957 -43.067906)
			(xy 10.565248 -42.998004) (xy 10.614806 -42.932396) (xy 10.670207 -42.871641) (xy 10.730978 -42.816258)
			(xy 10.796601 -42.76672) (xy 10.866515 -42.723449) (xy 10.940124 -42.686815) (xy 11.0168 -42.65713)
			(xy 11.095889 -42.634648) (xy 11.176714 -42.619561) (xy 11.258587 -42.611997) (xy 11.299698 -42.611548)
			(xy 11.346094 -42.612127) (xy 11.438382 -42.621772) (xy 11.529166 -42.640969) (xy 11.617459 -42.669509)
			(xy 11.660124 -42.687748) (xy 11.670066 -42.691554) (xy 11.69133 -42.691554) (xy 11.701272 -42.687748)
			(xy 11.743936 -42.669507) (xy 11.832227 -42.640961) (xy 11.923012 -42.621767) (xy 12.015302 -42.612133)
			(xy 12.061698 -42.611548) (xy 12.102805 -42.612014) (xy 12.184668 -42.619599) (xy 12.265483 -42.634703)
			(xy 12.34456 -42.657198) (xy 12.421224 -42.686892) (xy 12.494822 -42.723532) (xy 12.564726 -42.766805)
			(xy 12.63034 -42.816342) (xy 12.691104 -42.871722) (xy 12.7465 -42.932471) (xy 12.796056 -42.998071)
			(xy 12.839349 -43.067963) (xy 12.876009 -43.141551) (xy 12.905724 -43.218207) (xy 12.928241 -43.297277)
			(xy 12.943367 -43.378088) (xy 12.950974 -43.459949) (xy 12.95146 -43.501056) (xy 12.95085 -43.547459)
			(xy 12.941154 -43.639756) (xy 12.921896 -43.730542) (xy 12.893284 -43.818826) (xy 12.875006 -43.861482)
			(xy 12.871227 -43.871432) (xy 12.87121 -43.892688) (xy 12.875006 -43.90263) (xy 12.893256 -43.945296)
			(xy 12.921852 -44.033582) (xy 12.941112 -44.124363) (xy 12.950829 -44.216655) (xy 12.95146 -44.263056)
			(xy 12.950994 -44.304167) (xy 12.95059 -44.308522) (xy 37.125148 -44.308522) (xy 37.125734 -44.262126)
			(xy 37.135377 -44.169838) (xy 37.154572 -44.079054) (xy 37.18311 -43.990761) (xy 37.201348 -43.948096)
			(xy 37.205143 -43.93815) (xy 37.205151 -43.91689) (xy 37.201348 -43.906948) (xy 37.183114 -43.864281)
			(xy 37.154566 -43.775991) (xy 37.13537 -43.685207) (xy 37.125734 -43.592918) (xy 37.125148 -43.546522)
			(xy 37.125734 -43.500126) (xy 37.135377 -43.407838) (xy 37.154572 -43.317054) (xy 37.18311 -43.228761)
			(xy 37.201348 -43.186096) (xy 37.205143 -43.17615) (xy 37.205151 -43.15489) (xy 37.201348 -43.144948)
			(xy 37.183114 -43.102281) (xy 37.154566 -43.013991) (xy 37.13537 -42.923207) (xy 37.125734 -42.830918)
			(xy 37.125148 -42.784522) (xy 37.125734 -42.738126) (xy 37.135377 -42.645838) (xy 37.154572 -42.555054)
			(xy 37.18311 -42.466761) (xy 37.201348 -42.424096) (xy 37.205143 -42.41415) (xy 37.205151 -42.39289)
			(xy 37.201348 -42.382948) (xy 37.183114 -42.340281) (xy 37.154566 -42.251991) (xy 37.13537 -42.161207)
			(xy 37.125734 -42.068918) (xy 37.125148 -42.022522) (xy 37.125652 -41.980174) (xy 37.133703 -41.89586)
			(xy 37.149732 -41.812694) (xy 37.173593 -41.731427) (xy 37.205072 -41.652797) (xy 37.243883 -41.577516)
			(xy 37.289673 -41.506264) (xy 37.342029 -41.439688) (xy 37.400477 -41.37839) (xy 37.464487 -41.322925)
			(xy 37.533479 -41.273796) (xy 37.606829 -41.231447) (xy 37.683872 -41.196263) (xy 37.763911 -41.168561)
			(xy 37.84622 -41.148593) (xy 37.930055 -41.13654) (xy 38.014656 -41.13251) (xy 38.099257 -41.13654)
			(xy 38.183092 -41.148593) (xy 38.265401 -41.168561) (xy 38.34544 -41.196263) (xy 38.422483 -41.231447)
			(xy 38.495833 -41.273796) (xy 38.564825 -41.322925) (xy 38.628835 -41.37839) (xy 38.687283 -41.439688)
			(xy 38.739639 -41.506264) (xy 38.785429 -41.577516) (xy 38.82424 -41.652797) (xy 38.855719 -41.731427)
			(xy 38.87958 -41.812694) (xy 38.895609 -41.89586) (xy 38.90366 -41.980174) (xy 38.904164 -42.022522)
			(xy 38.903557 -42.068917) (xy 38.89392 -42.161205) (xy 38.874731 -42.251989) (xy 38.846199 -42.340283)
			(xy 38.827964 -42.382948) (xy 38.824143 -42.392886) (xy 38.824151 -42.414154) (xy 38.827964 -42.424096)
			(xy 38.846213 -42.466756) (xy 38.874757 -42.555049) (xy 38.893949 -42.645835) (xy 38.90358 -42.738126)
			(xy 38.904164 -42.784522) (xy 38.903557 -42.830917) (xy 38.89392 -42.923205) (xy 38.874731 -43.013989)
			(xy 38.846199 -43.102283) (xy 38.827964 -43.144948) (xy 38.824143 -43.154886) (xy 38.824151 -43.176154)
			(xy 38.827964 -43.186096) (xy 38.846213 -43.228756) (xy 38.874757 -43.317049) (xy 38.893949 -43.407835)
			(xy 38.90358 -43.500126) (xy 38.904164 -43.546522) (xy 38.903557 -43.592917) (xy 38.89392 -43.685205)
			(xy 38.874731 -43.775989) (xy 38.846199 -43.864283) (xy 38.827964 -43.906948) (xy 38.824143 -43.916886)
			(xy 38.824151 -43.938154) (xy 38.827964 -43.948096) (xy 38.846213 -43.990756) (xy 38.874757 -44.079049)
			(xy 38.893949 -44.169835) (xy 38.90358 -44.262126) (xy 38.904164 -44.308522) (xy 38.90366 -44.35087)
			(xy 38.895609 -44.435184) (xy 38.87958 -44.51835) (xy 38.855719 -44.599617) (xy 38.82424 -44.678247)
			(xy 38.785429 -44.753528) (xy 38.739639 -44.82478) (xy 38.687283 -44.891356) (xy 38.628835 -44.952654)
			(xy 38.564825 -45.008119) (xy 38.495833 -45.057248) (xy 38.422483 -45.099597) (xy 38.34544 -45.134781)
			(xy 38.265401 -45.162483) (xy 38.183092 -45.182451) (xy 38.099257 -45.194504) (xy 38.014656 -45.198535)
			(xy 37.930055 -45.194504) (xy 37.84622 -45.182451) (xy 37.763911 -45.162483) (xy 37.683872 -45.134781)
			(xy 37.606829 -45.099597) (xy 37.533479 -45.057248) (xy 37.464487 -45.008119) (xy 37.400477 -44.952654)
			(xy 37.342029 -44.891356) (xy 37.289673 -44.82478) (xy 37.243883 -44.753528) (xy 37.205072 -44.678247)
			(xy 37.173593 -44.599617) (xy 37.149732 -44.51835) (xy 37.133703 -44.435184) (xy 37.125652 -44.35087)
			(xy 37.125148 -44.308522) (xy 12.95059 -44.308522) (xy 12.943406 -44.386037) (xy 12.928296 -44.466857)
			(xy 12.905791 -44.545939) (xy 12.876085 -44.622605) (xy 12.83943 -44.696204) (xy 12.796139 -44.766105)
			(xy 12.746583 -44.831713) (xy 12.691183 -44.892468) (xy 12.630412 -44.947851) (xy 12.564791 -44.99739)
			(xy 12.494877 -45.040661) (xy 12.421268 -45.077295) (xy 12.344593 -45.10698) (xy 12.265506 -45.129463)
			(xy 12.184681 -45.144551) (xy 12.102809 -45.152115) (xy 12.061698 -45.152564) (xy 12.015302 -45.151986)
			(xy 11.923014 -45.14234) (xy 11.83223 -45.123143) (xy 11.743937 -45.094603) (xy 11.701272 -45.076364)
			(xy 11.69133 -45.072558) (xy 11.670066 -45.072558) (xy 11.660124 -45.076364) (xy 11.617461 -45.094607)
			(xy 11.529169 -45.123152) (xy 11.438384 -45.142346) (xy 11.346094 -45.151979) (xy 11.299698 -45.152564)
			(xy 11.258591 -45.152089) (xy 11.176728 -45.144505) (xy 11.095914 -45.129401) (xy 11.016838 -45.106906)
			(xy 10.940174 -45.077212) (xy 10.866577 -45.040572) (xy 10.796673 -44.9973) (xy 10.73106 -44.947763)
			(xy 10.670296 -44.892384) (xy 10.6149 -44.831636) (xy 10.565344 -44.766036) (xy 10.522051 -44.696145)
			(xy 10.485391 -44.622558) (xy 10.455675 -44.545903) (xy 10.433157 -44.466833) (xy 10.41803 -44.386023)
			(xy 10.410422 -44.304163) (xy 10.409936 -44.263056) (xy 0.509016 -44.263056) (xy 0.509016 -46.391322)
			(xy 7.843012 -46.391322) (xy 7.843601 -46.344927) (xy 7.853244 -46.252638) (xy 7.872438 -46.161855)
			(xy 7.900975 -46.073561) (xy 7.919212 -46.030896) (xy 7.923003 -46.02095) (xy 7.923012 -45.99969)
			(xy 7.919212 -45.989748) (xy 7.900976 -45.947082) (xy 7.872429 -45.858791) (xy 7.853234 -45.768007)
			(xy 7.843598 -45.675718) (xy 7.843012 -45.629322) (xy 7.843516 -45.586974) (xy 7.851567 -45.50266)
			(xy 7.867596 -45.419494) (xy 7.891457 -45.338227) (xy 7.922936 -45.259597) (xy 7.961747 -45.184316)
			(xy 8.007537 -45.113064) (xy 8.059893 -45.046488) (xy 8.118341 -44.98519) (xy 8.182351 -44.929725)
			(xy 8.251343 -44.880596) (xy 8.324693 -44.838247) (xy 8.401736 -44.803063) (xy 8.481775 -44.775361)
			(xy 8.564084 -44.755393) (xy 8.647919 -44.74334) (xy 8.73252 -44.73931) (xy 8.817121 -44.74334) (xy 8.900956 -44.755393)
			(xy 8.983265 -44.775361) (xy 9.063304 -44.803063) (xy 9.140347 -44.838247) (xy 9.213697 -44.880596)
			(xy 9.282689 -44.929725) (xy 9.346699 -44.98519) (xy 9.405147 -45.046488) (xy 9.457503 -45.113064)
			(xy 9.503293 -45.184316) (xy 9.542104 -45.259597) (xy 9.573583 -45.338227) (xy 9.597444 -45.419494)
			(xy 9.613473 -45.50266) (xy 9.621524 -45.586974) (xy 9.622028 -45.629322) (xy 9.621416 -45.675717)
			(xy 9.611779 -45.768004) (xy 9.592592 -45.858788) (xy 9.564062 -45.947082) (xy 9.545828 -45.989748)
			(xy 9.542008 -45.999686) (xy 9.542017 -46.020954) (xy 9.545828 -46.030896) (xy 9.564081 -46.073555)
			(xy 9.592623 -46.161848) (xy 9.611813 -46.252635) (xy 9.621444 -46.344926) (xy 9.622028 -46.391322)
			(xy 9.621548 -46.434206) (xy 9.613284 -46.519576) (xy 9.596844 -46.603755) (xy 9.572382 -46.685961)
			(xy 9.540123 -46.765432) (xy 9.500367 -46.841431) (xy 9.453484 -46.913252) (xy 9.399908 -46.980229)
			(xy 9.340136 -47.04174) (xy 9.274724 -47.097215) (xy 9.204277 -47.146139) (xy 9.167114 -47.167546)
			(xy 9.154668 -47.174658) (xy 9.140698 -47.198788) (xy 9.143746 -47.317152) (xy 9.158478 -47.340774)
			(xy 9.171432 -47.347124) (xy 9.207964 -47.3659) (xy 9.277759 -47.409217) (xy 9.343264 -47.458783)
			(xy 9.403921 -47.514175) (xy 9.459215 -47.574923) (xy 9.508673 -47.640508) (xy 9.551877 -47.710373)
			(xy 9.588457 -47.783923) (xy 9.618102 -47.860531) (xy 9.640559 -47.939546) (xy 9.655638 -48.020294)
			(xy 9.663211 -48.102088) (xy 9.663684 -48.14316) (xy 9.663089 -48.189555) (xy 9.653448 -48.281843)
			(xy 9.634255 -48.372627) (xy 9.60572 -48.460921) (xy 9.587484 -48.503586) (xy 9.583703 -48.513536)
			(xy 9.583688 -48.534792) (xy 9.587484 -48.544734) (xy 9.605714 -48.587402) (xy 9.634262 -48.675692)
			(xy 9.65346 -48.766475) (xy 9.663097 -48.858764) (xy 9.663684 -48.90516) (xy 9.663201 -48.947324)
			(xy 9.655208 -49.031272) (xy 9.63931 -49.114087) (xy 9.615649 -49.195027) (xy 9.584436 -49.273366)
			(xy 9.545953 -49.348401) (xy 9.500544 -49.419458) (xy 9.448617 -49.485902) (xy 9.390637 -49.547135)
			(xy 9.327125 -49.602608) (xy 9.258649 -49.651824) (xy 9.222486 -49.67351) (xy 9.210802 -49.680368)
			(xy 9.197594 -49.703228) (xy 9.196324 -49.817782) (xy 9.209278 -49.840896) (xy 9.220962 -49.848008)
			(xy 9.256057 -49.86996) (xy 9.322433 -49.919432) (xy 9.383925 -49.974859) (xy 9.44 -50.03576) (xy 9.490173 -50.101608)
			(xy 9.53401 -50.171834) (xy 9.571132 -50.245829) (xy 9.601217 -50.322954) (xy 9.624005 -50.402541)
			(xy 9.639299 -50.4839) (xy 9.646967 -50.566329) (xy 9.647428 -50.607722) (xy 9.646816 -50.654117)
			(xy 9.637179 -50.746404) (xy 9.617992 -50.837188) (xy 9.589462 -50.925482) (xy 9.571228 -50.968148)
			(xy 9.567408 -50.978086) (xy 9.567417 -50.999354) (xy 9.571228 -51.009296) (xy 9.589481 -51.051955)
			(xy 9.618023 -51.140248) (xy 9.637213 -51.231035) (xy 9.646844 -51.323326) (xy 9.647428 -51.369722)
			(xy 9.646924 -51.41207) (xy 9.638873 -51.496384) (xy 9.622844 -51.57955) (xy 9.598983 -51.660817)
			(xy 9.567504 -51.739447) (xy 9.528693 -51.814728) (xy 9.482903 -51.88598) (xy 9.430547 -51.952556)
			(xy 9.372099 -52.013854) (xy 9.308089 -52.069319) (xy 9.239097 -52.118448) (xy 9.165747 -52.160797)
			(xy 9.088704 -52.195981) (xy 9.008665 -52.223683) (xy 8.926356 -52.243651) (xy 8.842521 -52.255704)
			(xy 8.75792 -52.259735) (xy 8.673319 -52.255704) (xy 8.589484 -52.243651) (xy 8.507175 -52.223683)
			(xy 8.427136 -52.195981) (xy 8.350093 -52.160797) (xy 8.276743 -52.118448) (xy 8.207751 -52.069319)
			(xy 8.143741 -52.013854) (xy 8.085293 -51.952556) (xy 8.032937 -51.88598) (xy 7.987147 -51.814728)
			(xy 7.948336 -51.739447) (xy 7.916857 -51.660817) (xy 7.892996 -51.57955) (xy 7.876967 -51.496384)
			(xy 7.868916 -51.41207) (xy 7.868412 -51.369722) (xy 7.869001 -51.323327) (xy 7.878644 -51.231038)
			(xy 7.897838 -51.140255) (xy 7.926375 -51.051961) (xy 7.944612 -51.009296) (xy 7.948403 -50.99935)
			(xy 7.948412 -50.97809) (xy 7.944612 -50.968148) (xy 7.926376 -50.925482) (xy 7.897829 -50.837191)
			(xy 7.878634 -50.746407) (xy 7.868998 -50.654118) (xy 7.868412 -50.607722) (xy 7.868883 -50.565558)
			(xy 7.876877 -50.48161) (xy 7.892777 -50.398794) (xy 7.916439 -50.317854) (xy 7.947653 -50.239515)
			(xy 7.986137 -50.16448) (xy 8.031547 -50.093423) (xy 8.083476 -50.02698) (xy 8.141457 -49.965747)
			(xy 8.20497 -49.910274) (xy 8.273447 -49.861058) (xy 8.30961 -49.839372) (xy 8.321294 -49.832514)
			(xy 8.334502 -49.809654) (xy 8.335772 -49.6951) (xy 8.322818 -49.671986) (xy 8.311134 -49.664874)
			(xy 8.276036 -49.642926) (xy 8.20966 -49.593453) (xy 8.148169 -49.538026) (xy 8.092093 -49.477125)
			(xy 8.04192 -49.411276) (xy 7.998083 -49.34105) (xy 7.960962 -49.267054) (xy 7.930877 -49.189929)
			(xy 7.908089 -49.110342) (xy 7.892796 -49.028982) (xy 7.885129 -48.946553) (xy 7.884668 -48.90516)
			(xy 7.885274 -48.858765) (xy 7.894913 -48.766477) (xy 7.914102 -48.675694) (xy 7.942634 -48.587399)
			(xy 7.960868 -48.544734) (xy 7.964699 -48.534799) (xy 7.964683 -48.513528) (xy 7.960868 -48.503586)
			(xy 7.942609 -48.46093) (xy 7.914069 -48.372635) (xy 7.89488 -48.281848) (xy 7.885251 -48.189557)
			(xy 7.884668 -48.14316) (xy 7.885135 -48.100275) (xy 7.893401 -48.014905) (xy 7.909842 -47.930726)
			(xy 7.934306 -47.84852) (xy 7.966567 -47.769049) (xy 8.006323 -47.69305) (xy 8.053208 -47.621229)
			(xy 8.106785 -47.554252) (xy 8.166558 -47.492741) (xy 8.231971 -47.437267) (xy 8.302419 -47.388343)
			(xy 8.339582 -47.366936) (xy 8.352028 -47.359824) (xy 8.365998 -47.335694) (xy 8.36295 -47.21733)
			(xy 8.348218 -47.193708) (xy 8.335264 -47.187358) (xy 8.298736 -47.168575) (xy 8.228941 -47.125258)
			(xy 8.163437 -47.075693) (xy 8.10278 -47.020301) (xy 8.047486 -46.959554) (xy 7.998027 -46.89397)
			(xy 7.954823 -46.824105) (xy 7.918243 -46.750556) (xy 7.888598 -46.673949) (xy 7.866139 -46.594935)
			(xy 7.851059 -46.514187) (xy 7.843486 -46.432394) (xy 7.843012 -46.391322) (xy 0.509016 -46.391322)
			(xy 0.509016 -53.448712) (xy 6.524752 -53.448712) (xy 6.52535 -53.402309) (xy 6.535049 -53.310011)
			(xy 6.554311 -53.219226) (xy 6.582926 -53.130941) (xy 6.601206 -53.088286) (xy 6.605004 -53.078341)
			(xy 6.605008 -53.05708) (xy 6.601206 -53.047138) (xy 6.582946 -53.004476) (xy 6.554353 -52.916188)
			(xy 6.535095 -52.825406) (xy 6.525382 -52.733113) (xy 6.524752 -52.686712) (xy 6.525256 -52.644351)
			(xy 6.533309 -52.560014) (xy 6.549343 -52.476824) (xy 6.573211 -52.395534) (xy 6.604699 -52.316882)
			(xy 6.643521 -52.241579) (xy 6.689324 -52.170307) (xy 6.741695 -52.103711) (xy 6.80016 -52.042396)
			(xy 6.864188 -51.986915) (xy 6.9332 -51.937772) (xy 7.00657 -51.895412) (xy 7.083635 -51.860217)
			(xy 7.163697 -51.832508) (xy 7.24603 -51.812534) (xy 7.329889 -51.800477) (xy 7.414514 -51.796446)
			(xy 7.499139 -51.800477) (xy 7.582998 -51.812534) (xy 7.665331 -51.832508) (xy 7.745393 -51.860217)
			(xy 7.822458 -51.895412) (xy 7.895828 -51.937772) (xy 7.96484 -51.986915) (xy 8.028868 -52.042396)
			(xy 8.087333 -52.103711) (xy 8.139704 -52.170307) (xy 8.185507 -52.241579) (xy 8.224329 -52.316882)
			(xy 8.255817 -52.395534) (xy 8.279685 -52.476824) (xy 8.295719 -52.560014) (xy 8.303772 -52.644351)
			(xy 8.304276 -52.686712) (xy 8.303649 -52.733114) (xy 8.293958 -52.825411) (xy 8.274705 -52.916197)
			(xy 8.265527 -52.944522) (xy 40.985948 -52.944522) (xy 40.986534 -52.898126) (xy 40.996177 -52.805838)
			(xy 41.015372 -52.715054) (xy 41.04391 -52.626761) (xy 41.062148 -52.584096) (xy 41.065943 -52.57415)
			(xy 41.065951 -52.55289) (xy 41.062148 -52.542948) (xy 41.043914 -52.500281) (xy 41.015366 -52.411991)
			(xy 40.99617 -52.321207) (xy 40.986534 -52.228918) (xy 40.985948 -52.182522) (xy 40.986456 -52.139301)
			(xy 40.99482 -52.053265) (xy 41.01149 -51.968446) (xy 41.036308 -51.885644) (xy 41.069042 -51.80564)
			(xy 41.109382 -51.729188) (xy 41.156948 -51.65701) (xy 41.21129 -51.589786) (xy 41.271897 -51.528151)
			(xy 41.304718 -51.500024) (xy 41.313354 -51.492912) (xy 41.322752 -51.473354) (xy 41.324276 -51.37404)
			(xy 41.31564 -51.353974) (xy 41.307258 -51.346608) (xy 41.276644 -51.318528) (xy 41.220205 -51.257563)
			(xy 41.169699 -51.1916) (xy 41.125564 -51.121215) (xy 41.088186 -51.04702) (xy 41.05789 -50.969663)
			(xy 41.034941 -50.889818) (xy 41.019538 -50.80818) (xy 41.011816 -50.725461) (xy 41.011348 -50.683922)
			(xy 41.011934 -50.637526) (xy 41.021577 -50.545238) (xy 41.040772 -50.454454) (xy 41.06931 -50.366161)
			(xy 41.087548 -50.323496) (xy 41.091343 -50.31355) (xy 41.091351 -50.29229) (xy 41.087548 -50.282348)
			(xy 41.069314 -50.239681) (xy 41.040766 -50.151391) (xy 41.02157 -50.060607) (xy 41.011934 -49.968318)
			(xy 41.011348 -49.921922) (xy 41.011872 -49.878278) (xy 41.020417 -49.79141) (xy 41.037428 -49.705796)
			(xy 41.062742 -49.622259) (xy 41.096114 -49.541602) (xy 41.137223 -49.464601) (xy 41.185676 -49.391996)
			(xy 41.241006 -49.324485) (xy 41.30268 -49.262716) (xy 41.370107 -49.207284) (xy 41.442639 -49.158721)
			(xy 41.519577 -49.117494) (xy 41.600183 -49.083999) (xy 41.641776 -49.070768) (xy 41.657524 -49.065942)
			(xy 41.677336 -49.040034) (xy 41.680892 -48.910748) (xy 41.662604 -48.883824) (xy 41.64711 -48.878236)
			(xy 41.60801 -48.863456) (xy 41.532505 -48.82758) (xy 41.460698 -48.784781) (xy 41.393222 -48.735435)
			(xy 41.330672 -48.679977) (xy 41.273599 -48.618897) (xy 41.222507 -48.552733) (xy 41.177846 -48.482069)
			(xy 41.14001 -48.407527) (xy 41.109332 -48.329765) (xy 41.086084 -48.249468) (xy 41.070469 -48.167345)
			(xy 41.062626 -48.084119) (xy 41.062148 -48.042322) (xy 41.062734 -47.995926) (xy 41.072377 -47.903638)
			(xy 41.091572 -47.812854) (xy 41.12011 -47.724561) (xy 41.138348 -47.681896) (xy 41.142143 -47.67195)
			(xy 41.142151 -47.65069) (xy 41.138348 -47.640748) (xy 41.120114 -47.598081) (xy 41.091566 -47.509791)
			(xy 41.07237 -47.419007) (xy 41.062734 -47.326718) (xy 41.062148 -47.280322) (xy 41.062652 -47.237974)
			(xy 41.070703 -47.15366) (xy 41.086732 -47.070494) (xy 41.110593 -46.989227) (xy 41.142072 -46.910597)
			(xy 41.180883 -46.835316) (xy 41.226673 -46.764064) (xy 41.279029 -46.697488) (xy 41.337477 -46.63619)
			(xy 41.401487 -46.580725) (xy 41.470479 -46.531596) (xy 41.543829 -46.489247) (xy 41.620872 -46.454063)
			(xy 41.700911 -46.426361) (xy 41.78322 -46.406393) (xy 41.867055 -46.39434) (xy 41.951656 -46.39031)
			(xy 42.036257 -46.39434) (xy 42.120092 -46.406393) (xy 42.202401 -46.426361) (xy 42.28244 -46.454063)
			(xy 42.359483 -46.489247) (xy 42.432833 -46.531596) (xy 42.501825 -46.580725) (xy 42.565835 -46.63619)
			(xy 42.624283 -46.697488) (xy 42.676639 -46.764064) (xy 42.722429 -46.835316) (xy 42.76124 -46.910597)
			(xy 42.792719 -46.989227) (xy 42.81658 -47.070494) (xy 42.832609 -47.15366) (xy 42.84066 -47.237974)
			(xy 42.841164 -47.280322) (xy 42.840557 -47.326717) (xy 42.83092 -47.419005) (xy 42.811731 -47.509789)
			(xy 42.783199 -47.598083) (xy 42.764964 -47.640748) (xy 42.761143 -47.650686) (xy 42.761151 -47.671954)
			(xy 42.764964 -47.681896) (xy 42.783213 -47.724556) (xy 42.811757 -47.812849) (xy 42.830949 -47.903635)
			(xy 42.84058 -47.995926) (xy 42.841164 -48.042322) (xy 42.840581 -48.085965) (xy 42.832041 -48.172831)
			(xy 42.815035 -48.258443) (xy 42.789727 -48.341979) (xy 42.756361 -48.422635) (xy 42.715256 -48.499635)
			(xy 42.666809 -48.57224) (xy 42.611484 -48.639752) (xy 42.549814 -48.701522) (xy 42.482391 -48.756955)
			(xy 42.409864 -48.805519) (xy 42.33293 -48.846748) (xy 42.252328 -48.880244) (xy 42.210736 -48.893476)
			(xy 42.194988 -48.898302) (xy 42.175176 -48.92421) (xy 42.17162 -49.053496) (xy 42.189908 -49.08042)
			(xy 42.205402 -49.086008) (xy 42.244519 -49.100744) (xy 42.320025 -49.136623) (xy 42.391833 -49.179426)
			(xy 42.45931 -49.228776) (xy 42.52186 -49.284237) (xy 42.578932 -49.345321) (xy 42.630023 -49.411489)
			(xy 42.674683 -49.482157) (xy 42.712517 -49.556702) (xy 42.743192 -49.634468) (xy 42.766437 -49.714768)
			(xy 42.782049 -49.796895) (xy 42.789888 -49.880123) (xy 42.790364 -49.921922) (xy 42.789757 -49.968317)
			(xy 42.78012 -50.060605) (xy 42.760931 -50.151389) (xy 42.732399 -50.239683) (xy 42.714164 -50.282348)
			(xy 42.710343 -50.292286) (xy 42.710351 -50.313554) (xy 42.714164 -50.323496) (xy 42.732413 -50.366156)
			(xy 42.760957 -50.454449) (xy 42.780149 -50.545235) (xy 42.78978 -50.637526) (xy 42.790364 -50.683922)
			(xy 42.789883 -50.727144) (xy 42.781515 -50.813181) (xy 42.764842 -50.898) (xy 42.740019 -50.980802)
			(xy 42.707282 -51.060807) (xy 42.666939 -51.137258) (xy 42.619371 -51.209436) (xy 42.565025 -51.276659)
			(xy 42.504416 -51.338294) (xy 42.471594 -51.36642) (xy 42.462958 -51.373532) (xy 42.45356 -51.39309)
			(xy 42.452036 -51.492404) (xy 42.460672 -51.51247) (xy 42.469054 -51.519836) (xy 42.499692 -51.547891)
			(xy 42.556129 -51.608859) (xy 42.606634 -51.674825) (xy 42.650766 -51.745214) (xy 42.688142 -51.819412)
			(xy 42.718435 -51.896773) (xy 42.741381 -51.976621) (xy 42.75678 -52.058261) (xy 42.764498 -52.140982)
			(xy 42.764964 -52.182522) (xy 42.764357 -52.228917) (xy 42.75472 -52.321205) (xy 42.735531 -52.411989)
			(xy 42.706999 -52.500283) (xy 42.688764 -52.542948) (xy 42.684943 -52.552886) (xy 42.684951 -52.574154)
			(xy 42.688764 -52.584096) (xy 42.707013 -52.626756) (xy 42.735557 -52.715049) (xy 42.754749 -52.805835)
			(xy 42.76438 -52.898126) (xy 42.764964 -52.944522) (xy 42.764411 -52.98961) (xy 42.75534 -53.079327)
			(xy 42.737232 -53.167664) (xy 42.710273 -53.253714) (xy 42.674742 -53.336593) (xy 42.631001 -53.415449)
			(xy 42.605706 -53.452776) (xy 42.596816 -53.465222) (xy 42.596054 -53.49494) (xy 42.660062 -53.600604)
			(xy 42.686732 -53.613558) (xy 42.701972 -53.611526) (xy 42.730168 -53.608102) (xy 42.786854 -53.604417)
			(xy 42.815256 -53.60416) (xy 42.856365 -53.604694) (xy 42.938232 -53.612278) (xy 43.019051 -53.627384)
			(xy 43.09813 -53.649885) (xy 43.174795 -53.679587) (xy 43.248392 -53.716237) (xy 43.318293 -53.759523)
			(xy 43.3839 -53.809075) (xy 43.444655 -53.864471) (xy 43.500038 -53.925237) (xy 43.549577 -53.990854)
			(xy 43.59285 -54.060763) (xy 43.629485 -54.134368) (xy 43.659172 -54.211039) (xy 43.681657 -54.290123)
			(xy 43.696747 -54.370944) (xy 43.704314 -54.452813) (xy 43.704764 -54.493922) (xy 43.704157 -54.540317)
			(xy 43.69452 -54.632605) (xy 43.675331 -54.723389) (xy 43.646799 -54.811683) (xy 43.628564 -54.854348)
			(xy 43.624743 -54.864286) (xy 43.624751 -54.885554) (xy 43.628564 -54.895496) (xy 43.646813 -54.938156)
			(xy 43.675357 -55.026449) (xy 43.694549 -55.117235) (xy 43.70418 -55.209526) (xy 43.704764 -55.255922)
			(xy 43.70426 -55.29827) (xy 43.696209 -55.382584) (xy 43.68018 -55.46575) (xy 43.656319 -55.547017)
			(xy 43.62484 -55.625647) (xy 43.586029 -55.700928) (xy 43.540239 -55.77218) (xy 43.487883 -55.838756)
			(xy 43.429435 -55.900054) (xy 43.365425 -55.955519) (xy 43.296433 -56.004648) (xy 43.223083 -56.046997)
			(xy 43.14604 -56.082181) (xy 43.066001 -56.109883) (xy 42.983692 -56.129851) (xy 42.899857 -56.141904)
			(xy 42.815256 -56.145935) (xy 42.730655 -56.141904) (xy 42.64682 -56.129851) (xy 42.564511 -56.109883)
			(xy 42.484472 -56.082181) (xy 42.407429 -56.046997) (xy 42.334079 -56.004648) (xy 42.265087 -55.955519)
			(xy 42.201077 -55.900054) (xy 42.142629 -55.838756) (xy 42.090273 -55.77218) (xy 42.044483 -55.700928)
			(xy 42.005672 -55.625647) (xy 41.974193 -55.547017) (xy 41.950332 -55.46575) (xy 41.934303 -55.382584)
			(xy 41.926252 -55.29827) (xy 41.925748 -55.255922) (xy 41.926334 -55.209526) (xy 41.935977 -55.117238)
			(xy 41.955172 -55.026454) (xy 41.98371 -54.938161) (xy 42.001948 -54.895496) (xy 42.005743 -54.88555)
			(xy 42.005751 -54.86429) (xy 42.001948 -54.854348) (xy 41.983714 -54.811681) (xy 41.955166 -54.723391)
			(xy 41.93597 -54.632607) (xy 41.926334 -54.540318) (xy 41.925748 -54.493922) (xy 41.92627 -54.448834)
			(xy 41.935347 -54.359116) (xy 41.95346 -54.270777) (xy 41.980425 -54.184727) (xy 42.015962 -54.101849)
			(xy 42.059708 -54.022994) (xy 42.085006 -53.985668) (xy 42.093896 -53.973222) (xy 42.094658 -53.943504)
			(xy 42.03065 -53.83784) (xy 42.00398 -53.824886) (xy 41.98874 -53.826918) (xy 41.960544 -53.830341)
			(xy 41.903858 -53.834027) (xy 41.875456 -53.834284) (xy 41.834344 -53.833889) (xy 41.752471 -53.826297)
			(xy 41.671648 -53.811182) (xy 41.592565 -53.788673) (xy 41.515897 -53.758962) (xy 41.442297 -53.722302)
			(xy 41.372395 -53.679007) (xy 41.306786 -53.629445) (xy 41.246032 -53.57404) (xy 41.190649 -53.513266)
			(xy 41.141111 -53.447639) (xy 41.097841 -53.377721) (xy 41.061208 -53.304109) (xy 41.031525 -53.22743)
			(xy 41.009044 -53.148338) (xy 40.993958 -53.06751) (xy 40.986396 -52.985634) (xy 40.985948 -52.944522)
			(xy 8.265527 -52.944522) (xy 8.246097 -53.004482) (xy 8.227822 -53.047138) (xy 8.224009 -53.057078)
			(xy 8.224013 -53.078344) (xy 8.227822 -53.088286) (xy 8.246092 -53.130944) (xy 8.274682 -53.219233)
			(xy 8.293937 -53.310017) (xy 8.303648 -53.402311) (xy 8.304276 -53.448712) (xy 8.303772 -53.491073)
			(xy 8.295719 -53.57541) (xy 8.279685 -53.6586) (xy 8.255817 -53.73989) (xy 8.224329 -53.818542) (xy 8.185507 -53.893845)
			(xy 8.139704 -53.965117) (xy 8.087333 -54.031713) (xy 8.028868 -54.093028) (xy 7.96484 -54.148509)
			(xy 7.895828 -54.197652) (xy 7.822458 -54.240012) (xy 7.745393 -54.275207) (xy 7.665331 -54.302916)
			(xy 7.582998 -54.32289) (xy 7.499139 -54.334947) (xy 7.414514 -54.338979) (xy 7.329889 -54.334947)
			(xy 7.24603 -54.32289) (xy 7.163697 -54.302916) (xy 7.083635 -54.275207) (xy 7.00657 -54.240012)
			(xy 6.9332 -54.197652) (xy 6.864188 -54.148509) (xy 6.80016 -54.093028) (xy 6.741695 -54.031713)
			(xy 6.689324 -53.965117) (xy 6.643521 -53.893845) (xy 6.604699 -53.818542) (xy 6.573211 -53.73989)
			(xy 6.549343 -53.6586) (xy 6.533309 -53.57541) (xy 6.525256 -53.491073) (xy 6.524752 -53.448712)
			(xy 0.509016 -53.448712) (xy 0.509016 -58.913776) (xy 2.815336 -58.913776) (xy 2.815734 -58.875486)
			(xy 2.822344 -58.799192) (xy 2.835496 -58.723749) (xy 2.855091 -58.649719) (xy 2.86766 -58.613548)
			(xy 2.870323 -58.605114) (xy 2.870315 -58.587441) (xy 2.86766 -58.579004) (xy 2.855117 -58.542826)
			(xy 2.835544 -58.468793) (xy 2.822397 -58.393354) (xy 2.815772 -58.317064) (xy 2.815336 -58.278776)
			(xy 2.815789 -58.237665) (xy 2.823377 -58.155794) (xy 2.838488 -58.074973) (xy 2.860993 -57.995892)
			(xy 2.890701 -57.919224) (xy 2.927357 -57.845626) (xy 2.970648 -57.775724) (xy 3.020206 -57.710116)
			(xy 3.075607 -57.649361) (xy 3.136378 -57.593978) (xy 3.202001 -57.54444) (xy 3.271915 -57.501169)
			(xy 3.345524 -57.464535) (xy 3.4222 -57.43485) (xy 3.501289 -57.412368) (xy 3.582114 -57.397281)
			(xy 3.663987 -57.389717) (xy 3.705098 -57.389268) (xy 3.744024 -57.38968) (xy 3.821581 -57.396458)
			(xy 3.898248 -57.409989) (xy 3.97344 -57.430169) (xy 4.010152 -57.443116) (xy 4.018701 -57.44588)
			(xy 4.036655 -57.44588) (xy 4.045204 -57.443116) (xy 4.081915 -57.430165) (xy 4.157107 -57.409985)
			(xy 4.233775 -57.396453) (xy 4.311332 -57.389672) (xy 4.350258 -57.389268) (xy 4.389185 -57.389662)
			(xy 4.466742 -57.396445) (xy 4.543409 -57.409981) (xy 4.6186 -57.430167) (xy 4.655312 -57.443116)
			(xy 4.663861 -57.44588) (xy 4.681815 -57.44588) (xy 4.690364 -57.443116) (xy 4.727079 -57.430176)
			(xy 4.802269 -57.409993) (xy 4.878936 -57.396458) (xy 4.956492 -57.389674) (xy 4.995418 -57.389268)
			(xy 5.036525 -57.389744) (xy 5.118388 -57.397329) (xy 5.199202 -57.412432) (xy 5.278278 -57.434927)
			(xy 5.354942 -57.464621) (xy 5.428539 -57.50126) (xy 5.498443 -57.544533) (xy 5.564057 -57.59407)
			(xy 5.624821 -57.649448) (xy 5.680217 -57.710196) (xy 5.729773 -57.775796) (xy 5.773065 -57.845687)
			(xy 5.809726 -57.919274) (xy 5.839442 -57.995929) (xy 5.861959 -58.074999) (xy 5.877086 -58.155809)
			(xy 5.884694 -58.237669) (xy 5.88518 -58.278776) (xy 5.884767 -58.317066) (xy 5.878161 -58.39336)
			(xy 5.865014 -58.468802) (xy 5.845423 -58.542833) (xy 5.832856 -58.579004) (xy 5.830217 -58.587444)
			(xy 5.830209 -58.605112) (xy 5.832856 -58.613548) (xy 5.839714 -58.63336) (xy 5.84454 -58.647838)
			(xy 5.868162 -58.666634) (xy 5.991098 -58.67781) (xy 6.017768 -58.663586) (xy 6.025134 -58.650378)
			(xy 6.046362 -58.612722) (xy 6.095116 -58.541331) (xy 6.150565 -58.475008) (xy 6.212188 -58.414376)
			(xy 6.279401 -58.360008) (xy 6.351572 -58.312417) (xy 6.428019 -58.272052) (xy 6.508022 -58.239294)
			(xy 6.590825 -58.214451) (xy 6.675647 -58.197758) (xy 6.761689 -58.189373) (xy 6.804914 -58.18886)
			(xy 6.843846 -58.189297) (xy 6.921408 -58.196139) (xy 6.998076 -58.209736) (xy 7.073261 -58.229982)
			(xy 7.109968 -58.242962) (xy 7.118517 -58.245726) (xy 7.136471 -58.245726) (xy 7.14502 -58.242962)
			(xy 7.181726 -58.229981) (xy 7.256913 -58.209741) (xy 7.333581 -58.196145) (xy 7.411142 -58.189298)
			(xy 7.450074 -58.18886) (xy 7.489005 -58.189309) (xy 7.566568 -58.196148) (xy 7.643235 -58.209741)
			(xy 7.718421 -58.229984) (xy 7.755128 -58.242962) (xy 7.763677 -58.245726) (xy 7.781631 -58.245726)
			(xy 7.79018 -58.242962) (xy 7.82689 -58.229993) (xy 7.902076 -58.209749) (xy 7.978742 -58.19615)
			(xy 8.056303 -58.1893) (xy 8.095234 -58.18886) (xy 8.136348 -58.189329) (xy 8.218226 -58.196917)
			(xy 8.299055 -58.212026) (xy 8.378144 -58.23453) (xy 8.45482 -58.264234) (xy 8.528428 -58.300887)
			(xy 8.59834 -58.344175) (xy 8.66396 -58.393729) (xy 8.724728 -58.449127) (xy 8.750967 -58.47791)
			(xy 9.058409 -58.47791) (xy 9.06244 -58.393309) (xy 9.074493 -58.309475) (xy 9.094461 -58.227165)
			(xy 9.122163 -58.147127) (xy 9.157347 -58.070084) (xy 9.199695 -57.996735) (xy 9.248824 -57.927743)
			(xy 9.304288 -57.863733) (xy 9.365586 -57.805286) (xy 9.432162 -57.75293) (xy 9.503414 -57.707139)
			(xy 9.578695 -57.668329) (xy 9.657325 -57.63685) (xy 9.73859 -57.612988) (xy 9.821756 -57.596959)
			(xy 9.90607 -57.588908) (xy 9.948418 -57.588404) (xy 9.994814 -57.588979) (xy 10.087102 -57.598627)
			(xy 10.177886 -57.617825) (xy 10.266179 -57.646365) (xy 10.308844 -57.664604) (xy 10.318786 -57.66841)
			(xy 10.34005 -57.66841) (xy 10.349992 -57.664604) (xy 10.392652 -57.646354) (xy 10.480945 -57.617811)
			(xy 10.571731 -57.59862) (xy 10.664022 -57.588988) (xy 10.710418 -57.588404) (xy 10.752003 -57.588903)
			(xy 10.834811 -57.596646) (xy 10.916535 -57.612083) (xy 10.996463 -57.635078) (xy 11.073896 -57.66543)
			(xy 11.148159 -57.702875) (xy 11.218604 -57.747086) (xy 11.284616 -57.797678) (xy 11.34562 -57.854208)
			(xy 11.401083 -57.916184) (xy 11.42619 -57.949338) (xy 11.433302 -57.959244) (xy 11.454892 -57.970166)
			(xy 11.561064 -57.969912) (xy 11.582654 -57.95899) (xy 11.589766 -57.949084) (xy 11.614799 -57.915623)
			(xy 11.670256 -57.853101) (xy 11.731334 -57.796058) (xy 11.797494 -57.744996) (xy 11.868153 -57.700367)
			(xy 11.942687 -57.662563) (xy 12.020439 -57.631918) (xy 12.100722 -57.608702) (xy 12.18283 -57.59312)
			(xy 12.266037 -57.58531) (xy 12.307824 -57.584848) (xy 12.354219 -57.585453) (xy 12.446507 -57.595091)
			(xy 12.537291 -57.61428) (xy 12.625585 -57.642813) (xy 12.66825 -57.661048) (xy 12.678192 -57.664854)
			(xy 12.699456 -57.664854) (xy 12.709398 -57.661048) (xy 12.752058 -57.642799) (xy 12.840351 -57.614255)
			(xy 12.931137 -57.595063) (xy 13.023428 -57.585432) (xy 13.069824 -57.584848) (xy 13.116219 -57.585453)
			(xy 13.208507 -57.595091) (xy 13.299291 -57.61428) (xy 13.387585 -57.642813) (xy 13.43025 -57.661048)
			(xy 13.440192 -57.664854) (xy 13.461456 -57.664854) (xy 13.471398 -57.661048) (xy 13.514058 -57.642799)
			(xy 13.602351 -57.614255) (xy 13.693137 -57.595063) (xy 13.785428 -57.585432) (xy 13.831824 -57.584848)
			(xy 13.872926 -57.585323) (xy 13.954781 -57.592908) (xy 14.035586 -57.608013) (xy 14.114652 -57.63051)
			(xy 14.191306 -57.660206) (xy 14.264893 -57.696848) (xy 14.334785 -57.740124) (xy 14.400386 -57.789663)
			(xy 14.461136 -57.845044) (xy 14.516517 -57.905794) (xy 14.566056 -57.971395) (xy 14.609332 -58.041287)
			(xy 14.645974 -58.114874) (xy 14.67567 -58.191528) (xy 14.698167 -58.270594) (xy 14.713272 -58.351399)
			(xy 14.720857 -58.433254) (xy 14.721332 -58.474356) (xy 14.720939 -58.514124) (xy 14.713894 -58.593347)
			(xy 14.699801 -58.671624) (xy 14.678774 -58.748329) (xy 14.650981 -58.822851) (xy 14.63421 -58.858912)
			(xy 14.629682 -58.869586) (xy 14.629806 -58.892745) (xy 14.634464 -58.903362) (xy 14.639471 -58.913776)
			(xy 34.212784 -58.913776) (xy 34.21322 -58.873695) (xy 34.220435 -58.79386) (xy 34.234805 -58.714997)
			(xy 34.256212 -58.637747) (xy 34.269934 -58.600086) (xy 34.27267 -58.591745) (xy 34.272943 -58.574209)
			(xy 34.270442 -58.565796) (xy 34.255367 -58.519464) (xy 34.234216 -58.42435) (xy 34.22359 -58.327495)
			(xy 34.222944 -58.278776) (xy 34.223444 -58.237675) (xy 34.23103 -58.155822) (xy 34.246136 -58.075019)
			(xy 34.268633 -57.995955) (xy 34.298329 -57.919303) (xy 34.33497 -57.845718) (xy 34.378244 -57.775828)
			(xy 34.427782 -57.710228) (xy 34.483162 -57.649479) (xy 34.543909 -57.594098) (xy 34.609508 -57.544558)
			(xy 34.679397 -57.501282) (xy 34.752981 -57.464639) (xy 34.829632 -57.434941) (xy 34.908696 -57.412442)
			(xy 34.989499 -57.397334) (xy 35.071351 -57.389745) (xy 35.112452 -57.389268) (xy 35.152022 -57.38968)
			(xy 35.23085 -57.396689) (xy 35.308744 -57.410674) (xy 35.385087 -57.431524) (xy 35.422332 -57.444894)
			(xy 35.431001 -57.447724) (xy 35.449223 -57.447724) (xy 35.457892 -57.444894) (xy 35.495135 -57.43152)
			(xy 35.57148 -57.410675) (xy 35.649374 -57.396694) (xy 35.728202 -57.389687) (xy 35.767772 -57.389268)
			(xy 35.806698 -57.389687) (xy 35.884255 -57.396463) (xy 35.960922 -57.409992) (xy 36.036113 -57.430171)
			(xy 36.072826 -57.443116) (xy 36.081375 -57.44588) (xy 36.099329 -57.44588) (xy 36.107878 -57.443116)
			(xy 36.144591 -57.430172) (xy 36.219782 -57.40999) (xy 36.296449 -57.396456) (xy 36.374006 -57.389673)
			(xy 36.412932 -57.389268) (xy 36.454034 -57.389736) (xy 36.535888 -57.397324) (xy 36.616693 -57.412431)
			(xy 36.695759 -57.434929) (xy 36.772411 -57.464627) (xy 36.845997 -57.50127) (xy 36.915889 -57.544546)
			(xy 36.981489 -57.594086) (xy 37.042238 -57.649467) (xy 37.097619 -57.710217) (xy 37.147159 -57.775818)
			(xy 37.190434 -57.84571) (xy 37.227077 -57.919296) (xy 37.256773 -57.995949) (xy 37.279271 -58.075015)
			(xy 37.294378 -58.15582) (xy 37.301964 -58.237674) (xy 37.30244 -58.278776) (xy 37.302073 -58.317061)
			(xy 37.295527 -58.39335) (xy 37.28244 -58.468792) (xy 37.262908 -58.542828) (xy 37.25037 -58.579004)
			(xy 37.24773 -58.587444) (xy 37.247722 -58.605112) (xy 37.25037 -58.613548) (xy 37.257228 -58.63336)
			(xy 37.262054 -58.647838) (xy 37.285676 -58.666634) (xy 37.408612 -58.67781) (xy 37.435282 -58.663586)
			(xy 37.442648 -58.650378) (xy 37.463866 -58.612716) (xy 37.51262 -58.541325) (xy 37.568071 -58.475001)
			(xy 37.629694 -58.41437) (xy 37.696909 -58.360002) (xy 37.769081 -58.312412) (xy 37.845529 -58.272047)
			(xy 37.925533 -58.23929) (xy 38.008337 -58.214448) (xy 38.09316 -58.197756) (xy 38.179203 -58.189372)
			(xy 38.222428 -58.18886) (xy 38.26136 -58.189292) (xy 38.338922 -58.196136) (xy 38.41559 -58.209734)
			(xy 38.490775 -58.229982) (xy 38.527482 -58.242962) (xy 38.536031 -58.245726) (xy 38.553985 -58.245726)
			(xy 38.562534 -58.242962) (xy 38.599239 -58.229977) (xy 38.674426 -58.209738) (xy 38.751094 -58.196144)
			(xy 38.828656 -58.189298) (xy 38.867588 -58.18886) (xy 38.90652 -58.189304) (xy 38.984082 -58.196145)
			(xy 39.060749 -58.209739) (xy 39.135935 -58.229984) (xy 39.172642 -58.242962) (xy 39.181191 -58.245726)
			(xy 39.199145 -58.245726) (xy 39.207694 -58.242962) (xy 39.244403 -58.229989) (xy 39.319589 -58.209746)
			(xy 39.396255 -58.196149) (xy 39.473817 -58.189299) (xy 39.512748 -58.18886) (xy 39.553858 -58.189307)
			(xy 39.635728 -58.196898) (xy 39.716548 -58.212013) (xy 39.795628 -58.234521) (xy 39.872294 -58.26423)
			(xy 39.945891 -58.300887) (xy 40.015792 -58.344179) (xy 40.081399 -58.393737) (xy 40.142153 -58.449138)
			(xy 40.197535 -58.509909) (xy 40.243351 -58.5706) (xy 40.517355 -58.5706) (xy 40.521387 -58.485978)
			(xy 40.533443 -58.402122) (xy 40.553416 -58.319791) (xy 40.581124 -58.239732) (xy 40.616317 -58.16267)
			(xy 40.658676 -58.089301) (xy 40.707817 -58.020291) (xy 40.763296 -57.956265) (xy 40.824609 -57.897802)
			(xy 40.891202 -57.845432) (xy 40.962471 -57.79963) (xy 41.037771 -57.760809) (xy 41.116421 -57.729321)
			(xy 41.197707 -57.705452) (xy 41.280894 -57.689418) (xy 41.365229 -57.681364) (xy 41.407588 -57.68086)
			(xy 41.44652 -57.681304) (xy 41.524082 -57.688145) (xy 41.600749 -57.701739) (xy 41.675935 -57.721984)
			(xy 41.712642 -57.734962) (xy 41.721191 -57.737726) (xy 41.739145 -57.737726) (xy 41.747694 -57.734962)
			(xy 41.784403 -57.721989) (xy 41.859589 -57.701746) (xy 41.936255 -57.688149) (xy 42.013817 -57.681299)
			(xy 42.052748 -57.68086) (xy 42.095109 -57.681344) (xy 42.179449 -57.689398) (xy 42.262641 -57.705431)
			(xy 42.343932 -57.7293) (xy 42.422586 -57.760789) (xy 42.497891 -57.799611) (xy 42.569164 -57.845415)
			(xy 42.635761 -57.897788) (xy 42.697078 -57.956253) (xy 42.75256 -58.020282) (xy 42.801704 -58.089296)
			(xy 42.844066 -58.162668) (xy 42.879261 -58.239734) (xy 42.906971 -58.319798) (xy 42.926945 -58.402132)
			(xy 42.939003 -58.485993) (xy 42.939828 -58.503312) (xy 44.667424 -58.503312) (xy 44.668008 -58.456916)
			(xy 44.677653 -58.364628) (xy 44.696848 -58.273844) (xy 44.725386 -58.185551) (xy 44.743624 -58.142886)
			(xy 44.74742 -58.132941) (xy 44.747425 -58.11168) (xy 44.743624 -58.101738) (xy 44.725385 -58.059073)
			(xy 44.696839 -57.970782) (xy 44.677644 -57.879998) (xy 44.66801 -57.787708) (xy 44.667424 -57.741312)
			(xy 44.667864 -57.700208) (xy 44.675448 -57.618351) (xy 44.690553 -57.537543) (xy 44.71305 -57.458473)
			(xy 44.742747 -57.381816) (xy 44.77939 -57.308227) (xy 44.822667 -57.238333) (xy 44.872209 -57.17273)
			(xy 44.927592 -57.111978) (xy 44.988345 -57.056596) (xy 45.053949 -57.007056) (xy 45.123845 -56.96378)
			(xy 45.197435 -56.927138) (xy 45.274092 -56.897443) (xy 45.353162 -56.874948) (xy 45.433971 -56.859845)
			(xy 45.515828 -56.852263) (xy 45.556932 -56.851804) (xy 45.603327 -56.85241) (xy 45.695615 -56.862048)
			(xy 45.786399 -56.881237) (xy 45.874693 -56.909769) (xy 45.917358 -56.928004) (xy 45.9273 -56.93181)
			(xy 45.948564 -56.93181) (xy 45.958506 -56.928004) (xy 46.001164 -56.909749) (xy 46.089458 -56.881208)
			(xy 46.180244 -56.862017) (xy 46.272536 -56.852387) (xy 46.318932 -56.851804) (xy 46.365327 -56.85241)
			(xy 46.457615 -56.862048) (xy 46.548399 -56.881237) (xy 46.636693 -56.909769) (xy 46.679358 -56.928004)
			(xy 46.6893 -56.93181) (xy 46.710564 -56.93181) (xy 46.720506 -56.928004) (xy 46.763164 -56.909749)
			(xy 46.851458 -56.881208) (xy 46.942244 -56.862017) (xy 47.034536 -56.852387) (xy 47.080932 -56.851804)
			(xy 47.122035 -56.852236) (xy 47.203891 -56.859824) (xy 47.284698 -56.874932) (xy 47.363766 -56.897432)
			(xy 47.44042 -56.927131) (xy 47.514008 -56.963775) (xy 47.5839 -57.007054) (xy 47.649501 -57.056596)
			(xy 47.710251 -57.11198) (xy 47.765632 -57.172733) (xy 47.815171 -57.238336) (xy 47.858446 -57.308231)
			(xy 47.895087 -57.38182) (xy 47.924782 -57.458476) (xy 47.947278 -57.537545) (xy 47.962382 -57.618352)
			(xy 47.969966 -57.700209) (xy 47.97044 -57.741312) (xy 47.969867 -57.787708) (xy 47.96022 -57.879997)
			(xy 47.941021 -57.970781) (xy 47.91248 -58.059074) (xy 47.89424 -58.101738) (xy 47.890426 -58.111678)
			(xy 47.890431 -58.132944) (xy 47.89424 -58.142886) (xy 47.912491 -58.185546) (xy 47.941033 -58.273839)
			(xy 47.960224 -58.364625) (xy 47.969856 -58.456916) (xy 47.97044 -58.503312) (xy 47.969945 -58.544414)
			(xy 47.962359 -58.626267) (xy 47.947254 -58.70707) (xy 47.924757 -58.786136) (xy 47.895062 -58.862788)
			(xy 47.858421 -58.936374) (xy 47.815146 -59.006265) (xy 47.765608 -59.071865) (xy 47.710229 -59.132614)
			(xy 47.64948 -59.187995) (xy 47.583881 -59.237535) (xy 47.513991 -59.280811) (xy 47.440406 -59.317454)
			(xy 47.363755 -59.347151) (xy 47.28469 -59.369649) (xy 47.203886 -59.384756) (xy 47.122034 -59.392344)
			(xy 47.080932 -59.39282) (xy 47.034537 -59.392225) (xy 46.942249 -59.382583) (xy 46.851465 -59.363391)
			(xy 46.763171 -59.334856) (xy 46.720506 -59.31662) (xy 46.710564 -59.312814) (xy 46.6893 -59.312814)
			(xy 46.679358 -59.31662) (xy 46.636692 -59.334855) (xy 46.548401 -59.363401) (xy 46.457617 -59.382597)
			(xy 46.365328 -59.392233) (xy 46.318932 -59.39282) (xy 46.272537 -59.392225) (xy 46.180249 -59.382583)
			(xy 46.089465 -59.363391) (xy 46.001171 -59.334856) (xy 45.958506 -59.31662) (xy 45.948564 -59.312814)
			(xy 45.9273 -59.312814) (xy 45.917358 -59.31662) (xy 45.874692 -59.334855) (xy 45.786401 -59.363401)
			(xy 45.695617 -59.382597) (xy 45.603328 -59.392233) (xy 45.556932 -59.39282) (xy 45.51583 -59.392317)
			(xy 45.433976 -59.384735) (xy 45.35317 -59.369633) (xy 45.274103 -59.347139) (xy 45.197449 -59.317446)
			(xy 45.123861 -59.280806) (xy 45.053968 -59.237533) (xy 44.988366 -59.187996) (xy 44.927615 -59.132616)
			(xy 44.872233 -59.071868) (xy 44.822692 -59.006268) (xy 44.779415 -58.936377) (xy 44.742772 -58.862792)
			(xy 44.713075 -58.786139) (xy 44.690577 -58.707073) (xy 44.675471 -58.626268) (xy 44.667885 -58.544414)
			(xy 44.667424 -58.503312) (xy 42.939828 -58.503312) (xy 42.943034 -58.57062) (xy 42.939003 -58.655247)
			(xy 42.926945 -58.739108) (xy 42.906971 -58.821442) (xy 42.879261 -58.901506) (xy 42.844066 -58.978572)
			(xy 42.801704 -59.051944) (xy 42.75256 -59.120958) (xy 42.697078 -59.184987) (xy 42.635761 -59.243452)
			(xy 42.569164 -59.295825) (xy 42.497891 -59.341629) (xy 42.422586 -59.380451) (xy 42.343932 -59.41194)
			(xy 42.262641 -59.435809) (xy 42.179449 -59.451842) (xy 42.095109 -59.459896) (xy 42.052748 -59.460384)
			(xy 42.013816 -59.459962) (xy 41.936253 -59.453116) (xy 41.859585 -59.439515) (xy 41.7844 -59.419264)
			(xy 41.747694 -59.406282) (xy 41.739145 -59.403518) (xy 41.721191 -59.403518) (xy 41.712642 -59.406282)
			(xy 41.67593 -59.419247) (xy 41.600745 -59.439491) (xy 41.52408 -59.453091) (xy 41.446519 -59.459943)
			(xy 41.407588 -59.460384) (xy 41.365229 -59.459836) (xy 41.280894 -59.451782) (xy 41.197707 -59.435748)
			(xy 41.116421 -59.411879) (xy 41.037771 -59.380391) (xy 40.962471 -59.34157) (xy 40.891202 -59.295768)
			(xy 40.824609 -59.243398) (xy 40.763296 -59.184935) (xy 40.707817 -59.120909) (xy 40.658676 -59.051899)
			(xy 40.616317 -58.97853) (xy 40.581124 -58.901468) (xy 40.553416 -58.821409) (xy 40.533443 -58.739078)
			(xy 40.521387 -58.655222) (xy 40.517355 -58.5706) (xy 40.243351 -58.5706) (xy 40.247073 -58.575531)
			(xy 40.290344 -58.645445) (xy 40.326979 -58.719053) (xy 40.356665 -58.795728) (xy 40.379149 -58.874815)
			(xy 40.394239 -58.955639) (xy 40.401806 -59.037511) (xy 40.402256 -59.078622) (xy 40.401872 -59.116906)
			(xy 40.395331 -59.193195) (xy 40.382249 -59.268637) (xy 40.362721 -59.342674) (xy 40.350186 -59.37885)
			(xy 40.347523 -59.387284) (xy 40.34753 -59.404957) (xy 40.350186 -59.413394) (xy 40.362687 -59.44958)
			(xy 40.382202 -59.523617) (xy 40.395289 -59.599056) (xy 40.401851 -59.675339) (xy 40.402256 -59.713622)
			(xy 40.401808 -59.754729) (xy 40.394222 -59.836593) (xy 40.379116 -59.917408) (xy 40.356619 -59.996485)
			(xy 40.326923 -60.073149) (xy 40.290282 -60.146747) (xy 40.247007 -60.216651) (xy 40.197469 -60.282264)
			(xy 40.142088 -60.343028) (xy 40.081338 -60.398424) (xy 40.015737 -60.44798) (xy 39.945844 -60.491272)
			(xy 39.872256 -60.527932) (xy 39.795599 -60.557647) (xy 39.716528 -60.580164) (xy 39.635717 -60.595291)
			(xy 39.553855 -60.602898) (xy 39.512748 -60.603384) (xy 39.473173 -60.602949) (xy 39.394338 -60.595875)
			(xy 39.316444 -60.581824) (xy 39.240107 -60.560907) (xy 39.202868 -60.547504) (xy 39.194199 -60.544674)
			(xy 39.175977 -60.544674) (xy 39.167308 -60.547504) (xy 39.130069 -60.560906) (xy 39.05373 -60.581811)
			(xy 38.975836 -60.595856) (xy 38.897003 -60.602929) (xy 38.857428 -60.603384) (xy 38.819138 -60.602969)
			(xy 38.742844 -60.596364) (xy 38.667402 -60.583217) (xy 38.593371 -60.563627) (xy 38.5572 -60.55106)
			(xy 38.548763 -60.548409) (xy 38.531093 -60.548409) (xy 38.522656 -60.55106) (xy 38.486477 -60.563601)
			(xy 38.412445 -60.583174) (xy 38.337005 -60.596322) (xy 38.260716 -60.602947) (xy 38.222428 -60.603384)
			(xy 38.181317 -60.602921) (xy 38.099446 -60.595335) (xy 38.018624 -60.580226) (xy 37.939542 -60.557723)
			(xy 37.862874 -60.528017) (xy 37.789275 -60.491363) (xy 37.719372 -60.448072) (xy 37.653763 -60.398515)
			(xy 37.593008 -60.343115) (xy 37.537625 -60.282344) (xy 37.488086 -60.216721) (xy 37.444816 -60.146807)
			(xy 37.408182 -60.073197) (xy 37.378498 -59.996521) (xy 37.356016 -59.917432) (xy 37.34093 -59.836606)
			(xy 37.333368 -59.754733) (xy 37.33292 -59.713622) (xy 37.333289 -59.675337) (xy 37.339834 -59.599048)
			(xy 37.352921 -59.523606) (xy 37.372453 -59.44957) (xy 37.38499 -59.413394) (xy 37.387629 -59.404954)
			(xy 37.387636 -59.387287) (xy 37.38499 -59.37885) (xy 37.378132 -59.359038) (xy 37.373306 -59.34456)
			(xy 37.349684 -59.325764) (xy 37.226748 -59.314588) (xy 37.200078 -59.328812) (xy 37.192712 -59.34202)
			(xy 37.17144 -59.379641) (xy 37.122666 -59.450996) (xy 37.067204 -59.517286) (xy 37.005575 -59.577885)
			(xy 36.93836 -59.632223) (xy 36.866194 -59.679787) (xy 36.789755 -59.720129) (xy 36.709765 -59.75287)
			(xy 36.626977 -59.7777) (xy 36.542171 -59.794386) (xy 36.456148 -59.802769) (xy 36.412932 -59.803284)
			(xy 36.373362 -59.802873) (xy 36.294534 -59.795863) (xy 36.21664 -59.781878) (xy 36.140297 -59.761028)
			(xy 36.103052 -59.747658) (xy 36.094383 -59.744828) (xy 36.076161 -59.744828) (xy 36.067492 -59.747658)
			(xy 36.030251 -59.761039) (xy 35.953906 -59.781882) (xy 35.876011 -59.795861) (xy 35.797182 -59.802865)
			(xy 35.757612 -59.803284) (xy 35.718043 -59.802849) (xy 35.639215 -59.795846) (xy 35.561321 -59.781868)
			(xy 35.484977 -59.761025) (xy 35.447732 -59.747658) (xy 35.439063 -59.744828) (xy 35.420841 -59.744828)
			(xy 35.412172 -59.747658) (xy 35.374923 -59.761016) (xy 35.298581 -59.781865) (xy 35.220688 -59.79585)
			(xy 35.141861 -59.802862) (xy 35.102292 -59.803284) (xy 35.061188 -59.802855) (xy 34.979331 -59.795269)
			(xy 34.898523 -59.780163) (xy 34.819453 -59.757665) (xy 34.742797 -59.727967) (xy 34.669208 -59.691322)
			(xy 34.599314 -59.648044) (xy 34.533711 -59.598502) (xy 34.47296 -59.543118) (xy 34.417578 -59.482364)
			(xy 34.368038 -59.41676) (xy 34.324762 -59.346864) (xy 34.28812 -59.273274) (xy 34.258425 -59.196616)
			(xy 34.23593 -59.117546) (xy 34.220826 -59.036738) (xy 34.213243 -58.95488) (xy 34.212784 -58.913776)
			(xy 14.639471 -58.913776) (xy 14.65219 -58.940231) (xy 14.68162 -59.016566) (xy 14.703921 -59.09528)
			(xy 14.718903 -59.175708) (xy 14.726441 -59.257172) (xy 14.72692 -59.298078) (xy 14.726481 -59.339194)
			(xy 14.718895 -59.421075) (xy 14.703786 -59.501906) (xy 14.681283 -59.580999) (xy 14.651579 -59.657678)
			(xy 14.614925 -59.731289) (xy 14.571636 -59.801203) (xy 14.52208 -59.866825) (xy 14.46668 -59.927594)
			(xy 14.40591 -59.982993) (xy 14.340287 -60.032547) (xy 14.270371 -60.075835) (xy 14.196759 -60.112487)
			(xy 14.12008 -60.14219) (xy 14.040987 -60.164691) (xy 13.960155 -60.179798) (xy 13.878274 -60.187381)
			(xy 13.837158 -60.18784) (xy 13.790755 -60.187227) (xy 13.698458 -60.177532) (xy 13.607673 -60.158275)
			(xy 13.519388 -60.129663) (xy 13.476732 -60.111386) (xy 13.46679 -60.10758) (xy 13.445526 -60.10758)
			(xy 13.435584 -60.111386) (xy 13.392929 -60.129663) (xy 13.304639 -60.158252) (xy 13.213854 -60.177505)
			(xy 13.12156 -60.187213) (xy 13.075158 -60.18784) (xy 13.028755 -60.187227) (xy 12.936458 -60.177532)
			(xy 12.845673 -60.158275) (xy 12.757388 -60.129663) (xy 12.714732 -60.111386) (xy 12.70479 -60.10758)
			(xy 12.683526 -60.10758) (xy 12.673584 -60.111386) (xy 12.630929 -60.129663) (xy 12.542639 -60.158252)
			(xy 12.451854 -60.177505) (xy 12.35956 -60.187213) (xy 12.313158 -60.18784) (xy 12.272044 -60.187369)
			(xy 12.190166 -60.179782) (xy 12.109337 -60.164672) (xy 12.030248 -60.142169) (xy 11.953572 -60.112464)
			(xy 11.879964 -60.075812) (xy 11.810052 -60.032524) (xy 11.744432 -59.98297) (xy 11.683665 -59.927573)
			(xy 11.628268 -59.866805) (xy 11.578714 -59.801185) (xy 11.535426 -59.731273) (xy 11.498774 -59.657664)
			(xy 11.46907 -59.580988) (xy 11.446567 -59.501899) (xy 11.431458 -59.42107) (xy 11.423871 -59.339192)
			(xy 11.423396 -59.298078) (xy 11.424158 -59.261502) (xy 11.42492 -59.246516) (xy 11.409934 -59.221116)
			(xy 11.301222 -59.16549) (xy 11.271758 -59.168284) (xy 11.260074 -59.177428) (xy 11.226474 -59.203173)
			(xy 11.155239 -59.24891) (xy 11.079981 -59.287669) (xy 11.001379 -59.319101) (xy 10.920146 -59.34292)
			(xy 10.837017 -59.358912) (xy 10.752745 -59.36693) (xy 10.710418 -59.36742) (xy 10.664023 -59.36683)
			(xy 10.571734 -59.357187) (xy 10.480951 -59.337993) (xy 10.392657 -59.309457) (xy 10.349992 -59.29122)
			(xy 10.34005 -59.287414) (xy 10.318786 -59.287414) (xy 10.308844 -59.29122) (xy 10.26618 -59.30946)
			(xy 10.177888 -59.338005) (xy 10.087104 -59.357199) (xy 9.994814 -59.366834) (xy 9.948418 -59.36742)
			(xy 9.90607 -59.366912) (xy 9.821756 -59.358861) (xy 9.73859 -59.342832) (xy 9.657325 -59.31897)
			(xy 9.578695 -59.287491) (xy 9.503414 -59.248681) (xy 9.432162 -59.20289) (xy 9.365586 -59.150534)
			(xy 9.304288 -59.092087) (xy 9.248824 -59.028077) (xy 9.199695 -58.959085) (xy 9.157347 -58.885736)
			(xy 9.122163 -58.808693) (xy 9.094461 -58.728655) (xy 9.074493 -58.646345) (xy 9.06244 -58.562511)
			(xy 9.058409 -58.47791) (xy 8.750967 -58.47791) (xy 8.780124 -58.509895) (xy 8.829678 -58.575515)
			(xy 8.872966 -58.645427) (xy 8.909618 -58.719035) (xy 8.939322 -58.795711) (xy 8.961825 -58.874801)
			(xy 8.976934 -58.95563) (xy 8.984521 -59.037508) (xy 8.984996 -59.078622) (xy 8.9846 -59.116912)
			(xy 8.97799 -59.193207) (xy 8.964838 -59.268649) (xy 8.945241 -59.342679) (xy 8.932672 -59.37885)
			(xy 8.930009 -59.387284) (xy 8.930017 -59.404957) (xy 8.932672 -59.413394) (xy 8.945223 -59.449569)
			(xy 8.964795 -59.523603) (xy 8.97794 -59.599043) (xy 8.984561 -59.675334) (xy 8.984996 -59.713622)
			(xy 8.984519 -59.754736) (xy 8.976932 -59.836614) (xy 8.961822 -59.917442) (xy 8.939319 -59.996531)
			(xy 8.909615 -60.073207) (xy 8.872963 -60.146814) (xy 8.829675 -60.216726) (xy 8.780122 -60.282346)
			(xy 8.724725 -60.343113) (xy 8.663957 -60.39851) (xy 8.598338 -60.448064) (xy 8.528426 -60.491352)
			(xy 8.454818 -60.528004) (xy 8.378143 -60.557709) (xy 8.299054 -60.580212) (xy 8.218226 -60.595322)
			(xy 8.136348 -60.602909) (xy 8.095234 -60.603384) (xy 8.055659 -60.602923) (xy 7.976826 -60.595857)
			(xy 7.898932 -60.581813) (xy 7.822594 -60.560904) (xy 7.785354 -60.547504) (xy 7.776685 -60.544674)
			(xy 7.758463 -60.544674) (xy 7.749794 -60.547504) (xy 7.712556 -60.56091) (xy 7.636217 -60.581814)
			(xy 7.558322 -60.595857) (xy 7.479489 -60.60293) (xy 7.439914 -60.603384) (xy 7.401624 -60.602973)
			(xy 7.32533 -60.596367) (xy 7.249888 -60.583219) (xy 7.175857 -60.563627) (xy 7.139686 -60.55106)
			(xy 7.131249 -60.548409) (xy 7.113579 -60.548409) (xy 7.105142 -60.55106) (xy 7.068965 -60.563605)
			(xy 6.994932 -60.583177) (xy 6.919492 -60.596324) (xy 6.843202 -60.602948) (xy 6.804914 -60.603384)
			(xy 6.763799 -60.602918) (xy 6.68192 -60.595331) (xy 6.601091 -60.580222) (xy 6.522 -60.557719) (xy 6.445324 -60.528014)
			(xy 6.371715 -60.491362) (xy 6.301801 -60.448074) (xy 6.236181 -60.39852) (xy 6.175412 -60.343122)
			(xy 6.120014 -60.282354) (xy 6.07046 -60.216734) (xy 6.027171 -60.146821) (xy 5.990518 -60.073212)
			(xy 5.960813 -59.996535) (xy 5.93831 -59.917445) (xy 5.9232 -59.836616) (xy 5.915613 -59.754737)
			(xy 5.915152 -59.713622) (xy 5.915563 -59.675332) (xy 5.922169 -59.599038) (xy 5.935317 -59.523596)
			(xy 5.954909 -59.449565) (xy 5.967476 -59.413394) (xy 5.970115 -59.404954) (xy 5.970122 -59.387287)
			(xy 5.967476 -59.37885) (xy 5.960618 -59.359038) (xy 5.955792 -59.34456) (xy 5.93217 -59.325764)
			(xy 5.809234 -59.314588) (xy 5.782564 -59.328812) (xy 5.775198 -59.34202) (xy 5.753936 -59.379647)
			(xy 5.705162 -59.451002) (xy 5.649698 -59.517292) (xy 5.588068 -59.577891) (xy 5.520852 -59.632228)
			(xy 5.448685 -59.679792) (xy 5.372245 -59.720134) (xy 5.292254 -59.752874) (xy 5.209465 -59.777703)
			(xy 5.124659 -59.794388) (xy 5.038634 -59.80277) (xy 4.995418 -59.803284) (xy 4.955849 -59.802847)
			(xy 4.877021 -59.795845) (xy 4.799127 -59.781867) (xy 4.722783 -59.761025) (xy 4.685538 -59.747658)
			(xy 4.676869 -59.744828) (xy 4.658647 -59.744828) (xy 4.649978 -59.747658) (xy 4.612728 -59.761014)
			(xy 4.536386 -59.781864) (xy 4.458494 -59.79585) (xy 4.379667 -59.802861) (xy 4.340098 -59.803284)
			(xy 4.301814 -59.802893) (xy 4.225525 -59.796354) (xy 4.150083 -59.783273) (xy 4.076046 -59.763748)
			(xy 4.03987 -59.751214) (xy 4.031433 -59.748563) (xy 4.013763 -59.748563) (xy 4.005326 -59.751214)
			(xy 3.969138 -59.763711) (xy 3.895102 -59.783226) (xy 3.819664 -59.796314) (xy 3.743381 -59.802878)
			(xy 3.705098 -59.803284) (xy 3.663991 -59.802809) (xy 3.582128 -59.795225) (xy 3.501314 -59.780121)
			(xy 3.422238 -59.757626) (xy 3.345574 -59.727932) (xy 3.271977 -59.691292) (xy 3.202073 -59.64802)
			(xy 3.13646 -59.598483) (xy 3.075696 -59.543104) (xy 3.0203 -59.482356) (xy 2.970744 -59.416756)
			(xy 2.927451 -59.346865) (xy 2.890791 -59.273278) (xy 2.861075 -59.196623) (xy 2.838557 -59.117553)
			(xy 2.82343 -59.036743) (xy 2.815822 -58.954883) (xy 2.815336 -58.913776) (xy 0.509016 -58.913776)
			(xy 0.509016 -62.54191) (xy 12.055609 -62.54191) (xy 12.05964 -62.457309) (xy 12.071693 -62.373475)
			(xy 12.091661 -62.291165) (xy 12.119363 -62.211127) (xy 12.154547 -62.134084) (xy 12.196895 -62.060735)
			(xy 12.246024 -61.991743) (xy 12.301488 -61.927733) (xy 12.362786 -61.869286) (xy 12.429362 -61.81693)
			(xy 12.500614 -61.771139) (xy 12.575895 -61.732329) (xy 12.654525 -61.70085) (xy 12.73579 -61.676988)
			(xy 12.818956 -61.660959) (xy 12.90327 -61.652908) (xy 12.945618 -61.652404) (xy 12.992014 -61.652979)
			(xy 13.084302 -61.662627) (xy 13.175086 -61.681825) (xy 13.263379 -61.710365) (xy 13.306044 -61.728604)
			(xy 13.315986 -61.73241) (xy 13.33725 -61.73241) (xy 13.347192 -61.728604) (xy 13.389852 -61.710354)
			(xy 13.478145 -61.681811) (xy 13.568931 -61.66262) (xy 13.661222 -61.652988) (xy 13.707618 -61.652404)
			(xy 13.754014 -61.652979) (xy 13.846302 -61.662627) (xy 13.937086 -61.681825) (xy 14.025379 -61.710365)
			(xy 14.068044 -61.728604) (xy 14.077986 -61.73241) (xy 14.09925 -61.73241) (xy 14.109192 -61.728604)
			(xy 14.151852 -61.710354) (xy 14.240145 -61.681811) (xy 14.330931 -61.66262) (xy 14.423222 -61.652988)
			(xy 14.469618 -61.652404) (xy 14.511967 -61.652888) (xy 14.596283 -61.660939) (xy 14.679451 -61.676968)
			(xy 14.760719 -61.70083) (xy 14.839351 -61.73231) (xy 14.914634 -61.771121) (xy 14.985887 -61.816912)
			(xy 15.035719 -61.8561) (xy 44.743084 -61.8561) (xy 44.747114 -61.771497) (xy 44.759168 -61.68766)
			(xy 44.779138 -61.605348) (xy 44.806841 -61.525307) (xy 44.842027 -61.448262) (xy 44.884377 -61.374911)
			(xy 44.933509 -61.305918) (xy 44.988976 -61.241907) (xy 45.050277 -61.183459) (xy 45.116856 -61.131103)
			(xy 45.18811 -61.085313) (xy 45.263395 -61.046503) (xy 45.342028 -61.015026) (xy 45.423297 -60.991166)
			(xy 45.506466 -60.975139) (xy 45.590782 -60.967091) (xy 45.633132 -60.966604) (xy 45.679527 -60.96721)
			(xy 45.771815 -60.976848) (xy 45.862599 -60.996037) (xy 45.950893 -61.024569) (xy 45.993558 -61.042804)
			(xy 46.0035 -61.04661) (xy 46.024764 -61.04661) (xy 46.034706 -61.042804) (xy 46.077364 -61.024549)
			(xy 46.165658 -60.996008) (xy 46.256444 -60.976817) (xy 46.348736 -60.967187) (xy 46.395132 -60.966604)
			(xy 46.441527 -60.96721) (xy 46.533815 -60.976848) (xy 46.624599 -60.996037) (xy 46.712893 -61.024569)
			(xy 46.755558 -61.042804) (xy 46.7655 -61.04661) (xy 46.786764 -61.04661) (xy 46.796706 -61.042804)
			(xy 46.839364 -61.024549) (xy 46.927658 -60.996008) (xy 47.018444 -60.976817) (xy 47.110736 -60.967187)
			(xy 47.157132 -60.966604) (xy 47.19948 -60.967085) (xy 47.283793 -60.975139) (xy 47.366958 -60.99117)
			(xy 47.448222 -61.015034) (xy 47.526851 -61.046515) (xy 47.602131 -61.085327) (xy 47.673381 -61.131119)
			(xy 47.739955 -61.183476) (xy 47.801252 -61.241924) (xy 47.856715 -61.305934) (xy 47.905843 -61.374926)
			(xy 47.94819 -61.448276) (xy 47.983373 -61.525319) (xy 48.011074 -61.605357) (xy 48.031041 -61.687666)
			(xy 48.043095 -61.7715) (xy 48.047125 -61.8561) (xy 48.043095 -61.9407) (xy 48.031041 -62.024534)
			(xy 48.011074 -62.106843) (xy 47.983373 -62.186881) (xy 47.94819 -62.263924) (xy 47.905843 -62.337274)
			(xy 47.856715 -62.406266) (xy 47.801252 -62.470276) (xy 47.739955 -62.528724) (xy 47.673381 -62.581081)
			(xy 47.602131 -62.626873) (xy 47.526851 -62.665685) (xy 47.448222 -62.697166) (xy 47.366958 -62.72103)
			(xy 47.283793 -62.737061) (xy 47.19948 -62.745115) (xy 47.157132 -62.74562) (xy 47.110737 -62.745025)
			(xy 47.018449 -62.735383) (xy 46.927665 -62.716191) (xy 46.839371 -62.687656) (xy 46.796706 -62.66942)
			(xy 46.786764 -62.665614) (xy 46.7655 -62.665614) (xy 46.755558 -62.66942) (xy 46.712892 -62.687655)
			(xy 46.624601 -62.716201) (xy 46.533817 -62.735397) (xy 46.441528 -62.745033) (xy 46.395132 -62.74562)
			(xy 46.348737 -62.745025) (xy 46.256449 -62.735383) (xy 46.165665 -62.716191) (xy 46.077371 -62.687656)
			(xy 46.034706 -62.66942) (xy 46.024764 -62.665614) (xy 46.0035 -62.665614) (xy 45.993558 -62.66942)
			(xy 45.950892 -62.687655) (xy 45.862601 -62.716201) (xy 45.771817 -62.735397) (xy 45.679528 -62.745033)
			(xy 45.633132 -62.74562) (xy 45.590782 -62.745109) (xy 45.506466 -62.737061) (xy 45.423297 -62.721034)
			(xy 45.342028 -62.697174) (xy 45.263395 -62.665697) (xy 45.18811 -62.626887) (xy 45.116856 -62.581097)
			(xy 45.050277 -62.528741) (xy 44.988976 -62.470293) (xy 44.933509 -62.406282) (xy 44.884377 -62.337289)
			(xy 44.842027 -62.263938) (xy 44.806841 -62.186893) (xy 44.779138 -62.106852) (xy 44.759168 -62.02454)
			(xy 44.747114 -61.940703) (xy 44.743084 -61.8561) (xy 15.035719 -61.8561) (xy 15.052465 -61.869269)
			(xy 15.113764 -61.927718) (xy 15.16923 -61.991729) (xy 15.21836 -62.060723) (xy 15.26071 -62.134074)
			(xy 15.295895 -62.211119) (xy 15.323597 -62.291159) (xy 15.343566 -62.37347) (xy 15.35562 -62.457307)
			(xy 15.35965 -62.54191) (xy 15.35562 -62.626513) (xy 15.343566 -62.71035) (xy 15.323597 -62.792661)
			(xy 15.295895 -62.872701) (xy 15.26071 -62.949746) (xy 15.21836 -63.023097) (xy 15.16923 -63.092091)
			(xy 15.113764 -63.156102) (xy 15.052465 -63.214551) (xy 14.985887 -63.266908) (xy 14.914634 -63.312699)
			(xy 14.839351 -63.35151) (xy 14.760719 -63.38299) (xy 14.679451 -63.406852) (xy 14.596283 -63.422881)
			(xy 14.511967 -63.430932) (xy 14.469618 -63.43142) (xy 14.423223 -63.43083) (xy 14.330934 -63.421187)
			(xy 14.240151 -63.401993) (xy 14.151857 -63.373457) (xy 14.109192 -63.35522) (xy 14.09925 -63.351414)
			(xy 14.077986 -63.351414) (xy 14.068044 -63.35522) (xy 14.02538 -63.37346) (xy 13.937088 -63.402005)
			(xy 13.846304 -63.421199) (xy 13.754014 -63.430834) (xy 13.707618 -63.43142) (xy 13.661223 -63.43083)
			(xy 13.568934 -63.421187) (xy 13.478151 -63.401993) (xy 13.389857 -63.373457) (xy 13.347192 -63.35522)
			(xy 13.33725 -63.351414) (xy 13.315986 -63.351414) (xy 13.306044 -63.35522) (xy 13.26338 -63.37346)
			(xy 13.175088 -63.402005) (xy 13.084304 -63.421199) (xy 12.992014 -63.430834) (xy 12.945618 -63.43142)
			(xy 12.90327 -63.430912) (xy 12.818956 -63.422861) (xy 12.73579 -63.406832) (xy 12.654525 -63.38297)
			(xy 12.575895 -63.351491) (xy 12.500614 -63.312681) (xy 12.429362 -63.26689) (xy 12.362786 -63.214534)
			(xy 12.301488 -63.156087) (xy 12.246024 -63.092077) (xy 12.196895 -63.023085) (xy 12.154547 -62.949736)
			(xy 12.119363 -62.872693) (xy 12.091661 -62.792655) (xy 12.071693 -62.710345) (xy 12.05964 -62.626511)
			(xy 12.055609 -62.54191) (xy 0.509016 -62.54191) (xy 0.509016 -80.067912) (xy 3.729228 -80.067912)
			(xy 3.729828 -80.021509) (xy 3.739526 -79.929211) (xy 3.758788 -79.838426) (xy 3.787403 -79.750141)
			(xy 3.805682 -79.707486) (xy 3.809481 -79.697542) (xy 3.809485 -79.67628) (xy 3.805682 -79.666338)
			(xy 3.787421 -79.623677) (xy 3.758828 -79.535389) (xy 3.739571 -79.444606) (xy 3.729858 -79.352313)
			(xy 3.729228 -79.305912) (xy 3.729694 -79.264802) (xy 3.737282 -79.182931) (xy 3.752393 -79.102111)
			(xy 3.774897 -79.02303) (xy 3.804604 -78.946363) (xy 3.841259 -78.872765) (xy 3.884549 -78.802863)
			(xy 3.934106 -78.737255) (xy 3.989506 -78.6765) (xy 4.050276 -78.621117) (xy 4.115898 -78.571579)
			(xy 4.185811 -78.528308) (xy 4.25942 -78.491673) (xy 4.336095 -78.461988) (xy 4.415182 -78.439506)
			(xy 4.496007 -78.424418) (xy 4.577879 -78.416853) (xy 4.61899 -78.416404) (xy 4.665386 -78.416989)
			(xy 4.757674 -78.426634) (xy 4.848458 -78.445829) (xy 4.936751 -78.474366) (xy 4.979416 -78.492604)
			(xy 4.989358 -78.49641) (xy 5.010622 -78.49641) (xy 5.020564 -78.492604) (xy 5.063228 -78.474363)
			(xy 5.15152 -78.445818) (xy 5.242304 -78.426624) (xy 5.334594 -78.416989) (xy 5.38099 -78.416404)
			(xy 5.427386 -78.416989) (xy 5.519674 -78.426634) (xy 5.610458 -78.445829) (xy 5.698751 -78.474366)
			(xy 5.741416 -78.492604) (xy 5.751358 -78.49641) (xy 5.772622 -78.49641) (xy 5.782564 -78.492604)
			(xy 5.825228 -78.474363) (xy 5.91352 -78.445818) (xy 6.004304 -78.426624) (xy 6.096594 -78.416989)
			(xy 6.14299 -78.416404) (xy 6.189386 -78.416989) (xy 6.281674 -78.426634) (xy 6.372458 -78.445829)
			(xy 6.460751 -78.474366) (xy 6.503416 -78.492604) (xy 6.513358 -78.49641) (xy 6.534622 -78.49641)
			(xy 6.544564 -78.492604) (xy 6.587228 -78.474363) (xy 6.67552 -78.445818) (xy 6.766304 -78.426624)
			(xy 6.858594 -78.416989) (xy 6.90499 -78.416404) (xy 6.946097 -78.416883) (xy 7.027959 -78.424467)
			(xy 7.108773 -78.439571) (xy 7.187849 -78.462065) (xy 7.264513 -78.491759) (xy 7.33811 -78.528398)
			(xy 7.408014 -78.571671) (xy 7.473627 -78.621208) (xy 7.534391 -78.676586) (xy 7.589787 -78.737334)
			(xy 7.639343 -78.802933) (xy 7.682636 -78.872824) (xy 7.719297 -78.946411) (xy 7.749013 -79.023066)
			(xy 7.77153 -79.102135) (xy 7.786658 -79.182945) (xy 7.794266 -79.264805) (xy 7.794752 -79.305912)
			(xy 7.794127 -79.352314) (xy 7.784436 -79.444611) (xy 7.765182 -79.535397) (xy 7.736574 -79.623682)
			(xy 7.718298 -79.666338) (xy 7.714486 -79.676278) (xy 7.714491 -79.697544) (xy 7.718298 -79.707486)
			(xy 7.736566 -79.750144) (xy 7.765157 -79.838434) (xy 7.784413 -79.929217) (xy 7.794124 -80.021511)
			(xy 7.794752 -80.067912) (xy 7.794289 -80.109023) (xy 7.786702 -80.190893) (xy 7.771591 -80.271713)
			(xy 7.757306 -80.32191) (xy 8.55498 -80.32191) (xy 8.55901 -80.237309) (xy 8.571063 -80.153474) (xy 8.591031 -80.071165)
			(xy 8.618733 -79.991127) (xy 8.653917 -79.914084) (xy 8.696266 -79.840734) (xy 8.745394 -79.771742)
			(xy 8.800859 -79.707732) (xy 8.862157 -79.649285) (xy 8.928733 -79.596929) (xy 8.999985 -79.551138)
			(xy 9.075266 -79.512328) (xy 9.153896 -79.480849) (xy 9.235162 -79.456988) (xy 9.318328 -79.440959)
			(xy 9.402642 -79.432908) (xy 9.44499 -79.432404) (xy 9.491386 -79.432989) (xy 9.583674 -79.442634)
			(xy 9.674458 -79.461829) (xy 9.762751 -79.490366) (xy 9.805416 -79.508604) (xy 9.815358 -79.51241)
			(xy 9.836622 -79.51241) (xy 9.846564 -79.508604) (xy 9.889228 -79.490363) (xy 9.97752 -79.461818)
			(xy 10.068304 -79.442624) (xy 10.160594 -79.432989) (xy 10.20699 -79.432404) (xy 10.249339 -79.432904)
			(xy 10.333652 -79.440955) (xy 10.416819 -79.456984) (xy 10.498085 -79.480846) (xy 10.576715 -79.512324)
			(xy 10.651997 -79.551135) (xy 10.723249 -79.596926) (xy 10.789826 -79.649282) (xy 10.851124 -79.70773)
			(xy 10.862798 -79.721202) (xy 11.170412 -79.721202) (xy 11.170819 -79.682912) (xy 11.177427 -79.606618)
			(xy 11.190576 -79.531176) (xy 11.210168 -79.457145) (xy 11.222736 -79.420974) (xy 11.225386 -79.412537)
			(xy 11.225387 -79.394867) (xy 11.222736 -79.38643) (xy 11.210188 -79.350254) (xy 11.190616 -79.27622)
			(xy 11.177471 -79.20078) (xy 11.170847 -79.12449) (xy 11.170412 -79.086202) (xy 11.170915 -79.045089)
			(xy 11.178501 -78.963212) (xy 11.19361 -78.882386) (xy 11.216112 -78.803298) (xy 11.245815 -78.726623)
			(xy 11.282466 -78.653016) (xy 11.325752 -78.583105) (xy 11.375304 -78.517486) (xy 11.430699 -78.456719)
			(xy 11.491464 -78.401322) (xy 11.557082 -78.351768) (xy 11.626992 -78.30848) (xy 11.700597 -78.271826)
			(xy 11.777271 -78.242121) (xy 11.856358 -78.219617) (xy 11.937185 -78.204505) (xy 12.019061 -78.196916)
			(xy 12.060174 -78.19644) (xy 12.099749 -78.196898) (xy 12.178583 -78.203964) (xy 12.256477 -78.218009)
			(xy 12.332814 -78.238919) (xy 12.370054 -78.25232) (xy 12.378723 -78.25515) (xy 12.396945 -78.25515)
			(xy 12.405614 -78.25232) (xy 12.442851 -78.238913) (xy 12.519191 -78.218009) (xy 12.597086 -78.203966)
			(xy 12.675919 -78.196894) (xy 12.715494 -78.19644) (xy 12.753784 -78.196847) (xy 12.830078 -78.203454)
			(xy 12.90552 -78.216603) (xy 12.979551 -78.236196) (xy 13.015722 -78.248764) (xy 13.024159 -78.251415)
			(xy 13.041829 -78.251415) (xy 13.050266 -78.248764) (xy 13.086443 -78.236218) (xy 13.160476 -78.216646)
			(xy 13.235916 -78.203499) (xy 13.312206 -78.196876) (xy 13.350494 -78.19644) (xy 13.391609 -78.196904)
			(xy 13.473488 -78.204491) (xy 13.554317 -78.2196) (xy 13.633408 -78.242103) (xy 13.710085 -78.271807)
			(xy 13.783694 -78.30846) (xy 13.853608 -78.351748) (xy 13.919229 -78.401302) (xy 13.979997 -78.4567)
			(xy 14.035395 -78.517468) (xy 14.08495 -78.583089) (xy 14.128238 -78.653002) (xy 14.164891 -78.726611)
			(xy 14.194596 -78.803288) (xy 14.217099 -78.882379) (xy 14.232209 -78.963208) (xy 14.239796 -79.045087)
			(xy 14.240256 -79.086202) (xy 14.239852 -79.124492) (xy 14.233244 -79.200786) (xy 14.220094 -79.276228)
			(xy 14.2005 -79.350259) (xy 14.187932 -79.38643) (xy 14.185281 -79.394866) (xy 14.185281 -79.412537)
			(xy 14.187932 -79.420974) (xy 14.19479 -79.440786) (xy 14.199616 -79.455264) (xy 14.223238 -79.47406)
			(xy 14.346174 -79.485236) (xy 14.372844 -79.471012) (xy 14.38021 -79.457804) (xy 14.401476 -79.420179)
			(xy 14.450249 -79.348823) (xy 14.505712 -79.282533) (xy 14.567341 -79.221933) (xy 14.634556 -79.167595)
			(xy 14.706723 -79.120031) (xy 14.783163 -79.079689) (xy 14.863154 -79.046949) (xy 14.945943 -79.02212)
			(xy 15.030749 -79.005436) (xy 15.116774 -78.997053) (xy 15.15999 -78.99654) (xy 15.199559 -78.996973)
			(xy 15.278387 -79.003976) (xy 15.356281 -79.017955) (xy 15.432625 -79.038799) (xy 15.46987 -79.052166)
			(xy 15.478539 -79.054996) (xy 15.496761 -79.054996) (xy 15.50543 -79.052166) (xy 15.542679 -79.038809)
			(xy 15.619021 -79.017959) (xy 15.696914 -79.003973) (xy 15.775741 -78.996962) (xy 15.81531 -78.99654)
			(xy 15.853594 -78.996928) (xy 15.929883 -79.003467) (xy 16.005325 -79.016549) (xy 16.079362 -79.036075)
			(xy 16.115538 -79.04861) (xy 16.123975 -79.051261) (xy 16.141645 -79.051261) (xy 16.150082 -79.04861)
			(xy 16.18627 -79.036112) (xy 16.260306 -79.016597) (xy 16.335744 -79.003509) (xy 16.412027 -78.996946)
			(xy 16.45031 -78.99654) (xy 16.491417 -78.997003) (xy 16.57328 -79.004588) (xy 16.654095 -79.019693)
			(xy 16.733171 -79.042189) (xy 16.809835 -79.071883) (xy 16.883433 -79.108524) (xy 16.953337 -79.151797)
			(xy 17.01895 -79.201335) (xy 17.079714 -79.256715) (xy 17.13511 -79.317464) (xy 17.184666 -79.383064)
			(xy 17.227958 -79.452956) (xy 17.264619 -79.526543) (xy 17.294334 -79.603199) (xy 17.316851 -79.68227)
			(xy 17.331978 -79.76308) (xy 17.339586 -79.844941) (xy 17.340072 -79.886048) (xy 17.339651 -79.924337)
			(xy 17.333047 -80.000631) (xy 17.321325 -80.067912) (xy 31.49092 -80.067912) (xy 31.491505 -80.021516)
			(xy 31.501149 -79.929228) (xy 31.520344 -79.838444) (xy 31.548882 -79.750151) (xy 31.56712 -79.707486)
			(xy 31.570917 -79.697541) (xy 31.570921 -79.67628) (xy 31.56712 -79.666338) (xy 31.548881 -79.623673)
			(xy 31.520335 -79.535382) (xy 31.50114 -79.444598) (xy 31.491506 -79.352308) (xy 31.49092 -79.305912)
			(xy 31.491364 -79.264808) (xy 31.498948 -79.182951) (xy 31.514053 -79.102143) (xy 31.53655 -79.023074)
			(xy 31.566246 -78.946417) (xy 31.602889 -78.872828) (xy 31.646166 -78.802934) (xy 31.695708 -78.737331)
			(xy 31.751091 -78.67658) (xy 31.811844 -78.621197) (xy 31.877447 -78.571657) (xy 31.947342 -78.528381)
			(xy 32.020932 -78.49174) (xy 32.097589 -78.462044) (xy 32.176659 -78.439549) (xy 32.257467 -78.424446)
			(xy 32.339324 -78.416863) (xy 32.380428 -78.416404) (xy 32.426823 -78.417011) (xy 32.519111 -78.426649)
			(xy 32.609894 -78.445838) (xy 32.698189 -78.474369) (xy 32.740854 -78.492604) (xy 32.750796 -78.49641)
			(xy 32.77206 -78.49641) (xy 32.782002 -78.492604) (xy 32.824661 -78.474351) (xy 32.912954 -78.445809)
			(xy 33.00374 -78.426618) (xy 33.096032 -78.416987) (xy 33.142428 -78.416404) (xy 33.188823 -78.417011)
			(xy 33.281111 -78.426649) (xy 33.371894 -78.445838) (xy 33.460189 -78.474369) (xy 33.502854 -78.492604)
			(xy 33.512796 -78.49641) (xy 33.53406 -78.49641) (xy 33.544002 -78.492604) (xy 33.586661 -78.474351)
			(xy 33.674954 -78.445809) (xy 33.76574 -78.426618) (xy 33.858032 -78.416987) (xy 33.904428 -78.416404)
			(xy 33.945531 -78.41684) (xy 34.027387 -78.424427) (xy 34.108193 -78.439535) (xy 34.187261 -78.462034)
			(xy 34.263916 -78.491733) (xy 34.337503 -78.528378) (xy 34.407396 -78.571656) (xy 34.472997 -78.621198)
			(xy 34.533747 -78.676581) (xy 34.589128 -78.737334) (xy 34.638667 -78.802937) (xy 34.681942 -78.872832)
			(xy 34.718583 -78.946421) (xy 34.748278 -79.023077) (xy 34.770774 -79.102145) (xy 34.785878 -79.182953)
			(xy 34.793462 -79.264809) (xy 34.793936 -79.305912) (xy 34.793355 -79.352308) (xy 34.783709 -79.444596)
			(xy 34.764512 -79.53538) (xy 34.735974 -79.623673) (xy 34.717736 -79.666338) (xy 34.713922 -79.676278)
			(xy 34.713927 -79.697544) (xy 34.717736 -79.707486) (xy 34.735986 -79.750146) (xy 34.764529 -79.838439)
			(xy 34.78372 -79.929225) (xy 34.793352 -80.021516) (xy 34.793936 -80.067912) (xy 34.793445 -80.109014)
			(xy 34.785859 -80.190867) (xy 34.770754 -80.271671) (xy 34.756462 -80.3219) (xy 36.316384 -80.3219)
			(xy 36.320414 -80.237297) (xy 36.332468 -80.15346) (xy 36.352437 -80.071149) (xy 36.38014 -79.991108)
			(xy 36.415326 -79.914064) (xy 36.457676 -79.840712) (xy 36.506808 -79.771719) (xy 36.562275 -79.707709)
			(xy 36.623575 -79.649261) (xy 36.690154 -79.596905) (xy 36.761408 -79.551114) (xy 36.836693 -79.512305)
			(xy 36.915325 -79.480827) (xy 36.996594 -79.456967) (xy 37.079763 -79.440939) (xy 37.164078 -79.432891)
			(xy 37.206428 -79.432404) (xy 37.252823 -79.433011) (xy 37.345111 -79.442649) (xy 37.435894 -79.461838)
			(xy 37.524189 -79.490369) (xy 37.566854 -79.508604) (xy 37.576796 -79.51241) (xy 37.59806 -79.51241)
			(xy 37.608002 -79.508604) (xy 37.650661 -79.490351) (xy 37.738954 -79.461809) (xy 37.82974 -79.442618)
			(xy 37.922032 -79.432987) (xy 37.968428 -79.432404) (xy 38.010776 -79.432885) (xy 38.095089 -79.440938)
			(xy 38.178254 -79.456969) (xy 38.259519 -79.480833) (xy 38.338148 -79.512314) (xy 38.413428 -79.551126)
			(xy 38.484679 -79.596917) (xy 38.551254 -79.649274) (xy 38.61255 -79.707723) (xy 38.624229 -79.721202)
			(xy 38.932104 -79.721202) (xy 38.932492 -79.682918) (xy 38.939031 -79.606629) (xy 38.952112 -79.531187)
			(xy 38.971639 -79.45715) (xy 38.984174 -79.420974) (xy 38.986823 -79.412537) (xy 38.986824 -79.394867)
			(xy 38.984174 -79.38643) (xy 38.97165 -79.350251) (xy 38.952142 -79.276212) (xy 38.939061 -79.200771)
			(xy 38.932506 -79.124485) (xy 38.932104 -79.086202) (xy 38.932614 -79.045096) (xy 38.940198 -78.963235)
			(xy 38.955301 -78.882423) (xy 38.977795 -78.803349) (xy 39.007487 -78.726686) (xy 39.044125 -78.65309)
			(xy 39.087395 -78.583188) (xy 39.13693 -78.517575) (xy 39.192306 -78.456811) (xy 39.253052 -78.401415)
			(xy 39.318648 -78.351859) (xy 39.388537 -78.308566) (xy 39.462121 -78.271904) (xy 39.538774 -78.242187)
			(xy 39.617841 -78.219668) (xy 39.698648 -78.204538) (xy 39.780506 -78.196928) (xy 39.821612 -78.19644)
			(xy 39.861187 -78.196886) (xy 39.940021 -78.203956) (xy 40.017915 -78.218004) (xy 40.094253 -78.238918)
			(xy 40.131492 -78.25232) (xy 40.140161 -78.25515) (xy 40.158383 -78.25515) (xy 40.167052 -78.25232)
			(xy 40.204295 -78.238931) (xy 40.280633 -78.218022) (xy 40.358526 -78.203974) (xy 40.437358 -78.196896)
			(xy 40.476932 -78.19644) (xy 40.515222 -78.196836) (xy 40.591516 -78.203446) (xy 40.666959 -78.216598)
			(xy 40.74099 -78.236195) (xy 40.77716 -78.248764) (xy 40.785597 -78.251415) (xy 40.803267 -78.251415)
			(xy 40.811704 -78.248764) (xy 40.847877 -78.236207) (xy 40.921912 -78.216638) (xy 40.997353 -78.203495)
			(xy 41.073644 -78.196874) (xy 41.111932 -78.19644) (xy 41.153045 -78.196822) (xy 41.234919 -78.204413)
			(xy 41.315743 -78.219528) (xy 41.394827 -78.242037) (xy 41.471496 -78.271748) (xy 41.545097 -78.308408)
			(xy 41.615 -78.351704) (xy 41.680609 -78.401267) (xy 41.741364 -78.456672) (xy 41.796747 -78.517448)
			(xy 41.846285 -78.583076) (xy 41.889554 -78.652995) (xy 41.926187 -78.726609) (xy 41.955869 -78.80329)
			(xy 41.978349 -78.882383) (xy 41.993433 -78.963212) (xy 42.000993 -79.045089) (xy 42.00144 -79.086202)
			(xy 42.001051 -79.124486) (xy 41.994512 -79.200775) (xy 41.981431 -79.276217) (xy 41.961905 -79.350254)
			(xy 41.94937 -79.38643) (xy 41.946717 -79.394866) (xy 41.946718 -79.412537) (xy 41.94937 -79.420974)
			(xy 41.956228 -79.440786) (xy 41.961054 -79.455264) (xy 41.984676 -79.47406) (xy 42.107612 -79.485236)
			(xy 42.134282 -79.471012) (xy 42.141648 -79.457804) (xy 42.162886 -79.420162) (xy 42.211662 -79.348806)
			(xy 42.267127 -79.282516) (xy 42.328759 -79.221917) (xy 42.395977 -79.16758) (xy 42.468148 -79.120017)
			(xy 42.54459 -79.079676) (xy 42.624584 -79.046938) (xy 42.707376 -79.022112) (xy 42.792184 -79.00543)
			(xy 42.878211 -78.997052) (xy 42.921428 -78.99654) (xy 42.960998 -78.996961) (xy 43.039826 -79.003968)
			(xy 43.117719 -79.01795) (xy 43.194063 -79.038797) (xy 43.231308 -79.052166) (xy 43.239977 -79.054996)
			(xy 43.258199 -79.054996) (xy 43.266868 -79.052166) (xy 43.304113 -79.038798) (xy 43.380457 -79.017951)
			(xy 43.458351 -79.003969) (xy 43.537179 -78.996961) (xy 43.576748 -78.99654) (xy 43.615033 -78.996917)
			(xy 43.691321 -79.003459) (xy 43.766764 -79.016544) (xy 43.8408 -79.036074) (xy 43.876976 -79.04861)
			(xy 43.885413 -79.051261) (xy 43.903083 -79.051261) (xy 43.91152 -79.04861) (xy 43.947704 -79.036101)
			(xy 44.021742 -79.016589) (xy 44.097181 -79.003504) (xy 44.173465 -78.996944) (xy 44.211748 -78.99654)
			(xy 44.252853 -78.996921) (xy 44.334711 -79.004511) (xy 44.41552 -79.019621) (xy 44.49459 -79.042123)
			(xy 44.571246 -79.071824) (xy 44.644835 -79.108472) (xy 44.714729 -79.151754) (xy 44.78033 -79.2013)
			(xy 44.841081 -79.256687) (xy 44.896462 -79.317443) (xy 44.946 -79.383051) (xy 44.989274 -79.452949)
			(xy 45.025914 -79.526542) (xy 45.055608 -79.603201) (xy 45.078101 -79.682274) (xy 45.093203 -79.763084)
			(xy 45.100784 -79.844943) (xy 45.101256 -79.886048) (xy 45.10088 -79.924333) (xy 45.094337 -80.000621)
			(xy 45.081252 -80.076064) (xy 45.061722 -80.1501) (xy 45.049186 -80.186276) (xy 45.04651 -80.194706)
			(xy 45.046525 -80.212383) (xy 45.049186 -80.22082) (xy 45.061695 -80.257004) (xy 45.081207 -80.331042)
			(xy 45.094292 -80.406481) (xy 45.100852 -80.482765) (xy 45.101256 -80.521048) (xy 45.100779 -80.56215)
			(xy 45.093191 -80.644003) (xy 45.078082 -80.724806) (xy 45.055583 -80.803871) (xy 45.025886 -80.880523)
			(xy 44.989243 -80.954108) (xy 44.945967 -81.023998) (xy 44.896427 -81.089598) (xy 44.841047 -81.150347)
			(xy 44.780298 -81.205727) (xy 44.714698 -81.255267) (xy 44.644808 -81.298543) (xy 44.571223 -81.335186)
			(xy 44.494571 -81.364883) (xy 44.415506 -81.387382) (xy 44.334703 -81.402491) (xy 44.25285 -81.410079)
			(xy 44.211748 -81.410556) (xy 44.172821 -81.410159) (xy 44.095264 -81.403376) (xy 44.018597 -81.389841)
			(xy 43.943406 -81.369656) (xy 43.906694 -81.356708) (xy 43.898145 -81.353944) (xy 43.880191 -81.353944)
			(xy 43.871642 -81.356708) (xy 43.834927 -81.369647) (xy 43.759737 -81.38983) (xy 43.68307 -81.403365)
			(xy 43.605514 -81.41015) (xy 43.566588 -81.410556) (xy 43.527662 -81.410147) (xy 43.450105 -81.403368)
			(xy 43.373438 -81.389836) (xy 43.298246 -81.369655) (xy 43.261534 -81.356708) (xy 43.252985 -81.353944)
			(xy 43.235031 -81.353944) (xy 43.226482 -81.356708) (xy 43.189773 -81.369664) (xy 43.11458 -81.389843)
			(xy 43.037912 -81.403373) (xy 42.960355 -81.410152) (xy 42.921428 -81.410556) (xy 42.880327 -81.410007)
			(xy 42.798477 -81.402425) (xy 42.717674 -81.387323) (xy 42.63861 -81.364831) (xy 42.561959 -81.335139)
			(xy 42.488374 -81.298501) (xy 42.418483 -81.255231) (xy 42.352883 -81.205696) (xy 42.292134 -81.15032)
			(xy 42.236752 -81.089575) (xy 42.187212 -81.023979) (xy 42.143936 -80.954092) (xy 42.107292 -80.880511)
			(xy 42.077594 -80.803862) (xy 42.055094 -80.7248) (xy 42.039986 -80.643999) (xy 42.032397 -80.562149)
			(xy 42.03192 -80.521048) (xy 42.032296 -80.482763) (xy 42.03884 -80.406475) (xy 42.051924 -80.331032)
			(xy 42.071454 -80.256996) (xy 42.08399 -80.22082) (xy 42.086616 -80.212377) (xy 42.086631 -80.194712)
			(xy 42.08399 -80.186276) (xy 42.077132 -80.166464) (xy 42.072306 -80.151986) (xy 42.048684 -80.13319)
			(xy 41.925748 -80.122014) (xy 41.899078 -80.136238) (xy 41.891712 -80.149446) (xy 41.87046 -80.187088)
			(xy 41.821708 -80.258477) (xy 41.76626 -80.3248) (xy 41.70464 -80.385432) (xy 41.637429 -80.4398)
			(xy 41.565261 -80.487392) (xy 41.488816 -80.527758) (xy 41.408816 -80.560518) (xy 41.326016 -80.585364)
			(xy 41.241196 -80.60206) (xy 41.155156 -80.610449) (xy 41.111932 -80.610964) (xy 41.073001 -80.610512)
			(xy 40.995439 -80.603674) (xy 40.918771 -80.590081) (xy 40.843585 -80.569839) (xy 40.806878 -80.556862)
			(xy 40.798329 -80.554098) (xy 40.780375 -80.554098) (xy 40.771826 -80.556862) (xy 40.735116 -80.569831)
			(xy 40.65993 -80.590074) (xy 40.583264 -80.603673) (xy 40.505703 -80.610524) (xy 40.466772 -80.610964)
			(xy 40.42784 -80.61053) (xy 40.350278 -80.603686) (xy 40.27361 -80.590089) (xy 40.198425 -80.569842)
			(xy 40.161718 -80.556862) (xy 40.153169 -80.554098) (xy 40.135215 -80.554098) (xy 40.126666 -80.556862)
			(xy 40.089961 -80.569848) (xy 40.014774 -80.590087) (xy 39.938106 -80.603681) (xy 39.860544 -80.610526)
			(xy 39.821612 -80.610964) (xy 39.7805 -80.610536) (xy 39.698628 -80.602949) (xy 39.617805 -80.587838)
			(xy 39.538721 -80.565333) (xy 39.462052 -80.535625) (xy 39.388452 -80.498968) (xy 39.318549 -80.455676)
			(xy 39.25294 -80.406116) (xy 39.192184 -80.350714) (xy 39.136801 -80.28994) (xy 39.087263 -80.224315)
			(xy 39.043992 -80.154398) (xy 39.007359 -80.080786) (xy 38.977676 -80.004108) (xy 38.955196 -79.925017)
			(xy 38.940112 -79.844189) (xy 38.932551 -79.762314) (xy 38.932104 -79.721202) (xy 38.624229 -79.721202)
			(xy 38.668014 -79.771733) (xy 38.717142 -79.840725) (xy 38.759489 -79.914075) (xy 38.794673 -79.991118)
			(xy 38.822374 -80.071156) (xy 38.842341 -80.153465) (xy 38.854395 -80.237299) (xy 38.858425 -80.3219)
			(xy 38.854395 -80.406501) (xy 38.842341 -80.490335) (xy 38.822374 -80.572644) (xy 38.794673 -80.652682)
			(xy 38.759489 -80.729725) (xy 38.717142 -80.803075) (xy 38.668014 -80.872067) (xy 38.61255 -80.936077)
			(xy 38.551254 -80.994526) (xy 38.484679 -81.046883) (xy 38.413428 -81.092674) (xy 38.338148 -81.131486)
			(xy 38.259519 -81.162967) (xy 38.178254 -81.186831) (xy 38.095089 -81.202862) (xy 38.010776 -81.210915)
			(xy 37.968428 -81.21142) (xy 37.922033 -81.210826) (xy 37.829745 -81.201184) (xy 37.738961 -81.181991)
			(xy 37.650667 -81.153456) (xy 37.608002 -81.13522) (xy 37.59806 -81.131414) (xy 37.576796 -81.131414)
			(xy 37.566854 -81.13522) (xy 37.524188 -81.153456) (xy 37.435897 -81.182002) (xy 37.345113 -81.201198)
			(xy 37.252824 -81.210834) (xy 37.206428 -81.21142) (xy 37.164078 -81.210909) (xy 37.079763 -81.202861)
			(xy 36.996594 -81.186833) (xy 36.915325 -81.162973) (xy 36.836693 -81.131495) (xy 36.761408 -81.092686)
			(xy 36.690154 -81.046895) (xy 36.623575 -80.994539) (xy 36.562274 -80.936091) (xy 36.506808 -80.872081)
			(xy 36.457676 -80.803088) (xy 36.415326 -80.729736) (xy 36.38014 -80.652692) (xy 36.352437 -80.572651)
			(xy 36.332468 -80.49034) (xy 36.320414 -80.406503) (xy 36.316384 -80.3219) (xy 34.756462 -80.3219)
			(xy 34.748257 -80.350736) (xy 34.718561 -80.427389) (xy 34.68192 -80.500975) (xy 34.638645 -80.570866)
			(xy 34.589107 -80.636466) (xy 34.533727 -80.697216) (xy 34.472978 -80.752597) (xy 34.407379 -80.802136)
			(xy 34.337489 -80.845412) (xy 34.263904 -80.882055) (xy 34.187252 -80.911752) (xy 34.108186 -80.93425)
			(xy 34.027383 -80.949357) (xy 33.94553 -80.956944) (xy 33.904428 -80.95742) (xy 33.858033 -80.956826)
			(xy 33.765745 -80.947184) (xy 33.674961 -80.927991) (xy 33.586667 -80.899456) (xy 33.544002 -80.88122)
			(xy 33.53406 -80.877414) (xy 33.512796 -80.877414) (xy 33.502854 -80.88122) (xy 33.460188 -80.899456)
			(xy 33.371897 -80.928002) (xy 33.281113 -80.947198) (xy 33.188824 -80.956834) (xy 33.142428 -80.95742)
			(xy 33.096033 -80.956826) (xy 33.003745 -80.947184) (xy 32.912961 -80.927991) (xy 32.824667 -80.899456)
			(xy 32.782002 -80.88122) (xy 32.77206 -80.877414) (xy 32.750796 -80.877414) (xy 32.740854 -80.88122)
			(xy 32.698188 -80.899456) (xy 32.609897 -80.928002) (xy 32.519113 -80.947198) (xy 32.426824 -80.956834)
			(xy 32.380428 -80.95742) (xy 32.339326 -80.956921) (xy 32.257471 -80.949339) (xy 32.176666 -80.934236)
			(xy 32.097599 -80.911742) (xy 32.020944 -80.882048) (xy 31.947357 -80.845408) (xy 31.877464 -80.802135)
			(xy 31.811862 -80.752597) (xy 31.751111 -80.697218) (xy 31.695728 -80.636469) (xy 31.646188 -80.570869)
			(xy 31.602911 -80.500978) (xy 31.566268 -80.427392) (xy 31.536571 -80.350739) (xy 31.514073 -80.271673)
			(xy 31.498967 -80.190868) (xy 31.491381 -80.109014) (xy 31.49092 -80.067912) (xy 17.321325 -80.067912)
			(xy 17.319903 -80.076074) (xy 17.300314 -80.150105) (xy 17.287748 -80.186276) (xy 17.285073 -80.194707)
			(xy 17.285089 -80.212383) (xy 17.287748 -80.22082) (xy 17.300282 -80.257001) (xy 17.319857 -80.331033)
			(xy 17.333007 -80.406471) (xy 17.339634 -80.48276) (xy 17.340072 -80.521048) (xy 17.339693 -80.56216)
			(xy 17.332101 -80.644034) (xy 17.316985 -80.724858) (xy 17.294475 -80.803942) (xy 17.264763 -80.880611)
			(xy 17.228102 -80.954211) (xy 17.184806 -81.024113) (xy 17.135243 -81.089722) (xy 17.079838 -81.150477)
			(xy 17.019062 -81.205859) (xy 16.953434 -81.255397) (xy 16.883515 -81.298667) (xy 16.809901 -81.335299)
			(xy 16.733221 -81.364983) (xy 16.654129 -81.387462) (xy 16.573299 -81.402547) (xy 16.491423 -81.410109)
			(xy 16.45031 -81.410556) (xy 16.411384 -81.410141) (xy 16.333827 -81.403363) (xy 16.25716 -81.389833)
			(xy 16.181969 -81.369654) (xy 16.145256 -81.356708) (xy 16.136707 -81.353944) (xy 16.118753 -81.353944)
			(xy 16.110204 -81.356708) (xy 16.073493 -81.369658) (xy 15.998301 -81.389838) (xy 15.921633 -81.40337)
			(xy 15.844076 -81.410151) (xy 15.80515 -81.410556) (xy 15.766223 -81.410159) (xy 15.688666 -81.403376)
			(xy 15.611999 -81.389841) (xy 15.536808 -81.369656) (xy 15.500096 -81.356708) (xy 15.491547 -81.353944)
			(xy 15.473593 -81.353944) (xy 15.465044 -81.356708) (xy 15.428329 -81.369647) (xy 15.353138 -81.38983)
			(xy 15.276472 -81.403365) (xy 15.198916 -81.41015) (xy 15.15999 -81.410556) (xy 15.118883 -81.410097)
			(xy 15.037019 -81.402512) (xy 14.956205 -81.387407) (xy 14.877128 -81.364911) (xy 14.800464 -81.335216)
			(xy 14.726866 -81.298576) (xy 14.656962 -81.255302) (xy 14.591348 -81.205764) (xy 14.530584 -81.150384)
			(xy 14.475188 -81.089635) (xy 14.425633 -81.024034) (xy 14.38234 -80.954142) (xy 14.34568 -80.880554)
			(xy 14.315965 -80.803898) (xy 14.293448 -80.724827) (xy 14.278321 -80.644016) (xy 14.270714 -80.562155)
			(xy 14.270228 -80.521048) (xy 14.270648 -80.482759) (xy 14.277252 -80.406465) (xy 14.290397 -80.331022)
			(xy 14.309986 -80.256991) (xy 14.322552 -80.22082) (xy 14.325179 -80.212377) (xy 14.325194 -80.194712)
			(xy 14.322552 -80.186276) (xy 14.315694 -80.166464) (xy 14.310868 -80.151986) (xy 14.287246 -80.13319)
			(xy 14.16431 -80.122014) (xy 14.13764 -80.136238) (xy 14.130274 -80.149446) (xy 14.10905 -80.187104)
			(xy 14.060295 -80.258494) (xy 14.004844 -80.324817) (xy 13.943222 -80.385448) (xy 13.876007 -80.439815)
			(xy 13.803836 -80.487406) (xy 13.727389 -80.527771) (xy 13.647386 -80.560529) (xy 13.564583 -80.585372)
			(xy 13.479761 -80.602065) (xy 13.393719 -80.610451) (xy 13.350494 -80.610964) (xy 13.311562 -80.610524)
			(xy 13.234 -80.603682) (xy 13.157333 -80.590086) (xy 13.082147 -80.569841) (xy 13.04544 -80.556862)
			(xy 13.036891 -80.554098) (xy 13.018937 -80.554098) (xy 13.010388 -80.556862) (xy 12.973681 -80.569842)
			(xy 12.898495 -80.590082) (xy 12.821827 -80.603678) (xy 12.744265 -80.610525) (xy 12.705334 -80.610964)
			(xy 12.666403 -80.610512) (xy 12.588841 -80.603673) (xy 12.512173 -80.590081) (xy 12.436987 -80.569839)
			(xy 12.40028 -80.556862) (xy 12.391731 -80.554098) (xy 12.373777 -80.554098) (xy 12.365228 -80.556862)
			(xy 12.328517 -80.56983) (xy 12.253332 -80.590074) (xy 12.176666 -80.603673) (xy 12.099105 -80.610524)
			(xy 12.060174 -80.610964) (xy 12.019059 -80.610512) (xy 11.937181 -80.602923) (xy 11.856352 -80.587811)
			(xy 11.777263 -80.565306) (xy 11.700587 -80.5356) (xy 11.626979 -80.498945) (xy 11.557067 -80.455656)
			(xy 11.491448 -80.406101) (xy 11.430681 -80.350703) (xy 11.375284 -80.289934) (xy 11.32573 -80.224313)
			(xy 11.282443 -80.1544) (xy 11.245791 -80.080791) (xy 11.216086 -80.004114) (xy 11.193584 -79.925024)
			(xy 11.178474 -79.844195) (xy 11.170887 -79.762317) (xy 11.170412 -79.721202) (xy 10.862798 -79.721202)
			(xy 10.906589 -79.77174) (xy 10.955718 -79.840732) (xy 10.998066 -79.914082) (xy 11.033251 -79.991125)
			(xy 11.060953 -80.071164) (xy 11.080921 -80.153474) (xy 11.092974 -80.237309) (xy 11.097005 -80.32191)
			(xy 11.092974 -80.406511) (xy 11.080921 -80.490346) (xy 11.060953 -80.572656) (xy 11.033251 -80.652695)
			(xy 10.998066 -80.729738) (xy 10.955718 -80.803088) (xy 10.906589 -80.87208) (xy 10.851124 -80.93609)
			(xy 10.789826 -80.994538) (xy 10.723249 -81.046894) (xy 10.651997 -81.092685) (xy 10.576715 -81.131496)
			(xy 10.498085 -81.162974) (xy 10.416819 -81.186836) (xy 10.333652 -81.202865) (xy 10.249339 -81.210916)
			(xy 10.20699 -81.21142) (xy 10.160594 -81.21084) (xy 10.068306 -81.201194) (xy 9.977522 -81.181997)
			(xy 9.889229 -81.153458) (xy 9.846564 -81.13522) (xy 9.836622 -81.131414) (xy 9.815358 -81.131414)
			(xy 9.805416 -81.13522) (xy 9.762755 -81.153469) (xy 9.674462 -81.182012) (xy 9.583677 -81.201204)
			(xy 9.491386 -81.210836) (xy 9.44499 -81.21142) (xy 9.402642 -81.210912) (xy 9.318328 -81.202861)
			(xy 9.235162 -81.186832) (xy 9.153896 -81.162971) (xy 9.075266 -81.131492) (xy 8.999985 -81.092682)
			(xy 8.928733 -81.046891) (xy 8.862157 -80.994535) (xy 8.800859 -80.936088) (xy 8.745394 -80.872078)
			(xy 8.696266 -80.803086) (xy 8.653917 -80.729736) (xy 8.618733 -80.652693) (xy 8.591031 -80.572655)
			(xy 8.571063 -80.490346) (xy 8.55901 -80.406511) (xy 8.55498 -80.32191) (xy 7.757306 -80.32191) (xy 7.749086 -80.350795)
			(xy 7.719379 -80.427461) (xy 7.682723 -80.50106) (xy 7.639433 -80.570961) (xy 7.589876 -80.636569)
			(xy 7.534476 -80.697324) (xy 7.473705 -80.752707) (xy 7.408083 -80.802245) (xy 7.338169 -80.845516)
			(xy 7.264561 -80.882151) (xy 7.187885 -80.911836) (xy 7.108798 -80.934318) (xy 7.027973 -80.949406)
			(xy 6.946101 -80.956971) (xy 6.90499 -80.95742) (xy 6.858594 -80.95684) (xy 6.766306 -80.947194)
			(xy 6.675522 -80.927997) (xy 6.587229 -80.899458) (xy 6.544564 -80.88122) (xy 6.534622 -80.877414)
			(xy 6.513358 -80.877414) (xy 6.503416 -80.88122) (xy 6.460755 -80.899469) (xy 6.372462 -80.928012)
			(xy 6.281677 -80.947204) (xy 6.189386 -80.956836) (xy 6.14299 -80.95742) (xy 6.096594 -80.95684)
			(xy 6.004306 -80.947194) (xy 5.913522 -80.927997) (xy 5.825229 -80.899458) (xy 5.782564 -80.88122)
			(xy 5.772622 -80.877414) (xy 5.751358 -80.877414) (xy 5.741416 -80.88122) (xy 5.698755 -80.899469)
			(xy 5.610462 -80.928012) (xy 5.519677 -80.947204) (xy 5.427386 -80.956836) (xy 5.38099 -80.95742)
			(xy 5.334594 -80.95684) (xy 5.242306 -80.947194) (xy 5.151522 -80.927997) (xy 5.063229 -80.899458)
			(xy 5.020564 -80.88122) (xy 5.010622 -80.877414) (xy 4.989358 -80.877414) (xy 4.979416 -80.88122)
			(xy 4.936755 -80.899469) (xy 4.848462 -80.928012) (xy 4.757677 -80.947204) (xy 4.665386 -80.956836)
			(xy 4.61899 -80.95742) (xy 4.577883 -80.956947) (xy 4.49602 -80.949363) (xy 4.415206 -80.934259)
			(xy 4.33613 -80.911764) (xy 4.259466 -80.88207) (xy 4.185868 -80.845431) (xy 4.115964 -80.802158)
			(xy 4.05035 -80.752621) (xy 3.989587 -80.697242) (xy 3.93419 -80.636493) (xy 3.884635 -80.570894)
			(xy 3.841342 -80.501002) (xy 3.804682 -80.427415) (xy 3.774966 -80.35076) (xy 3.752449 -80.27169)
			(xy 3.737322 -80.19088) (xy 3.729714 -80.109019) (xy 3.729228 -80.067912) (xy 0.509016 -80.067912)
			(xy 0.509016 -84.385912) (xy 39.460424 -84.385912) (xy 39.461008 -84.339516) (xy 39.470653 -84.247228)
			(xy 39.489848 -84.156444) (xy 39.518386 -84.068151) (xy 39.536624 -84.025486) (xy 39.54042 -84.015541)
			(xy 39.540425 -83.99428) (xy 39.536624 -83.984338) (xy 39.518385 -83.941673) (xy 39.489839 -83.853382)
			(xy 39.470644 -83.762598) (xy 39.46101 -83.670308) (xy 39.460424 -83.623912) (xy 39.460928 -83.581564)
			(xy 39.468979 -83.49725) (xy 39.485008 -83.414084) (xy 39.508869 -83.332817) (xy 39.540348 -83.254187)
			(xy 39.579159 -83.178906) (xy 39.624949 -83.107654) (xy 39.677305 -83.041078) (xy 39.735753 -82.97978)
			(xy 39.799763 -82.924315) (xy 39.868755 -82.875186) (xy 39.942105 -82.832837) (xy 40.019148 -82.797653)
			(xy 40.099187 -82.769951) (xy 40.181496 -82.749983) (xy 40.265331 -82.73793) (xy 40.349932 -82.7339)
			(xy 40.434533 -82.73793) (xy 40.518368 -82.749983) (xy 40.600677 -82.769951) (xy 40.680716 -82.797653)
			(xy 40.757759 -82.832837) (xy 40.831109 -82.875186) (xy 40.900101 -82.924315) (xy 40.964111 -82.97978)
			(xy 41.022559 -83.041078) (xy 41.074915 -83.107654) (xy 41.120705 -83.178906) (xy 41.159516 -83.254187)
			(xy 41.190995 -83.332817) (xy 41.214856 -83.414084) (xy 41.230885 -83.49725) (xy 41.238936 -83.581564)
			(xy 41.23944 -83.623912) (xy 41.238867 -83.670308) (xy 41.22922 -83.762597) (xy 41.210021 -83.853381)
			(xy 41.18148 -83.941674) (xy 41.16324 -83.984338) (xy 41.159426 -83.994278) (xy 41.159431 -84.015544)
			(xy 41.16324 -84.025486) (xy 41.181491 -84.068146) (xy 41.210033 -84.156439) (xy 41.229224 -84.247225)
			(xy 41.238856 -84.339516) (xy 41.23944 -84.385912) (xy 41.238936 -84.42826) (xy 41.230885 -84.512574)
			(xy 41.214856 -84.59574) (xy 41.190995 -84.677007) (xy 41.159516 -84.755637) (xy 41.120705 -84.830918)
			(xy 41.074915 -84.90217) (xy 41.022559 -84.968746) (xy 40.964111 -85.030044) (xy 40.900101 -85.085509)
			(xy 40.831109 -85.134638) (xy 40.757759 -85.176987) (xy 40.680716 -85.212171) (xy 40.600677 -85.239873)
			(xy 40.518368 -85.259841) (xy 40.434533 -85.271894) (xy 40.349932 -85.275925) (xy 40.265331 -85.271894)
			(xy 40.181496 -85.259841) (xy 40.099187 -85.239873) (xy 40.019148 -85.212171) (xy 39.942105 -85.176987)
			(xy 39.868755 -85.134638) (xy 39.799763 -85.085509) (xy 39.735753 -85.030044) (xy 39.677305 -84.968746)
			(xy 39.624949 -84.90217) (xy 39.579159 -84.830918) (xy 39.540348 -84.755637) (xy 39.508869 -84.677007)
			(xy 39.485008 -84.59574) (xy 39.468979 -84.512574) (xy 39.460928 -84.42826) (xy 39.460424 -84.385912)
			(xy 0.509016 -84.385912) (xy 0.509016 -89.153238) (xy 12.572492 -89.153238) (xy 12.572861 -89.114953)
			(xy 12.579406 -89.038664) (xy 12.592493 -88.963222) (xy 12.612024 -88.889186) (xy 12.624562 -88.85301)
			(xy 12.627193 -88.844568) (xy 12.627206 -88.826902) (xy 12.624562 -88.818466) (xy 12.612047 -88.782284)
			(xy 12.592537 -88.708246) (xy 12.579454 -88.632806) (xy 12.572895 -88.556521) (xy 12.572492 -88.518238)
			(xy 12.572861 -88.479953) (xy 12.579406 -88.403664) (xy 12.592493 -88.328222) (xy 12.612024 -88.254186)
			(xy 12.624562 -88.21801) (xy 12.627193 -88.209568) (xy 12.627206 -88.191902) (xy 12.624562 -88.183466)
			(xy 12.612047 -88.147284) (xy 12.592537 -88.073246) (xy 12.579454 -87.997806) (xy 12.572895 -87.921521)
			(xy 12.572492 -87.883238) (xy 12.573026 -87.842034) (xy 12.580643 -87.759979) (xy 12.595814 -87.678979)
			(xy 12.618411 -87.59973) (xy 12.64824 -87.52291) (xy 12.685044 -87.449177) (xy 12.728508 -87.379163)
			(xy 12.778261 -87.313469) (xy 12.833875 -87.252657) (xy 12.894874 -87.197247) (xy 12.960735 -87.147716)
			(xy 13.030895 -87.104488) (xy 13.104751 -87.067932) (xy 13.181671 -87.038362) (xy 13.221208 -87.02675)
			(xy 13.231515 -87.023234) (xy 13.248152 -87.009222) (xy 13.257547 -86.989605) (xy 13.258292 -86.978744)
			(xy 13.259547 -86.93559) (xy 13.26949 -86.849826) (xy 13.287695 -86.765428) (xy 13.313992 -86.68319)
			(xy 13.348131 -86.603888) (xy 13.389793 -86.528265) (xy 13.438585 -86.457035) (xy 13.494049 -86.390867)
			(xy 13.555662 -86.330383) (xy 13.622845 -86.276153) (xy 13.694966 -86.228687) (xy 13.771346 -86.188431)
			(xy 13.851267 -86.155764) (xy 13.933976 -86.130994) (xy 14.018696 -86.114353) (xy 14.10463 -86.105998)
			(xy 14.1478 -86.105492) (xy 14.188902 -86.105967) (xy 14.270757 -86.113552) (xy 14.351562 -86.128657)
			(xy 14.430629 -86.151153) (xy 14.507283 -86.180849) (xy 14.58087 -86.217491) (xy 14.650762 -86.260766)
			(xy 14.716363 -86.310306) (xy 14.722951 -86.316312) (xy 35.838892 -86.316312) (xy 35.839383 -86.274361)
			(xy 35.847275 -86.19083) (xy 35.86299 -86.108412) (xy 35.886388 -86.027838) (xy 35.901376 -85.988652)
			(xy 35.904581 -85.979525) (xy 35.904565 -85.960194) (xy 35.901376 -85.95106) (xy 35.886389 -85.911873)
			(xy 35.862968 -85.831304) (xy 35.847246 -85.748886) (xy 35.839364 -85.665352) (xy 35.838892 -85.6234)
			(xy 35.839396 -85.581052) (xy 35.847447 -85.496738) (xy 35.863476 -85.413572) (xy 35.887337 -85.332305)
			(xy 35.918816 -85.253675) (xy 35.957627 -85.178394) (xy 36.003417 -85.107142) (xy 36.055773 -85.040566)
			(xy 36.114221 -84.979268) (xy 36.178231 -84.923803) (xy 36.247223 -84.874674) (xy 36.320573 -84.832325)
			(xy 36.397616 -84.797141) (xy 36.477655 -84.769439) (xy 36.559964 -84.749471) (xy 36.643799 -84.737418)
			(xy 36.7284 -84.733388) (xy 36.813001 -84.737418) (xy 36.896836 -84.749471) (xy 36.979145 -84.769439)
			(xy 37.059184 -84.797141) (xy 37.136227 -84.832325) (xy 37.209577 -84.874674) (xy 37.278569 -84.923803)
			(xy 37.342579 -84.979268) (xy 37.401027 -85.040566) (xy 37.453383 -85.107142) (xy 37.499173 -85.178394)
			(xy 37.537984 -85.253675) (xy 37.569463 -85.332305) (xy 37.593324 -85.413572) (xy 37.609353 -85.496738)
			(xy 37.617404 -85.581052) (xy 37.617908 -85.6234) (xy 37.617421 -85.665351) (xy 37.609528 -85.748882)
			(xy 37.593812 -85.8313) (xy 37.570412 -85.911874) (xy 37.555424 -85.95106) (xy 37.552267 -85.9602)
			(xy 37.552252 -85.979519) (xy 37.555424 -85.988652) (xy 37.570414 -86.027838) (xy 37.593835 -86.108407)
			(xy 37.609556 -86.190826) (xy 37.617436 -86.27436) (xy 37.617908 -86.316312) (xy 37.617404 -86.35866)
			(xy 37.609353 -86.442974) (xy 37.593324 -86.52614) (xy 37.569463 -86.607407) (xy 37.537984 -86.686037)
			(xy 37.499173 -86.761318) (xy 37.453383 -86.83257) (xy 37.401027 -86.899146) (xy 37.342579 -86.960444)
			(xy 37.278569 -87.015909) (xy 37.209577 -87.065038) (xy 37.136227 -87.107387) (xy 37.059184 -87.142571)
			(xy 36.979145 -87.170273) (xy 36.896836 -87.190241) (xy 36.813001 -87.202294) (xy 36.7284 -87.206325)
			(xy 36.643799 -87.202294) (xy 36.559964 -87.190241) (xy 36.477655 -87.170273) (xy 36.397616 -87.142571)
			(xy 36.320573 -87.107387) (xy 36.247223 -87.065038) (xy 36.178231 -87.015909) (xy 36.114221 -86.960444)
			(xy 36.055773 -86.899146) (xy 36.003417 -86.83257) (xy 35.957627 -86.761318) (xy 35.918816 -86.686037)
			(xy 35.887337 -86.607407) (xy 35.863476 -86.52614) (xy 35.847447 -86.442974) (xy 35.839396 -86.35866)
			(xy 35.838892 -86.316312) (xy 14.722951 -86.316312) (xy 14.777113 -86.365687) (xy 14.832494 -86.426437)
			(xy 14.882034 -86.492038) (xy 14.925309 -86.56193) (xy 14.961951 -86.635517) (xy 14.991647 -86.712171)
			(xy 15.014143 -86.791238) (xy 15.029248 -86.872043) (xy 15.036833 -86.953898) (xy 15.037308 -86.995)
			(xy 15.036809 -87.036205) (xy 15.029189 -87.118261) (xy 15.014014 -87.199261) (xy 14.991413 -87.278511)
			(xy 14.961582 -87.355332) (xy 14.924775 -87.429064) (xy 14.881308 -87.499078) (xy 14.831553 -87.564772)
			(xy 14.775936 -87.625584) (xy 14.714935 -87.680993) (xy 14.649071 -87.730524) (xy 14.578909 -87.773752)
			(xy 14.505051 -87.810307) (xy 14.428129 -87.839876) (xy 14.388592 -87.851488) (xy 14.378272 -87.854974)
			(xy 14.361634 -87.868997) (xy 14.352246 -87.888628) (xy 14.351508 -87.899494) (xy 14.349967 -87.947817)
			(xy 14.337717 -88.043725) (xy 14.315149 -88.137742) (xy 14.299438 -88.183466) (xy 14.296768 -88.191898)
			(xy 14.296781 -88.209573) (xy 14.299438 -88.21801) (xy 14.311946 -88.254194) (xy 14.331458 -88.328232)
			(xy 14.344543 -88.403671) (xy 14.351104 -88.479955) (xy 14.351508 -88.518238) (xy 14.351132 -88.556523)
			(xy 14.344589 -88.632811) (xy 14.331504 -88.708254) (xy 14.311975 -88.78229) (xy 14.299438 -88.818466)
			(xy 14.296768 -88.826898) (xy 14.296781 -88.844573) (xy 14.299438 -88.85301) (xy 14.311946 -88.889194)
			(xy 14.331458 -88.963232) (xy 14.344543 -89.038671) (xy 14.351104 -89.114955) (xy 14.351508 -89.153238)
			(xy 14.351004 -89.195586) (xy 14.342953 -89.2799) (xy 14.328055 -89.3572) (xy 37.185092 -89.3572)
			(xy 37.185578 -89.314532) (xy 37.193723 -89.229587) (xy 37.209955 -89.14581) (xy 37.234128 -89.06397)
			(xy 37.249608 -89.024206) (xy 37.252896 -89.014962) (xy 37.252881 -88.995357) (xy 37.249608 -88.986106)
			(xy 37.234119 -88.946345) (xy 37.209928 -88.864509) (xy 37.193695 -88.78073) (xy 37.185569 -88.695781)
			(xy 37.185092 -88.653112) (xy 37.185583 -88.611161) (xy 37.193475 -88.52763) (xy 37.20919 -88.445212)
			(xy 37.232588 -88.364638) (xy 37.247576 -88.325452) (xy 37.250781 -88.316325) (xy 37.250765 -88.296994)
			(xy 37.247576 -88.28786) (xy 37.232589 -88.248673) (xy 37.209168 -88.168104) (xy 37.193446 -88.085686)
			(xy 37.185564 -88.002152) (xy 37.185092 -87.9602) (xy 37.185596 -87.917852) (xy 37.193647 -87.833538)
			(xy 37.209676 -87.750372) (xy 37.233537 -87.669105) (xy 37.265016 -87.590475) (xy 37.303827 -87.515194)
			(xy 37.349617 -87.443942) (xy 37.401973 -87.377366) (xy 37.460421 -87.316068) (xy 37.524431 -87.260603)
			(xy 37.593423 -87.211474) (xy 37.666773 -87.169125) (xy 37.743816 -87.133941) (xy 37.823855 -87.106239)
			(xy 37.906164 -87.086271) (xy 37.989999 -87.074218) (xy 38.0746 -87.070188) (xy 38.159201 -87.074218)
			(xy 38.243036 -87.086271) (xy 38.325345 -87.106239) (xy 38.405384 -87.133941) (xy 38.482427 -87.169125)
			(xy 38.555777 -87.211474) (xy 38.624769 -87.260603) (xy 38.688779 -87.316068) (xy 38.747227 -87.377366)
			(xy 38.799583 -87.443942) (xy 38.845373 -87.515194) (xy 38.884184 -87.590475) (xy 38.915663 -87.669105)
			(xy 38.939524 -87.750372) (xy 38.955553 -87.833538) (xy 38.963604 -87.917852) (xy 38.964108 -87.9602)
			(xy 38.963621 -88.002151) (xy 38.955728 -88.085682) (xy 38.940012 -88.1681) (xy 38.916612 -88.248674)
			(xy 38.901624 -88.28786) (xy 38.898467 -88.297) (xy 38.898452 -88.316319) (xy 38.901624 -88.325452)
			(xy 38.916614 -88.364638) (xy 38.940035 -88.445207) (xy 38.955756 -88.527626) (xy 38.963636 -88.61116)
			(xy 38.964108 -88.653112) (xy 38.963625 -88.69578) (xy 38.95548 -88.780726) (xy 38.939246 -88.864503)
			(xy 38.915073 -88.946342) (xy 38.899592 -88.986106) (xy 38.896352 -88.995364) (xy 38.896337 -89.014956)
			(xy 38.899592 -89.024206) (xy 38.915085 -89.063966) (xy 38.939275 -89.145802) (xy 38.955507 -89.229582)
			(xy 38.963632 -89.314531) (xy 38.964108 -89.3572) (xy 38.963604 -89.399548) (xy 38.955553 -89.483862)
			(xy 38.939524 -89.567028) (xy 38.915663 -89.648295) (xy 38.884184 -89.726925) (xy 38.845373 -89.802206)
			(xy 38.799583 -89.873458) (xy 38.747227 -89.940034) (xy 38.688779 -90.001332) (xy 38.624769 -90.056797)
			(xy 38.555777 -90.105926) (xy 38.482427 -90.148275) (xy 38.405384 -90.183459) (xy 38.325345 -90.211161)
			(xy 38.243036 -90.231129) (xy 38.159201 -90.243182) (xy 38.0746 -90.247213) (xy 37.989999 -90.243182)
			(xy 37.906164 -90.231129) (xy 37.823855 -90.211161) (xy 37.743816 -90.183459) (xy 37.666773 -90.148275)
			(xy 37.593423 -90.105926) (xy 37.524431 -90.056797) (xy 37.460421 -90.001332) (xy 37.401973 -89.940034)
			(xy 37.349617 -89.873458) (xy 37.303827 -89.802206) (xy 37.265016 -89.726925) (xy 37.233537 -89.648295)
			(xy 37.209676 -89.567028) (xy 37.193647 -89.483862) (xy 37.185596 -89.399548) (xy 37.185092 -89.3572)
			(xy 14.328055 -89.3572) (xy 14.326924 -89.363066) (xy 14.303063 -89.444333) (xy 14.271584 -89.522963)
			(xy 14.232773 -89.598244) (xy 14.186983 -89.669496) (xy 14.134627 -89.736072) (xy 14.076179 -89.79737)
			(xy 14.012169 -89.852835) (xy 13.943177 -89.901964) (xy 13.869827 -89.944313) (xy 13.792784 -89.979497)
			(xy 13.712745 -90.007199) (xy 13.630436 -90.027167) (xy 13.546601 -90.03922) (xy 13.462 -90.043251)
			(xy 13.377399 -90.03922) (xy 13.293564 -90.027167) (xy 13.211255 -90.007199) (xy 13.131216 -89.979497)
			(xy 13.054173 -89.944313) (xy 12.980823 -89.901964) (xy 12.911831 -89.852835) (xy 12.847821 -89.79737)
			(xy 12.789373 -89.736072) (xy 12.737017 -89.669496) (xy 12.691227 -89.598244) (xy 12.652416 -89.522963)
			(xy 12.620937 -89.444333) (xy 12.597076 -89.363066) (xy 12.581047 -89.2799) (xy 12.572996 -89.195586)
			(xy 12.572492 -89.153238) (xy 0.509016 -89.153238) (xy 0.509016 -91.878912) (xy 3.555492 -91.878912)
			(xy 3.556079 -91.832517) (xy 3.565723 -91.740228) (xy 3.584918 -91.649445) (xy 3.613455 -91.561151)
			(xy 3.631692 -91.518486) (xy 3.63549 -91.508542) (xy 3.635495 -91.48728) (xy 3.631692 -91.477338)
			(xy 3.613451 -91.434674) (xy 3.584906 -91.346382) (xy 3.565712 -91.255598) (xy 3.556077 -91.163308)
			(xy 3.555492 -91.116912) (xy 3.555964 -91.075809) (xy 3.563548 -90.993954) (xy 3.578652 -90.913147)
			(xy 3.601148 -90.834079) (xy 3.630843 -90.757424) (xy 3.667485 -90.683836) (xy 3.71076 -90.613943)
			(xy 3.7603 -90.548341) (xy 3.815681 -90.487589) (xy 3.876432 -90.432207) (xy 3.942033 -90.382667)
			(xy 4.011926 -90.339391) (xy 4.085513 -90.302748) (xy 4.162168 -90.273052) (xy 4.241236 -90.250555)
			(xy 4.322042 -90.235449) (xy 4.403897 -90.227864) (xy 4.445 -90.227404) (xy 4.491396 -90.227986)
			(xy 4.583684 -90.237631) (xy 4.674468 -90.256827) (xy 4.762761 -90.285366) (xy 4.805426 -90.303604)
			(xy 4.815368 -90.30741) (xy 4.836632 -90.30741) (xy 4.846574 -90.303604) (xy 4.889236 -90.28536)
			(xy 4.977529 -90.256816) (xy 5.068314 -90.237622) (xy 5.160604 -90.227989) (xy 5.207 -90.227404)
			(xy 5.253396 -90.227986) (xy 5.345684 -90.237631) (xy 5.436468 -90.256827) (xy 5.524761 -90.285366)
			(xy 5.567426 -90.303604) (xy 5.577368 -90.30741) (xy 5.598632 -90.30741) (xy 5.608574 -90.303604)
			(xy 5.651236 -90.28536) (xy 5.739529 -90.256816) (xy 5.830314 -90.237622) (xy 5.922604 -90.227989)
			(xy 5.969 -90.227404) (xy 6.015396 -90.227986) (xy 6.107684 -90.237631) (xy 6.198468 -90.256827)
			(xy 6.286761 -90.285366) (xy 6.329426 -90.303604) (xy 6.339368 -90.30741) (xy 6.360632 -90.30741)
			(xy 6.370574 -90.303604) (xy 6.413236 -90.28536) (xy 6.501529 -90.256816) (xy 6.592314 -90.237622)
			(xy 6.684604 -90.227989) (xy 6.731 -90.227404) (xy 6.772103 -90.227862) (xy 6.853959 -90.235447)
			(xy 6.934766 -90.250553) (xy 7.013834 -90.27305) (xy 7.090489 -90.302746) (xy 7.164077 -90.339389)
			(xy 7.233971 -90.382665) (xy 7.299573 -90.432205) (xy 7.360324 -90.487587) (xy 7.415706 -90.548339)
			(xy 7.465246 -90.613941) (xy 7.508522 -90.683834) (xy 7.545165 -90.757423) (xy 7.574861 -90.834078)
			(xy 7.597358 -90.913146) (xy 7.612463 -90.993953) (xy 7.620048 -91.075809) (xy 7.620508 -91.116912)
			(xy 7.619929 -91.163308) (xy 7.610283 -91.255596) (xy 7.591086 -91.34638) (xy 7.562546 -91.434673)
			(xy 7.544308 -91.477338) (xy 7.540495 -91.487278) (xy 7.5405 -91.508544) (xy 7.544308 -91.518486)
			(xy 7.562557 -91.561147) (xy 7.5911 -91.64944) (xy 7.610292 -91.740225) (xy 7.619924 -91.832516)
			(xy 7.620508 -91.878912) (xy 7.620045 -91.920015) (xy 7.612459 -92.001869) (xy 7.597353 -92.082675)
			(xy 7.574855 -92.161742) (xy 7.545158 -92.238396) (xy 7.508516 -92.311983) (xy 7.465239 -92.381875)
			(xy 7.415699 -92.447476) (xy 7.360317 -92.508226) (xy 7.299566 -92.563607) (xy 7.233965 -92.613146)
			(xy 7.164072 -92.656421) (xy 7.090485 -92.693063) (xy 7.01383 -92.722759) (xy 6.934763 -92.745255)
			(xy 6.853957 -92.76036) (xy 6.772103 -92.767945) (xy 6.731 -92.76842) (xy 6.684604 -92.767836) (xy 6.592316 -92.758191)
			(xy 6.501532 -92.738996) (xy 6.413239 -92.710458) (xy 6.370574 -92.69222) (xy 6.360632 -92.688414)
			(xy 6.339368 -92.688414) (xy 6.329426 -92.69222) (xy 6.286764 -92.710466) (xy 6.198472 -92.739009)
			(xy 6.107686 -92.758202) (xy 6.015396 -92.767835) (xy 5.969 -92.76842) (xy 5.922604 -92.767836) (xy 5.830316 -92.758191)
			(xy 5.739532 -92.738996) (xy 5.651239 -92.710458) (xy 5.608574 -92.69222) (xy 5.598632 -92.688414)
			(xy 5.577368 -92.688414) (xy 5.567426 -92.69222) (xy 5.524764 -92.710466) (xy 5.436472 -92.739009)
			(xy 5.345686 -92.758202) (xy 5.253396 -92.767835) (xy 5.207 -92.76842) (xy 5.160604 -92.767836) (xy 5.068316 -92.758191)
			(xy 4.977532 -92.738996) (xy 4.889239 -92.710458) (xy 4.846574 -92.69222) (xy 4.836632 -92.688414)
			(xy 4.815368 -92.688414) (xy 4.805426 -92.69222) (xy 4.762764 -92.710466) (xy 4.674472 -92.739009)
			(xy 4.583686 -92.758202) (xy 4.491396 -92.767835) (xy 4.445 -92.76842) (xy 4.403898 -92.767943) (xy 4.322043 -92.760358)
			(xy 4.241238 -92.745253) (xy 4.162171 -92.722757) (xy 4.085518 -92.693061) (xy 4.011931 -92.656419)
			(xy 3.942039 -92.613144) (xy 3.876438 -92.563605) (xy 3.815688 -92.508224) (xy 3.760307 -92.447474)
			(xy 3.710767 -92.381873) (xy 3.667492 -92.311981) (xy 3.63085 -92.238394) (xy 3.601154 -92.16174)
			(xy 3.578657 -92.082674) (xy 3.563552 -92.001869) (xy 3.555967 -91.920014) (xy 3.555492 -91.878912)
			(xy 0.509016 -91.878912) (xy 0.509016 -93.979238) (xy 12.572492 -93.979238) (xy 12.572861 -93.940953)
			(xy 12.579406 -93.864664) (xy 12.592493 -93.789222) (xy 12.612024 -93.715186) (xy 12.624562 -93.67901)
			(xy 12.627193 -93.670568) (xy 12.627206 -93.652902) (xy 12.624562 -93.644466) (xy 12.612047 -93.608284)
			(xy 12.592537 -93.534246) (xy 12.579454 -93.458806) (xy 12.572895 -93.382521) (xy 12.572492 -93.344238)
			(xy 12.572861 -93.305953) (xy 12.579406 -93.229664) (xy 12.592493 -93.154222) (xy 12.612024 -93.080186)
			(xy 12.624562 -93.04401) (xy 12.627193 -93.035568) (xy 12.627206 -93.017902) (xy 12.624562 -93.009466)
			(xy 12.612047 -92.973284) (xy 12.592537 -92.899246) (xy 12.579454 -92.823806) (xy 12.572895 -92.747521)
			(xy 12.572492 -92.709238) (xy 12.572996 -92.66689) (xy 12.581047 -92.582576) (xy 12.597076 -92.49941)
			(xy 12.620937 -92.418143) (xy 12.652416 -92.339513) (xy 12.691227 -92.264232) (xy 12.737017 -92.19298)
			(xy 12.789373 -92.126404) (xy 12.847821 -92.065106) (xy 12.911831 -92.009641) (xy 12.980823 -91.960512)
			(xy 13.054173 -91.918163) (xy 13.131216 -91.882979) (xy 13.211255 -91.855277) (xy 13.293564 -91.835309)
			(xy 13.377399 -91.823256) (xy 13.462 -91.819226) (xy 13.546601 -91.823256) (xy 13.630436 -91.835309)
			(xy 13.712745 -91.855277) (xy 13.792784 -91.882979) (xy 13.869827 -91.918163) (xy 13.943177 -91.960512)
			(xy 14.012169 -92.009641) (xy 14.076179 -92.065106) (xy 14.134627 -92.126404) (xy 14.186983 -92.19298)
			(xy 14.232773 -92.264232) (xy 14.271584 -92.339513) (xy 14.303063 -92.418143) (xy 14.326924 -92.49941)
			(xy 14.342953 -92.582576) (xy 14.351004 -92.66689) (xy 14.351508 -92.709238) (xy 14.351132 -92.747523)
			(xy 14.344589 -92.823811) (xy 14.331504 -92.899254) (xy 14.311975 -92.97329) (xy 14.299438 -93.009466)
			(xy 14.296768 -93.017898) (xy 14.296781 -93.035573) (xy 14.299438 -93.04401) (xy 14.311946 -93.080194)
			(xy 14.331458 -93.154232) (xy 14.344543 -93.229671) (xy 14.351104 -93.305955) (xy 14.351508 -93.344238)
			(xy 14.351132 -93.382523) (xy 14.344589 -93.458811) (xy 14.331504 -93.534254) (xy 14.311975 -93.60829)
			(xy 14.299438 -93.644466) (xy 14.296768 -93.652898) (xy 14.296781 -93.670573) (xy 14.299438 -93.67901)
			(xy 14.311946 -93.715194) (xy 14.331458 -93.789232) (xy 14.344543 -93.864671) (xy 14.351104 -93.940955)
			(xy 14.351508 -93.979238) (xy 14.351004 -94.021586) (xy 14.347699 -94.0562) (xy 37.185092 -94.0562)
			(xy 37.185578 -94.013532) (xy 37.193723 -93.928587) (xy 37.209955 -93.84481) (xy 37.234128 -93.76297)
			(xy 37.249608 -93.723206) (xy 37.252896 -93.713962) (xy 37.252881 -93.694357) (xy 37.249608 -93.685106)
			(xy 37.234119 -93.645345) (xy 37.209928 -93.563509) (xy 37.193695 -93.47973) (xy 37.185569 -93.394781)
			(xy 37.185092 -93.352112) (xy 37.185526 -93.311974) (xy 37.19274 -93.232022) (xy 37.207128 -93.153046)
			(xy 37.228573 -93.075687) (xy 37.256901 -93.000575) (xy 37.273992 -92.964254) (xy 37.278542 -92.95367)
			(xy 37.278524 -92.930651) (xy 37.273992 -92.920058) (xy 37.256885 -92.883745) (xy 37.228557 -92.808631)
			(xy 37.207114 -92.731271) (xy 37.19273 -92.652292) (xy 37.185523 -92.572339) (xy 37.185092 -92.5322)
			(xy 37.185596 -92.489852) (xy 37.193647 -92.405538) (xy 37.209676 -92.322372) (xy 37.233537 -92.241105)
			(xy 37.265016 -92.162475) (xy 37.303827 -92.087194) (xy 37.349617 -92.015942) (xy 37.401973 -91.949366)
			(xy 37.460421 -91.888068) (xy 37.524431 -91.832603) (xy 37.593423 -91.783474) (xy 37.666773 -91.741125)
			(xy 37.743816 -91.705941) (xy 37.823855 -91.678239) (xy 37.906164 -91.658271) (xy 37.989999 -91.646218)
			(xy 38.0746 -91.642188) (xy 38.159201 -91.646218) (xy 38.243036 -91.658271) (xy 38.325345 -91.678239)
			(xy 38.405384 -91.705941) (xy 38.482427 -91.741125) (xy 38.555777 -91.783474) (xy 38.624769 -91.832603)
			(xy 38.688779 -91.888068) (xy 38.747227 -91.949366) (xy 38.799583 -92.015942) (xy 38.803258 -92.02166)
			(xy 44.032424 -92.02166) (xy 44.032804 -91.983375) (xy 44.039346 -91.907087) (xy 44.05243 -91.831644)
			(xy 44.071958 -91.757608) (xy 44.084494 -91.721432) (xy 44.087163 -91.713) (xy 44.08715 -91.695325)
			(xy 44.084494 -91.686888) (xy 44.071987 -91.650704) (xy 44.052474 -91.576666) (xy 44.039389 -91.501227)
			(xy 44.032828 -91.424943) (xy 44.032424 -91.38666) (xy 44.032829 -91.345556) (xy 44.040417 -91.263699)
			(xy 44.055527 -91.182891) (xy 44.078027 -91.103822) (xy 44.107728 -91.027166) (xy 44.144374 -90.953578)
			(xy 44.187654 -90.883685) (xy 44.237198 -90.818084) (xy 44.292584 -90.757333) (xy 44.353339 -90.701952)
			(xy 44.418945 -90.652413) (xy 44.488841 -90.609139) (xy 44.562432 -90.572499) (xy 44.63909 -90.542805)
			(xy 44.718161 -90.52031) (xy 44.79897 -90.505207) (xy 44.880828 -90.497625) (xy 44.921932 -90.497152)
			(xy 44.968327 -90.497754) (xy 45.060615 -90.507393) (xy 45.151399 -90.526583) (xy 45.239693 -90.555116)
			(xy 45.282358 -90.573352) (xy 45.2923 -90.577158) (xy 45.313564 -90.577158) (xy 45.323506 -90.573352)
			(xy 45.366163 -90.555094) (xy 45.454457 -90.526554) (xy 45.545244 -90.507365) (xy 45.637536 -90.497735)
			(xy 45.683932 -90.497152) (xy 45.730327 -90.497754) (xy 45.822615 -90.507393) (xy 45.913399 -90.526583)
			(xy 46.001693 -90.555116) (xy 46.044358 -90.573352) (xy 46.0543 -90.577158) (xy 46.075564 -90.577158)
			(xy 46.085506 -90.573352) (xy 46.128163 -90.555094) (xy 46.216457 -90.526554) (xy 46.307244 -90.507365)
			(xy 46.399536 -90.497735) (xy 46.445932 -90.497152) (xy 46.492327 -90.497754) (xy 46.584615 -90.507393)
			(xy 46.675399 -90.526583) (xy 46.763693 -90.555116) (xy 46.806358 -90.573352) (xy 46.8163 -90.577158)
			(xy 46.837564 -90.577158) (xy 46.847506 -90.573352) (xy 46.890163 -90.555094) (xy 46.978457 -90.526554)
			(xy 47.069244 -90.507365) (xy 47.161536 -90.497735) (xy 47.207932 -90.497152) (xy 47.249034 -90.497636)
			(xy 47.330887 -90.505223) (xy 47.41169 -90.52033) (xy 47.490755 -90.542828) (xy 47.567408 -90.572525)
			(xy 47.640993 -90.609167) (xy 47.710884 -90.652442) (xy 47.776483 -90.701981) (xy 47.837233 -90.757362)
			(xy 47.892614 -90.81811) (xy 47.942153 -90.88371) (xy 47.985429 -90.9536) (xy 48.022072 -91.027185)
			(xy 48.051769 -91.103837) (xy 48.074268 -91.182902) (xy 48.089375 -91.263705) (xy 48.096964 -91.345558)
			(xy 48.09744 -91.38666) (xy 48.097068 -91.424945) (xy 48.090524 -91.501234) (xy 48.077438 -91.576676)
			(xy 48.057907 -91.650712) (xy 48.04537 -91.686888) (xy 48.042738 -91.69533) (xy 48.042725 -91.712996)
			(xy 48.04537 -91.721432) (xy 48.057886 -91.757614) (xy 48.077395 -91.831652) (xy 48.090478 -91.907092)
			(xy 48.097037 -91.983377) (xy 48.09744 -92.02166) (xy 48.09691 -92.062762) (xy 48.089329 -92.144614)
			(xy 48.074227 -92.225418) (xy 48.051735 -92.304484) (xy 48.022043 -92.381138) (xy 47.985405 -92.454725)
			(xy 47.942134 -92.524617) (xy 47.892598 -92.590218) (xy 47.83722 -92.65097) (xy 47.776474 -92.706352)
			(xy 47.710876 -92.755893) (xy 47.640988 -92.79917) (xy 47.567404 -92.835814) (xy 47.490753 -92.865512)
			(xy 47.411689 -92.888011) (xy 47.330886 -92.903119) (xy 47.249034 -92.910706) (xy 47.207932 -92.911168)
			(xy 47.161537 -92.910577) (xy 47.069248 -92.900935) (xy 46.978465 -92.881741) (xy 46.890171 -92.853205)
			(xy 46.847506 -92.834968) (xy 46.837564 -92.831162) (xy 46.8163 -92.831162) (xy 46.806358 -92.834968)
			(xy 46.76369 -92.8532) (xy 46.6754 -92.881748) (xy 46.584617 -92.900945) (xy 46.492328 -92.910581)
			(xy 46.445932 -92.911168) (xy 46.399537 -92.910577) (xy 46.307248 -92.900935) (xy 46.216465 -92.881741)
			(xy 46.128171 -92.853205) (xy 46.085506 -92.834968) (xy 46.075564 -92.831162) (xy 46.0543 -92.831162)
			(xy 46.044358 -92.834968) (xy 46.00169 -92.8532) (xy 45.9134 -92.881748) (xy 45.822617 -92.900945)
			(xy 45.730328 -92.910581) (xy 45.683932 -92.911168) (xy 45.637537 -92.910577) (xy 45.545248 -92.900935)
			(xy 45.454465 -92.881741) (xy 45.366171 -92.853205) (xy 45.323506 -92.834968) (xy 45.313564 -92.831162)
			(xy 45.2923 -92.831162) (xy 45.282358 -92.834968) (xy 45.23969 -92.8532) (xy 45.1514 -92.881748)
			(xy 45.060617 -92.900945) (xy 44.968328 -92.910581) (xy 44.921932 -92.911168) (xy 44.880828 -92.910717)
			(xy 44.798971 -92.903135) (xy 44.718163 -92.888031) (xy 44.639093 -92.865536) (xy 44.562436 -92.83584)
			(xy 44.488846 -92.799198) (xy 44.418952 -92.755922) (xy 44.353349 -92.706381) (xy 44.292597 -92.650998)
			(xy 44.237214 -92.590245) (xy 44.187674 -92.524642) (xy 44.144398 -92.454747) (xy 44.107757 -92.381157)
			(xy 44.078062 -92.3045) (xy 44.055567 -92.225429) (xy 44.040464 -92.144621) (xy 44.032882 -92.062764)
			(xy 44.032424 -92.02166) (xy 38.803258 -92.02166) (xy 38.845373 -92.087194) (xy 38.884184 -92.162475)
			(xy 38.915663 -92.241105) (xy 38.939524 -92.322372) (xy 38.955553 -92.405538) (xy 38.963604 -92.489852)
			(xy 38.964108 -92.5322) (xy 38.963678 -92.572338) (xy 38.956464 -92.65229) (xy 38.942074 -92.731267)
			(xy 38.920628 -92.808626) (xy 38.892299 -92.883738) (xy 38.875208 -92.920058) (xy 38.870715 -92.93066)
			(xy 38.870697 -92.953661) (xy 38.875208 -92.964254) (xy 38.89232 -93.000565) (xy 38.920646 -93.075679)
			(xy 38.942088 -93.15304) (xy 38.956471 -93.232019) (xy 38.963678 -93.311973) (xy 38.964108 -93.352112)
			(xy 38.963625 -93.39478) (xy 38.95548 -93.479726) (xy 38.939246 -93.563503) (xy 38.915073 -93.645342)
			(xy 38.899592 -93.685106) (xy 38.896352 -93.694364) (xy 38.896337 -93.713956) (xy 38.899592 -93.723206)
			(xy 38.915085 -93.762966) (xy 38.939275 -93.844802) (xy 38.955507 -93.928582) (xy 38.963632 -94.013531)
			(xy 38.964108 -94.0562) (xy 38.963604 -94.098548) (xy 38.955553 -94.182862) (xy 38.939524 -94.266028)
			(xy 38.915663 -94.347295) (xy 38.884184 -94.425925) (xy 38.845373 -94.501206) (xy 38.799583 -94.572458)
			(xy 38.747227 -94.639034) (xy 38.688779 -94.700332) (xy 38.624769 -94.755797) (xy 38.555777 -94.804926)
			(xy 38.482427 -94.847275) (xy 38.405384 -94.882459) (xy 38.325345 -94.910161) (xy 38.243036 -94.930129)
			(xy 38.159201 -94.942182) (xy 38.0746 -94.946213) (xy 37.989999 -94.942182) (xy 37.906164 -94.930129)
			(xy 37.823855 -94.910161) (xy 37.743816 -94.882459) (xy 37.666773 -94.847275) (xy 37.593423 -94.804926)
			(xy 37.524431 -94.755797) (xy 37.460421 -94.700332) (xy 37.401973 -94.639034) (xy 37.349617 -94.572458)
			(xy 37.303827 -94.501206) (xy 37.265016 -94.425925) (xy 37.233537 -94.347295) (xy 37.209676 -94.266028)
			(xy 37.193647 -94.182862) (xy 37.185596 -94.098548) (xy 37.185092 -94.0562) (xy 14.347699 -94.0562)
			(xy 14.342953 -94.1059) (xy 14.326924 -94.189066) (xy 14.303063 -94.270333) (xy 14.271584 -94.348963)
			(xy 14.232773 -94.424244) (xy 14.186983 -94.495496) (xy 14.134627 -94.562072) (xy 14.076179 -94.62337)
			(xy 14.012169 -94.678835) (xy 13.943177 -94.727964) (xy 13.869827 -94.770313) (xy 13.792784 -94.805497)
			(xy 13.712745 -94.833199) (xy 13.630436 -94.853167) (xy 13.546601 -94.86522) (xy 13.462 -94.869251)
			(xy 13.377399 -94.86522) (xy 13.293564 -94.853167) (xy 13.211255 -94.833199) (xy 13.131216 -94.805497)
			(xy 13.054173 -94.770313) (xy 12.980823 -94.727964) (xy 12.911831 -94.678835) (xy 12.847821 -94.62337)
			(xy 12.789373 -94.562072) (xy 12.737017 -94.495496) (xy 12.691227 -94.424244) (xy 12.652416 -94.348963)
			(xy 12.620937 -94.270333) (xy 12.597076 -94.189066) (xy 12.581047 -94.1059) (xy 12.572996 -94.021586)
			(xy 12.572492 -93.979238) (xy 0.509016 -93.979238) (xy 0.509016 -98.975361) (xy 26.288742 -98.975361)
			(xy 26.288742 -98.890639) (xy 26.296795 -98.806302) (xy 26.312829 -98.723112) (xy 26.336697 -98.641822)
			(xy 26.368185 -98.56317) (xy 26.407007 -98.487867) (xy 26.45281 -98.416595) (xy 26.505181 -98.349999)
			(xy 26.563646 -98.288684) (xy 26.627674 -98.233203) (xy 26.696686 -98.18406) (xy 26.770056 -98.1417)
			(xy 26.847121 -98.106505) (xy 26.927183 -98.078796) (xy 27.009516 -98.058822) (xy 27.093375 -98.046765)
			(xy 27.178 -98.042734) (xy 27.262625 -98.046765) (xy 27.346484 -98.058822) (xy 27.428817 -98.078796)
			(xy 27.508879 -98.106505) (xy 27.585944 -98.1417) (xy 27.659314 -98.18406) (xy 27.728326 -98.233203)
			(xy 27.792354 -98.288684) (xy 27.850819 -98.349999) (xy 27.90319 -98.416595) (xy 27.948993 -98.487867)
			(xy 27.987815 -98.56317) (xy 28.019303 -98.641822) (xy 28.043171 -98.723112) (xy 28.059205 -98.806302)
			(xy 28.067258 -98.890639) (xy 28.067762 -98.933) (xy 28.067258 -98.975361) (xy 28.059205 -99.059698)
			(xy 28.043171 -99.142888) (xy 28.019303 -99.224178) (xy 27.987815 -99.30283) (xy 27.948993 -99.378133)
			(xy 27.90319 -99.449405) (xy 27.850819 -99.516001) (xy 27.792354 -99.577316) (xy 27.728326 -99.632797)
			(xy 27.659314 -99.68194) (xy 27.585944 -99.7243) (xy 27.508879 -99.759495) (xy 27.428817 -99.787204)
			(xy 27.346484 -99.807178) (xy 27.262625 -99.819235) (xy 27.178 -99.823267) (xy 27.093375 -99.819235)
			(xy 27.009516 -99.807178) (xy 26.927183 -99.787204) (xy 26.847121 -99.759495) (xy 26.770056 -99.7243)
			(xy 26.696686 -99.68194) (xy 26.627674 -99.632797) (xy 26.563646 -99.577316) (xy 26.505181 -99.516001)
			(xy 26.45281 -99.449405) (xy 26.407007 -99.378133) (xy 26.368185 -99.30283) (xy 26.336697 -99.224178)
			(xy 26.312829 -99.142888) (xy 26.296795 -99.059698) (xy 26.288742 -98.975361) (xy 0.509016 -98.975361)
			(xy 0.509016 -101.134361) (xy 20.065742 -101.134361) (xy 20.065742 -101.049639) (xy 20.073795 -100.965302)
			(xy 20.089829 -100.882112) (xy 20.113697 -100.800822) (xy 20.145185 -100.72217) (xy 20.184007 -100.646867)
			(xy 20.22981 -100.575595) (xy 20.282181 -100.508999) (xy 20.340646 -100.447684) (xy 20.404674 -100.392203)
			(xy 20.473686 -100.34306) (xy 20.547056 -100.3007) (xy 20.624121 -100.265505) (xy 20.704183 -100.237796)
			(xy 20.786516 -100.217822) (xy 20.870375 -100.205765) (xy 20.955 -100.201734) (xy 21.039625 -100.205765)
			(xy 21.123484 -100.217822) (xy 21.205817 -100.237796) (xy 21.285879 -100.265505) (xy 21.362944 -100.3007)
			(xy 21.436314 -100.34306) (xy 21.505326 -100.392203) (xy 21.569354 -100.447684) (xy 21.627819 -100.508999)
			(xy 21.68019 -100.575595) (xy 21.725993 -100.646867) (xy 21.764815 -100.72217) (xy 21.796303 -100.800822)
			(xy 21.807219 -100.838) (xy 28.702 -100.838) (xy 28.702474 -100.796921) (xy 28.710055 -100.715113)
			(xy 28.725151 -100.634354) (xy 28.747635 -100.555332) (xy 28.777314 -100.478722) (xy 28.813935 -100.405177)
			(xy 28.857185 -100.335325) (xy 28.906697 -100.269762) (xy 28.962046 -100.209046) (xy 29.022762 -100.153697)
			(xy 29.088325 -100.104185) (xy 29.158177 -100.060935) (xy 29.231722 -100.024314) (xy 29.308332 -99.994635)
			(xy 29.387354 -99.972151) (xy 29.468113 -99.957055) (xy 29.549921 -99.949474) (xy 29.591 -99.949)
			(xy 29.632983 -99.949463) (xy 29.716576 -99.957372) (xy 29.79905 -99.973128) (xy 29.879672 -99.996591)
			(xy 29.957721 -100.027553) (xy 30.032503 -100.065736) (xy 30.103351 -100.110801) (xy 30.169634 -100.162346)
			(xy 30.23076 -100.219912) (xy 30.286186 -100.282986) (xy 30.335417 -100.351005) (xy 30.378014 -100.423364)
			(xy 30.413598 -100.499417) (xy 30.428184 -100.538788) (xy 30.430456 -100.544618) (xy 30.437389 -100.555027)
			(xy 30.4419 -100.559362) (xy 30.472208 -100.587402) (xy 30.52802 -100.64826) (xy 30.577954 -100.714026)
			(xy 30.621581 -100.784135) (xy 30.658526 -100.857984) (xy 30.68847 -100.934938) (xy 30.711156 -101.014335)
			(xy 30.72639 -101.095493) (xy 30.73404 -101.177713) (xy 30.734508 -101.219) (xy 30.734033 -101.260102)
			(xy 30.726448 -101.341957) (xy 30.711343 -101.422762) (xy 30.688847 -101.501829) (xy 30.659151 -101.578483)
			(xy 30.622509 -101.65207) (xy 30.579234 -101.721962) (xy 30.529694 -101.787563) (xy 30.474313 -101.848313)
			(xy 30.413563 -101.903694) (xy 30.347962 -101.953234) (xy 30.27807 -101.996509) (xy 30.204483 -102.033151)
			(xy 30.127829 -102.062847) (xy 30.048762 -102.085343) (xy 29.967957 -102.100448) (xy 29.886102 -102.108033)
			(xy 29.845 -102.108508) (xy 29.802903 -102.108048) (xy 29.719084 -102.100101) (xy 29.636391 -102.084268)
			(xy 29.555565 -102.060692) (xy 29.477328 -102.029583) (xy 29.402381 -101.99122) (xy 29.331395 -101.945945)
			(xy 29.265005 -101.894166) (xy 29.203806 -101.836344) (xy 29.148344 -101.772997) (xy 29.099118 -101.704693)
			(xy 29.056566 -101.632042) (xy 29.02107 -101.555695) (xy 29.006546 -101.51618) (xy 29.004259 -101.51036)
			(xy 28.997316 -101.499963) (xy 28.99283 -101.495606) (xy 28.962727 -101.467571) (xy 28.907237 -101.406838)
			(xy 28.857597 -101.341238) (xy 28.814231 -101.271331) (xy 28.777511 -101.197716) (xy 28.74775 -101.121022)
			(xy 28.725204 -101.041907) (xy 28.710065 -100.961046) (xy 28.702463 -100.879133) (xy 28.702 -100.838)
			(xy 21.807219 -100.838) (xy 21.820171 -100.882112) (xy 21.836205 -100.965302) (xy 21.844258 -101.049639)
			(xy 21.844762 -101.092) (xy 21.844258 -101.134361) (xy 21.836205 -101.218698) (xy 21.820171 -101.301888)
			(xy 21.796303 -101.383178) (xy 21.764815 -101.46183) (xy 21.725993 -101.537133) (xy 21.68019 -101.608405)
			(xy 21.627819 -101.675001) (xy 21.569354 -101.736316) (xy 21.505326 -101.791797) (xy 21.436314 -101.84094)
			(xy 21.362944 -101.8833) (xy 21.285879 -101.918495) (xy 21.205817 -101.946204) (xy 21.123484 -101.966178)
			(xy 21.039625 -101.978235) (xy 20.955 -101.982267) (xy 20.870375 -101.978235) (xy 20.786516 -101.966178)
			(xy 20.704183 -101.946204) (xy 20.624121 -101.918495) (xy 20.547056 -101.8833) (xy 20.473686 -101.84094)
			(xy 20.404674 -101.791797) (xy 20.340646 -101.736316) (xy 20.282181 -101.675001) (xy 20.22981 -101.608405)
			(xy 20.184007 -101.537133) (xy 20.145185 -101.46183) (xy 20.113697 -101.383178) (xy 20.089829 -101.301888)
			(xy 20.073795 -101.218698) (xy 20.065742 -101.134361) (xy 0.509016 -101.134361) (xy 0.509016 -102.810056)
			(xy 6.441451 -102.810056) (xy 6.445429 -102.710063) (xy 6.457339 -102.610703) (xy 6.477106 -102.512602)
			(xy 6.504605 -102.416383) (xy 6.539661 -102.322652) (xy 6.582053 -102.232003) (xy 6.631514 -102.145009)
			(xy 6.68773 -102.062219) (xy 6.750346 -101.984157) (xy 6.818965 -101.911317) (xy 6.893156 -101.844159)
			(xy 6.972447 -101.783107) (xy 7.056338 -101.728549) (xy 7.144299 -101.680828) (xy 7.235773 -101.640246)
			(xy 7.330182 -101.60706) (xy 7.426929 -101.58148) (xy 7.525403 -101.563667) (xy 7.624981 -101.553735)
			(xy 7.725033 -101.551745) (xy 7.824927 -101.557711) (xy 7.924031 -101.571595) (xy 8.021719 -101.593308)
			(xy 8.117373 -101.622714) (xy 8.210388 -101.659627) (xy 8.300176 -101.703813) (xy 8.38617 -101.754994)
			(xy 8.467826 -101.812844) (xy 8.544627 -101.877) (xy 8.616089 -101.947054) (xy 8.681759 -102.022565)
			(xy 8.741221 -102.103055) (xy 8.794101 -102.188014) (xy 8.840064 -102.276906) (xy 8.878819 -102.369169)
			(xy 8.910121 -102.464219) (xy 8.933773 -102.561456) (xy 8.949624 -102.660265) (xy 8.957574 -102.76002)
			(xy 8.958072 -102.810056) (xy 8.957574 -102.860092) (xy 8.949624 -102.959847) (xy 8.933773 -103.058656)
			(xy 8.910121 -103.155893) (xy 8.878819 -103.250943) (xy 8.874033 -103.262336) (xy 18.801076 -103.262336)
			(xy 18.801076 -103.177688) (xy 18.809122 -103.093422) (xy 18.825142 -103.010303) (xy 18.84899 -102.929084)
			(xy 18.880451 -102.850499) (xy 18.919239 -102.77526) (xy 18.965003 -102.704049) (xy 19.01733 -102.637511)
			(xy 19.075744 -102.576248) (xy 19.139717 -102.520815) (xy 19.20867 -102.471714) (xy 19.281978 -102.429389)
			(xy 19.358977 -102.394225) (xy 19.43897 -102.366539) (xy 19.521232 -102.346582) (xy 19.605019 -102.334536)
			(xy 19.689572 -102.330508) (xy 19.774125 -102.334536) (xy 19.857912 -102.346582) (xy 19.940174 -102.366539)
			(xy 20.020167 -102.394225) (xy 20.097166 -102.429389) (xy 20.170474 -102.471714) (xy 20.239427 -102.520815)
			(xy 20.3034 -102.576248) (xy 20.361814 -102.637511) (xy 20.414141 -102.704049) (xy 20.459905 -102.77526)
			(xy 20.498693 -102.850499) (xy 20.530154 -102.929084) (xy 20.554002 -103.010303) (xy 20.570022 -103.093422)
			(xy 20.578068 -103.177688) (xy 20.578572 -103.220012) (xy 20.578068 -103.262336) (xy 20.570022 -103.346602)
			(xy 20.554002 -103.429721) (xy 20.530154 -103.51094) (xy 20.498693 -103.589525) (xy 20.459905 -103.664764)
			(xy 20.414141 -103.735975) (xy 20.361814 -103.802513) (xy 20.3034 -103.863776) (xy 20.239427 -103.919209)
			(xy 20.170474 -103.96831) (xy 20.097166 -104.010635) (xy 20.020167 -104.045799) (xy 19.940174 -104.073485)
			(xy 19.857912 -104.093442) (xy 19.774125 -104.105488) (xy 19.689572 -104.109516) (xy 19.605019 -104.105488)
			(xy 19.521232 -104.093442) (xy 19.43897 -104.073485) (xy 19.358977 -104.045799) (xy 19.281978 -104.010635)
			(xy 19.20867 -103.96831) (xy 19.139717 -103.919209) (xy 19.075744 -103.863776) (xy 19.01733 -103.802513)
			(xy 18.965003 -103.735975) (xy 18.919239 -103.664764) (xy 18.880451 -103.589525) (xy 18.84899 -103.51094)
			(xy 18.825142 -103.429721) (xy 18.809122 -103.346602) (xy 18.801076 -103.262336) (xy 8.874033 -103.262336)
			(xy 8.840064 -103.343206) (xy 8.794101 -103.432098) (xy 8.741221 -103.517057) (xy 8.681759 -103.597547)
			(xy 8.616089 -103.673058) (xy 8.544627 -103.743112) (xy 8.467826 -103.807268) (xy 8.38617 -103.865118)
			(xy 8.300176 -103.916299) (xy 8.210388 -103.960485) (xy 8.117373 -103.997398) (xy 8.021719 -104.026804)
			(xy 7.924031 -104.048517) (xy 7.824927 -104.062401) (xy 7.725033 -104.068367) (xy 7.624981 -104.066377)
			(xy 7.525403 -104.056445) (xy 7.426929 -104.038632) (xy 7.330182 -104.013052) (xy 7.235773 -103.979866)
			(xy 7.144299 -103.939284) (xy 7.056338 -103.891563) (xy 6.972447 -103.837005) (xy 6.893156 -103.775953)
			(xy 6.818965 -103.708795) (xy 6.750346 -103.635955) (xy 6.68773 -103.557893) (xy 6.631514 -103.475103)
			(xy 6.582053 -103.388109) (xy 6.539661 -103.29746) (xy 6.504605 -103.203729) (xy 6.477106 -103.10751)
			(xy 6.457339 -103.009409) (xy 6.445429 -102.910049) (xy 6.441451 -102.810056) (xy 0.509016 -102.810056)
			(xy 0.509016 -105.452361) (xy 19.938742 -105.452361) (xy 19.938742 -105.367639) (xy 19.946795 -105.283302)
			(xy 19.962829 -105.200112) (xy 19.986697 -105.118822) (xy 20.018185 -105.04017) (xy 20.057007 -104.964867)
			(xy 20.10281 -104.893595) (xy 20.155181 -104.826999) (xy 20.213646 -104.765684) (xy 20.277674 -104.710203)
			(xy 20.346686 -104.66106) (xy 20.420056 -104.6187) (xy 20.497121 -104.583505) (xy 20.577183 -104.555796)
			(xy 20.659516 -104.535822) (xy 20.743375 -104.523765) (xy 20.828 -104.519734) (xy 20.912625 -104.523765)
			(xy 20.996484 -104.535822) (xy 21.078817 -104.555796) (xy 21.158879 -104.583505) (xy 21.235944 -104.6187)
			(xy 21.309314 -104.66106) (xy 21.378326 -104.710203) (xy 21.442354 -104.765684) (xy 21.500819 -104.826999)
			(xy 21.55319 -104.893595) (xy 21.598993 -104.964867) (xy 21.637815 -105.04017) (xy 21.669303 -105.118822)
			(xy 21.693171 -105.200112) (xy 21.709205 -105.283302) (xy 21.717258 -105.367639) (xy 21.717762 -105.41)
			(xy 21.717258 -105.452361) (xy 21.709205 -105.536698) (xy 21.693171 -105.619888) (xy 21.669303 -105.701178)
			(xy 21.637815 -105.77983) (xy 21.598993 -105.855133) (xy 21.55319 -105.926405) (xy 21.500819 -105.993001)
			(xy 21.442354 -106.054316) (xy 21.378326 -106.109797) (xy 21.309314 -106.15894) (xy 21.235944 -106.2013)
			(xy 21.158879 -106.236495) (xy 21.078817 -106.264204) (xy 20.996484 -106.284178) (xy 20.912625 -106.296235)
			(xy 20.828 -106.300267) (xy 20.743375 -106.296235) (xy 20.659516 -106.284178) (xy 20.577183 -106.264204)
			(xy 20.497121 -106.236495) (xy 20.420056 -106.2013) (xy 20.346686 -106.15894) (xy 20.277674 -106.109797)
			(xy 20.213646 -106.054316) (xy 20.155181 -105.993001) (xy 20.10281 -105.926405) (xy 20.057007 -105.855133)
			(xy 20.018185 -105.77983) (xy 19.986697 -105.701178) (xy 19.962829 -105.619888) (xy 19.946795 -105.536698)
			(xy 19.938742 -105.452361) (xy 0.509016 -105.452361) (xy 0.509016 -108.500361) (xy 17.144742 -108.500361)
			(xy 17.144742 -108.415639) (xy 17.152795 -108.331302) (xy 17.168829 -108.248112) (xy 17.192697 -108.166822)
			(xy 17.224185 -108.08817) (xy 17.263007 -108.012867) (xy 17.30881 -107.941595) (xy 17.361181 -107.874999)
			(xy 17.419646 -107.813684) (xy 17.483674 -107.758203) (xy 17.552686 -107.70906) (xy 17.626056 -107.6667)
			(xy 17.703121 -107.631505) (xy 17.783183 -107.603796) (xy 17.865516 -107.583822) (xy 17.949375 -107.571765)
			(xy 18.034 -107.567734) (xy 18.118625 -107.571765) (xy 18.202484 -107.583822) (xy 18.284817 -107.603796)
			(xy 18.364879 -107.631505) (xy 18.441944 -107.6667) (xy 18.515314 -107.70906) (xy 18.584326 -107.758203)
			(xy 18.648354 -107.813684) (xy 18.706819 -107.874999) (xy 18.75919 -107.941595) (xy 18.804993 -108.012867)
			(xy 18.843815 -108.08817) (xy 18.875303 -108.166822) (xy 18.899171 -108.248112) (xy 18.915205 -108.331302)
			(xy 18.923258 -108.415639) (xy 18.923762 -108.458) (xy 18.923258 -108.500361) (xy 18.915205 -108.584698)
			(xy 18.899171 -108.667888) (xy 18.886816 -108.709968) (xy 43.677851 -108.709968) (xy 43.681826 -108.607518)
			(xy 43.693729 -108.505685) (xy 43.713487 -108.40508) (xy 43.740982 -108.306309) (xy 43.776048 -108.209965)
			(xy 43.818474 -108.116629) (xy 43.868006 -108.026861) (xy 43.924346 -107.941201) (xy 43.987154 -107.860165)
			(xy 44.056052 -107.784239) (xy 44.130628 -107.713881) (xy 44.210431 -107.649513) (xy 44.294982 -107.591524)
			(xy 44.383773 -107.54026) (xy 44.476269 -107.496032) (xy 44.571914 -107.459104) (xy 44.670134 -107.429699)
			(xy 44.770337 -107.407994) (xy 44.87192 -107.394118) (xy 44.974274 -107.388157) (xy 45.076781 -107.390145)
			(xy 45.178826 -107.400071) (xy 45.279795 -107.417874) (xy 45.379081 -107.443449) (xy 45.476086 -107.47664)
			(xy 45.570228 -107.517249) (xy 45.66094 -107.565031) (xy 45.747676 -107.619699) (xy 45.829915 -107.680923)
			(xy 45.907162 -107.748337) (xy 45.978953 -107.821534) (xy 46.044856 -107.900074) (xy 46.104475 -107.983484)
			(xy 46.15745 -108.071264) (xy 46.203464 -108.162886) (xy 46.24224 -108.257797) (xy 46.273544 -108.355428)
			(xy 46.297188 -108.455191) (xy 46.31303 -108.556486) (xy 46.320975 -108.658705) (xy 46.321472 -108.709968)
			(xy 46.320975 -108.761231) (xy 46.31303 -108.86345) (xy 46.297188 -108.964745) (xy 46.273544 -109.064508)
			(xy 46.24224 -109.162139) (xy 46.203464 -109.25705) (xy 46.15745 -109.348672) (xy 46.104475 -109.436452)
			(xy 46.044856 -109.519862) (xy 45.978953 -109.598402) (xy 45.907162 -109.671599) (xy 45.829915 -109.739013)
			(xy 45.747676 -109.800237) (xy 45.66094 -109.854905) (xy 45.570228 -109.902687) (xy 45.476086 -109.943296)
			(xy 45.379081 -109.976487) (xy 45.279795 -110.002062) (xy 45.178826 -110.019865) (xy 45.076781 -110.029791)
			(xy 44.974274 -110.031779) (xy 44.87192 -110.025818) (xy 44.770337 -110.011942) (xy 44.670134 -109.990237)
			(xy 44.571914 -109.960832) (xy 44.476269 -109.923904) (xy 44.383773 -109.879676) (xy 44.294982 -109.828412)
			(xy 44.210431 -109.770423) (xy 44.130628 -109.706055) (xy 44.056052 -109.635697) (xy 43.987154 -109.559771)
			(xy 43.924346 -109.478735) (xy 43.868006 -109.393075) (xy 43.818474 -109.303307) (xy 43.776048 -109.209971)
			(xy 43.740982 -109.113627) (xy 43.713487 -109.014856) (xy 43.693729 -108.914251) (xy 43.681826 -108.812418)
			(xy 43.677851 -108.709968) (xy 18.886816 -108.709968) (xy 18.875303 -108.749178) (xy 18.843815 -108.82783)
			(xy 18.804993 -108.903133) (xy 18.75919 -108.974405) (xy 18.706819 -109.041001) (xy 18.648354 -109.102316)
			(xy 18.584326 -109.157797) (xy 18.515314 -109.20694) (xy 18.441944 -109.2493) (xy 18.364879 -109.284495)
			(xy 18.284817 -109.312204) (xy 18.202484 -109.332178) (xy 18.118625 -109.344235) (xy 18.034 -109.348267)
			(xy 17.949375 -109.344235) (xy 17.865516 -109.332178) (xy 17.783183 -109.312204) (xy 17.703121 -109.284495)
			(xy 17.626056 -109.2493) (xy 17.552686 -109.20694) (xy 17.483674 -109.157797) (xy 17.419646 -109.102316)
			(xy 17.361181 -109.041001) (xy 17.30881 -108.974405) (xy 17.263007 -108.903133) (xy 17.224185 -108.82783)
			(xy 17.192697 -108.749178) (xy 17.168829 -108.667888) (xy 17.152795 -108.584698) (xy 17.144742 -108.500361)
			(xy 0.509016 -108.500361) (xy 0.509016 -110.709964) (xy 41.677855 -110.709964) (xy 41.68183 -110.607514)
			(xy 41.693733 -110.505681) (xy 41.713491 -110.405076) (xy 41.740986 -110.306305) (xy 41.776052 -110.209961)
			(xy 41.818478 -110.116625) (xy 41.86801 -110.026857) (xy 41.92435 -109.941197) (xy 41.987158 -109.860161)
			(xy 42.056056 -109.784235) (xy 42.130632 -109.713877) (xy 42.210435 -109.649509) (xy 42.294986 -109.59152)
			(xy 42.383777 -109.540256) (xy 42.476273 -109.496028) (xy 42.571918 -109.4591) (xy 42.670138 -109.429695)
			(xy 42.770341 -109.40799) (xy 42.871924 -109.394114) (xy 42.974278 -109.388153) (xy 43.076785 -109.390141)
			(xy 43.17883 -109.400067) (xy 43.279799 -109.41787) (xy 43.379085 -109.443445) (xy 43.47609 -109.476636)
			(xy 43.570232 -109.517245) (xy 43.660944 -109.565027) (xy 43.74768 -109.619695) (xy 43.829919 -109.680919)
			(xy 43.907166 -109.748333) (xy 43.978957 -109.82153) (xy 44.04486 -109.90007) (xy 44.104479 -109.98348)
			(xy 44.157454 -110.07126) (xy 44.203468 -110.162882) (xy 44.242244 -110.257793) (xy 44.273548 -110.355424)
			(xy 44.297192 -110.455187) (xy 44.313034 -110.556482) (xy 44.320979 -110.658701) (xy 44.321476 -110.709964)
			(xy 44.320979 -110.761227) (xy 44.313034 -110.863446) (xy 44.297192 -110.964741) (xy 44.273548 -111.064504)
			(xy 44.242244 -111.162135) (xy 44.203468 -111.257046) (xy 44.157454 -111.348668) (xy 44.104479 -111.436448)
			(xy 44.04486 -111.519858) (xy 43.978957 -111.598398) (xy 43.907166 -111.671595) (xy 43.829919 -111.739009)
			(xy 43.74768 -111.800233) (xy 43.660944 -111.854901) (xy 43.570232 -111.902683) (xy 43.47609 -111.943292)
			(xy 43.379085 -111.976483) (xy 43.279799 -112.002058) (xy 43.17883 -112.019861) (xy 43.076785 -112.029787)
			(xy 42.974278 -112.031775) (xy 42.871924 -112.025814) (xy 42.770341 -112.011938) (xy 42.670138 -111.990233)
			(xy 42.571918 -111.960828) (xy 42.476273 -111.9239) (xy 42.383777 -111.879672) (xy 42.294986 -111.828408)
			(xy 42.210435 -111.770419) (xy 42.130632 -111.706051) (xy 42.056056 -111.635693) (xy 41.987158 -111.559767)
			(xy 41.92435 -111.478731) (xy 41.86801 -111.393071) (xy 41.818478 -111.303303) (xy 41.776052 -111.209967)
			(xy 41.740986 -111.113623) (xy 41.713491 -111.014852) (xy 41.693733 -110.914247) (xy 41.68183 -110.812414)
			(xy 41.677855 -110.709964) (xy 0.509016 -110.709964) (xy 0.509016 -112.70996) (xy 7.377949 -112.70996)
			(xy 7.381924 -112.60751) (xy 7.393827 -112.505677) (xy 7.413585 -112.405072) (xy 7.44108 -112.306301)
			(xy 7.476146 -112.209957) (xy 7.518572 -112.116621) (xy 7.568104 -112.026853) (xy 7.624444 -111.941193)
			(xy 7.687252 -111.860157) (xy 7.75615 -111.784231) (xy 7.830726 -111.713873) (xy 7.910529 -111.649505)
			(xy 7.99508 -111.591516) (xy 8.083871 -111.540252) (xy 8.176367 -111.496024) (xy 8.272012 -111.459096)
			(xy 8.370232 -111.429691) (xy 8.470435 -111.407986) (xy 8.572018 -111.39411) (xy 8.674372 -111.388149)
			(xy 8.776879 -111.390137) (xy 8.878924 -111.400063) (xy 8.979893 -111.417866) (xy 9.079179 -111.443441)
			(xy 9.176184 -111.476632) (xy 9.270326 -111.517241) (xy 9.361038 -111.565023) (xy 9.447774 -111.619691)
			(xy 9.530013 -111.680915) (xy 9.60726 -111.748329) (xy 9.679051 -111.821526) (xy 9.744954 -111.900066)
			(xy 9.804573 -111.983476) (xy 9.857548 -112.071256) (xy 9.903562 -112.162878) (xy 9.942338 -112.257789)
			(xy 9.973642 -112.35542) (xy 9.997286 -112.455183) (xy 10.013128 -112.556478) (xy 10.021073 -112.658697)
			(xy 10.02139 -112.691361) (xy 17.017742 -112.691361) (xy 17.017742 -112.606639) (xy 17.025795 -112.522302)
			(xy 17.041829 -112.439112) (xy 17.065697 -112.357822) (xy 17.097185 -112.27917) (xy 17.136007 -112.203867)
			(xy 17.18181 -112.132595) (xy 17.234181 -112.065999) (xy 17.292646 -112.004684) (xy 17.356674 -111.949203)
			(xy 17.425686 -111.90006) (xy 17.499056 -111.8577) (xy 17.576121 -111.822505) (xy 17.656183 -111.794796)
			(xy 17.738516 -111.774822) (xy 17.822375 -111.762765) (xy 17.907 -111.758734) (xy 17.991625 -111.762765)
			(xy 18.075484 -111.774822) (xy 18.157817 -111.794796) (xy 18.237879 -111.822505) (xy 18.314944 -111.8577)
			(xy 18.388314 -111.90006) (xy 18.457326 -111.949203) (xy 18.521354 -112.004684) (xy 18.579819 -112.065999)
			(xy 18.63219 -112.132595) (xy 18.677993 -112.203867) (xy 18.716815 -112.27917) (xy 18.748303 -112.357822)
			(xy 18.772171 -112.439112) (xy 18.788205 -112.522302) (xy 18.796258 -112.606639) (xy 18.796762 -112.649)
			(xy 18.796258 -112.691361) (xy 18.788205 -112.775698) (xy 18.772171 -112.858888) (xy 18.748303 -112.940178)
			(xy 18.716815 -113.01883) (xy 18.677993 -113.094133) (xy 18.63219 -113.165405) (xy 18.579819 -113.232001)
			(xy 18.521354 -113.293316) (xy 18.457326 -113.348797) (xy 18.388314 -113.39794) (xy 18.314944 -113.4403)
			(xy 18.237879 -113.475495) (xy 18.157817 -113.503204) (xy 18.075484 -113.523178) (xy 17.991625 -113.535235)
			(xy 17.907 -113.539267) (xy 17.822375 -113.535235) (xy 17.738516 -113.523178) (xy 17.656183 -113.503204)
			(xy 17.576121 -113.475495) (xy 17.499056 -113.4403) (xy 17.425686 -113.39794) (xy 17.356674 -113.348797)
			(xy 17.292646 -113.293316) (xy 17.234181 -113.232001) (xy 17.18181 -113.165405) (xy 17.136007 -113.094133)
			(xy 17.097185 -113.01883) (xy 17.065697 -112.940178) (xy 17.041829 -112.858888) (xy 17.025795 -112.775698)
			(xy 17.017742 -112.691361) (xy 10.02139 -112.691361) (xy 10.02157 -112.70996) (xy 10.021073 -112.761223)
			(xy 10.013128 -112.863442) (xy 9.997286 -112.964737) (xy 9.973642 -113.0645) (xy 9.942338 -113.162131)
			(xy 9.903562 -113.257042) (xy 9.857548 -113.348664) (xy 9.804573 -113.436444) (xy 9.744954 -113.519854)
			(xy 9.679051 -113.598394) (xy 9.60726 -113.671591) (xy 9.530013 -113.739005) (xy 9.447774 -113.800229)
			(xy 9.361038 -113.854897) (xy 9.270326 -113.902679) (xy 9.176184 -113.943288) (xy 9.079179 -113.976479)
			(xy 8.979893 -114.002054) (xy 8.878924 -114.019857) (xy 8.776879 -114.029783) (xy 8.674372 -114.031771)
			(xy 8.572018 -114.02581) (xy 8.470435 -114.011934) (xy 8.370232 -113.990229) (xy 8.272012 -113.960824)
			(xy 8.176367 -113.923896) (xy 8.083871 -113.879668) (xy 7.99508 -113.828404) (xy 7.910529 -113.770415)
			(xy 7.830726 -113.706047) (xy 7.75615 -113.635689) (xy 7.687252 -113.559763) (xy 7.624444 -113.478727)
			(xy 7.568104 -113.393067) (xy 7.518572 -113.303299) (xy 7.476146 -113.209963) (xy 7.44108 -113.113619)
			(xy 7.413585 -113.014848) (xy 7.393827 -112.914243) (xy 7.381924 -112.81241) (xy 7.377949 -112.70996)
			(xy 0.509016 -112.70996) (xy 0.509016 -114.709956) (xy 5.377953 -114.709956) (xy 5.381928 -114.607506)
			(xy 5.393831 -114.505673) (xy 5.413589 -114.405068) (xy 5.441084 -114.306297) (xy 5.47615 -114.209953)
			(xy 5.518576 -114.116617) (xy 5.568108 -114.026849) (xy 5.624448 -113.941189) (xy 5.687256 -113.860153)
			(xy 5.756154 -113.784227) (xy 5.83073 -113.713869) (xy 5.910533 -113.649501) (xy 5.995084 -113.591512)
			(xy 6.083875 -113.540248) (xy 6.176371 -113.49602) (xy 6.272016 -113.459092) (xy 6.370236 -113.429687)
			(xy 6.470439 -113.407982) (xy 6.572022 -113.394106) (xy 6.674376 -113.388145) (xy 6.776883 -113.390133)
			(xy 6.878928 -113.400059) (xy 6.979897 -113.417862) (xy 7.079183 -113.443437) (xy 7.176188 -113.476628)
			(xy 7.27033 -113.517237) (xy 7.361042 -113.565019) (xy 7.447778 -113.619687) (xy 7.530017 -113.680911)
			(xy 7.607264 -113.748325) (xy 7.679055 -113.821522) (xy 7.744958 -113.900062) (xy 7.804577 -113.983472)
			(xy 7.857552 -114.071252) (xy 7.903566 -114.162874) (xy 7.942342 -114.257785) (xy 7.973646 -114.355416)
			(xy 7.99729 -114.455179) (xy 8.013132 -114.556474) (xy 8.021077 -114.658693) (xy 8.021574 -114.709956)
			(xy 8.021077 -114.761219) (xy 8.013132 -114.863438) (xy 7.99729 -114.964733) (xy 7.973646 -115.064496)
			(xy 7.942342 -115.162127) (xy 7.903566 -115.257038) (xy 7.857552 -115.34866) (xy 7.804577 -115.43644)
			(xy 7.744958 -115.51985) (xy 7.679055 -115.59839) (xy 7.607264 -115.671587) (xy 7.530017 -115.739001)
			(xy 7.447778 -115.800225) (xy 7.361042 -115.854893) (xy 7.27033 -115.902675) (xy 7.176188 -115.943284)
			(xy 7.079183 -115.976475) (xy 6.979897 -116.00205) (xy 6.878928 -116.019853) (xy 6.776883 -116.029779)
			(xy 6.674376 -116.031767) (xy 6.572022 -116.025806) (xy 6.470439 -116.01193) (xy 6.370236 -115.990225)
			(xy 6.272016 -115.96082) (xy 6.176371 -115.923892) (xy 6.083875 -115.879664) (xy 5.995084 -115.8284)
			(xy 5.910533 -115.770411) (xy 5.83073 -115.706043) (xy 5.756154 -115.635685) (xy 5.687256 -115.559759)
			(xy 5.624448 -115.478723) (xy 5.568108 -115.393063) (xy 5.518576 -115.303295) (xy 5.47615 -115.209959)
			(xy 5.441084 -115.113615) (xy 5.413589 -115.014844) (xy 5.393831 -114.914239) (xy 5.381928 -114.812406)
			(xy 5.377953 -114.709956) (xy 0.509016 -114.709956) (xy 0.509016 -116.84) (xy 17.220692 -116.84)
			(xy 17.221212 -116.796905) (xy 17.229531 -116.711118) (xy 17.246109 -116.626538) (xy 17.270792 -116.543958)
			(xy 17.303347 -116.464153) (xy 17.34347 -116.387872) (xy 17.390783 -116.31583) (xy 17.444844 -116.248703)
			(xy 17.505145 -116.18712) (xy 17.571121 -116.13166) (xy 17.642152 -116.082842) (xy 17.717573 -116.041124)
			(xy 17.796675 -116.006898) (xy 17.878718 -115.980484) (xy 17.920716 -115.970812) (xy 17.928895 -115.968685)
			(xy 17.943298 -115.959859) (xy 17.94891 -115.95354) (xy 17.976985 -115.920571) (xy 18.038611 -115.859729)
			(xy 18.105864 -115.80517) (xy 18.178105 -115.757411) (xy 18.254649 -115.716906) (xy 18.33477 -115.684039)
			(xy 18.417708 -115.659121) (xy 18.502676 -115.642389) (xy 18.58887 -115.634001) (xy 18.63217 -115.6335)
			(xy 18.673249 -115.633989) (xy 18.755057 -115.641567) (xy 18.835817 -115.656661) (xy 18.91484 -115.679142)
			(xy 18.991451 -115.708819) (xy 19.064997 -115.745439) (xy 19.13485 -115.788688) (xy 19.200415 -115.838198)
			(xy 19.261132 -115.893547) (xy 19.316483 -115.954262) (xy 19.365995 -116.019825) (xy 19.409247 -116.089677)
			(xy 19.445868 -116.163222) (xy 19.475548 -116.239832) (xy 19.498032 -116.318854) (xy 19.513129 -116.399613)
			(xy 19.52071 -116.481421) (xy 19.52117 -116.5225) (xy 19.52064 -116.565503) (xy 19.512324 -116.651107)
			(xy 19.495782 -116.735507) (xy 19.471166 -116.817916) (xy 19.438707 -116.897562) (xy 19.398708 -116.973701)
			(xy 19.351544 -117.045622) (xy 19.297654 -117.112652) (xy 19.237544 -117.174165) (xy 19.171774 -117.229586)
			(xy 19.10096 -117.278396) (xy 19.025763 -117.32014) (xy 18.946887 -117.354427) (xy 18.865068 -117.380937)
			(xy 18.823178 -117.390672) (xy 18.814999 -117.392801) (xy 18.800597 -117.401626) (xy 18.794984 -117.407944)
			(xy 18.766867 -117.441037) (xy 18.705173 -117.502157) (xy 18.637816 -117.556972) (xy 18.5699 -117.602)
			(xy 30.097988 -117.602) (xy 30.102018 -117.517399) (xy 30.114071 -117.433564) (xy 30.134039 -117.351255)
			(xy 30.161741 -117.271216) (xy 30.196925 -117.194173) (xy 30.239274 -117.120823) (xy 30.288403 -117.051831)
			(xy 30.343868 -116.987821) (xy 30.405166 -116.929373) (xy 30.471742 -116.877017) (xy 30.542994 -116.831227)
			(xy 30.618275 -116.792416) (xy 30.696905 -116.760937) (xy 30.778172 -116.737076) (xy 30.861338 -116.721047)
			(xy 30.945652 -116.712996) (xy 30.988 -116.712492) (xy 31.028194 -116.712951) (xy 31.108256 -116.720185)
			(xy 31.18734 -116.734611) (xy 31.264799 -116.756112) (xy 31.340003 -116.784513) (xy 31.376366 -116.801646)
			(xy 31.385389 -116.805561) (xy 31.404998 -116.806883) (xy 31.423678 -116.800774) (xy 31.431484 -116.794788)
			(xy 31.465894 -116.766349) (xy 31.53944 -116.715744) (xy 31.617688 -116.672766) (xy 31.69985 -116.637846)
			(xy 31.785097 -116.611337) (xy 31.872573 -116.593505) (xy 31.961395 -116.584531) (xy 32.006032 -116.583968)
			(xy 32.048356 -116.584476) (xy 32.132621 -116.592522) (xy 32.21574 -116.608542) (xy 32.296959 -116.63239)
			(xy 32.375544 -116.663851) (xy 32.450782 -116.702639) (xy 32.521993 -116.748404) (xy 32.588531 -116.80073)
			(xy 32.649794 -116.859144) (xy 32.705226 -116.923117) (xy 32.754327 -116.99207) (xy 32.796651 -117.065377)
			(xy 32.831815 -117.142376) (xy 32.859501 -117.222369) (xy 32.879458 -117.304631) (xy 32.891504 -117.388418)
			(xy 32.895532 -117.47297) (xy 32.891504 -117.557522) (xy 32.879458 -117.641309) (xy 32.859501 -117.723571)
			(xy 32.831815 -117.803564) (xy 32.796651 -117.880563) (xy 32.754327 -117.95387) (xy 32.705226 -118.022823)
			(xy 32.649794 -118.086796) (xy 32.588531 -118.14521) (xy 32.521993 -118.197536) (xy 32.450782 -118.243301)
			(xy 32.375544 -118.282089) (xy 32.296959 -118.31355) (xy 32.21574 -118.337398) (xy 32.132621 -118.353418)
			(xy 32.048356 -118.361464) (xy 32.006032 -118.361968) (xy 31.965943 -118.361526) (xy 31.886093 -118.354303)
			(xy 31.807218 -118.339911) (xy 31.729961 -118.318469) (xy 31.654952 -118.29015) (xy 31.618682 -118.273068)
			(xy 31.609682 -118.269171) (xy 31.590126 -118.267914) (xy 31.571544 -118.274137) (xy 31.563818 -118.28018)
			(xy 31.529361 -118.308724) (xy 31.455669 -118.359483) (xy 31.377253 -118.402587) (xy 31.294905 -118.437598)
			(xy 31.209457 -118.464163) (xy 31.121774 -118.482014) (xy 31.032741 -118.490969) (xy 30.988 -118.491508)
			(xy 30.945652 -118.491004) (xy 30.861338 -118.482953) (xy 30.778172 -118.466924) (xy 30.696905 -118.443063)
			(xy 30.618275 -118.411584) (xy 30.542994 -118.372773) (xy 30.471742 -118.326983) (xy 30.405166 -118.274627)
			(xy 30.343868 -118.216179) (xy 30.288403 -118.152169) (xy 30.239274 -118.083177) (xy 30.196925 -118.009827)
			(xy 30.161741 -117.932784) (xy 30.134039 -117.852745) (xy 30.114071 -117.770436) (xy 30.102018 -117.686601)
			(xy 30.097988 -117.602) (xy 18.5699 -117.602) (xy 18.565435 -117.60496) (xy 18.488722 -117.645664)
			(xy 18.408406 -117.678696) (xy 18.325253 -117.703742) (xy 18.240054 -117.720563) (xy 18.153622 -117.728999)
			(xy 18.1102 -117.729508) (xy 18.069098 -117.729033) (xy 17.987243 -117.721448) (xy 17.906438 -117.706343)
			(xy 17.827371 -117.683847) (xy 17.750717 -117.654151) (xy 17.67713 -117.617509) (xy 17.607238 -117.574234)
			(xy 17.541637 -117.524694) (xy 17.480887 -117.469313) (xy 17.425506 -117.408563) (xy 17.375966 -117.342962)
			(xy 17.332691 -117.27307) (xy 17.296049 -117.199483) (xy 17.266353 -117.122829) (xy 17.243857 -117.043762)
			(xy 17.228752 -116.962957) (xy 17.221167 -116.881102) (xy 17.220692 -116.84) (xy 0.509016 -116.84)
			(xy 0.509016 -120.609868) (xy 42.741353 -120.609868) (xy 42.745331 -120.509875) (xy 42.757241 -120.410515)
			(xy 42.777008 -120.312414) (xy 42.804507 -120.216195) (xy 42.839563 -120.122464) (xy 42.881955 -120.031815)
			(xy 42.931416 -119.944821) (xy 42.987632 -119.862031) (xy 43.050248 -119.783969) (xy 43.118867 -119.711129)
			(xy 43.193058 -119.643971) (xy 43.272349 -119.582919) (xy 43.35624 -119.528361) (xy 43.444201 -119.48064)
			(xy 43.535675 -119.440058) (xy 43.630084 -119.406872) (xy 43.726831 -119.381292) (xy 43.825305 -119.363479)
			(xy 43.924883 -119.353547) (xy 44.024935 -119.351557) (xy 44.124829 -119.357523) (xy 44.223933 -119.371407)
			(xy 44.321621 -119.39312) (xy 44.417275 -119.422526) (xy 44.51029 -119.459439) (xy 44.600078 -119.503625)
			(xy 44.686072 -119.554806) (xy 44.767728 -119.612656) (xy 44.844529 -119.676812) (xy 44.915991 -119.746866)
			(xy 44.981661 -119.822377) (xy 45.041123 -119.902867) (xy 45.094003 -119.987826) (xy 45.139966 -120.076718)
			(xy 45.178721 -120.168981) (xy 45.210023 -120.264031) (xy 45.233675 -120.361268) (xy 45.249526 -120.460077)
			(xy 45.257476 -120.559832) (xy 45.257974 -120.609868) (xy 45.257476 -120.659904) (xy 45.249526 -120.759659)
			(xy 45.233675 -120.858468) (xy 45.210023 -120.955705) (xy 45.178721 -121.050755) (xy 45.139966 -121.143018)
			(xy 45.094003 -121.23191) (xy 45.041123 -121.316869) (xy 44.981661 -121.397359) (xy 44.915991 -121.47287)
			(xy 44.844529 -121.542924) (xy 44.767728 -121.60708) (xy 44.686072 -121.66493) (xy 44.600078 -121.716111)
			(xy 44.51029 -121.760297) (xy 44.417275 -121.79721) (xy 44.321621 -121.826616) (xy 44.223933 -121.848329)
			(xy 44.124829 -121.862213) (xy 44.024935 -121.868179) (xy 43.924883 -121.866189) (xy 43.825305 -121.856257)
			(xy 43.726831 -121.838444) (xy 43.630084 -121.812864) (xy 43.535675 -121.779678) (xy 43.444201 -121.739096)
			(xy 43.35624 -121.691375) (xy 43.272349 -121.636817) (xy 43.193058 -121.575765) (xy 43.118867 -121.508607)
			(xy 43.050248 -121.435767) (xy 42.987632 -121.357705) (xy 42.931416 -121.274915) (xy 42.881955 -121.187921)
			(xy 42.839563 -121.097272) (xy 42.804507 -121.003541) (xy 42.777008 -120.907322) (xy 42.757241 -120.809221)
			(xy 42.745331 -120.709861) (xy 42.741353 -120.609868) (xy 0.509016 -120.609868) (xy 0.509016 -193.082361)
			(xy 4.952742 -193.082361) (xy 4.952742 -192.997639) (xy 4.960795 -192.913302) (xy 4.976829 -192.830112)
			(xy 5.000697 -192.748822) (xy 5.032185 -192.67017) (xy 5.071007 -192.594867) (xy 5.11681 -192.523595)
			(xy 5.169181 -192.456999) (xy 5.227646 -192.395684) (xy 5.291674 -192.340203) (xy 5.360686 -192.29106)
			(xy 5.434056 -192.2487) (xy 5.511121 -192.213505) (xy 5.591183 -192.185796) (xy 5.673516 -192.165822)
			(xy 5.757375 -192.153765) (xy 5.842 -192.149734) (xy 5.926625 -192.153765) (xy 6.010484 -192.165822)
			(xy 6.092817 -192.185796) (xy 6.172879 -192.213505) (xy 6.249944 -192.2487) (xy 6.323314 -192.29106)
			(xy 6.392326 -192.340203) (xy 6.456354 -192.395684) (xy 6.514819 -192.456999) (xy 6.56719 -192.523595)
			(xy 6.612993 -192.594867) (xy 6.651815 -192.67017) (xy 6.683303 -192.748822) (xy 6.707171 -192.830112)
			(xy 6.723205 -192.913302) (xy 6.731258 -192.997639) (xy 6.731762 -193.04) (xy 6.731258 -193.082361)
			(xy 6.723205 -193.166698) (xy 6.707171 -193.249888) (xy 6.683303 -193.331178) (xy 6.651815 -193.40983)
			(xy 6.612993 -193.485133) (xy 6.56719 -193.556405) (xy 6.514819 -193.623001) (xy 6.456354 -193.684316)
			(xy 6.392326 -193.739797) (xy 6.323314 -193.78894) (xy 6.249944 -193.8313) (xy 6.172879 -193.866495)
			(xy 6.092817 -193.894204) (xy 6.010484 -193.914178) (xy 5.926625 -193.926235) (xy 5.842 -193.930267)
			(xy 5.757375 -193.926235) (xy 5.673516 -193.914178) (xy 5.591183 -193.894204) (xy 5.511121 -193.866495)
			(xy 5.434056 -193.8313) (xy 5.360686 -193.78894) (xy 5.291674 -193.739797) (xy 5.227646 -193.684316)
			(xy 5.169181 -193.623001) (xy 5.11681 -193.556405) (xy 5.071007 -193.485133) (xy 5.032185 -193.40983)
			(xy 5.000697 -193.331178) (xy 4.976829 -193.249888) (xy 4.960795 -193.166698) (xy 4.952742 -193.082361)
			(xy 0.509016 -193.082361) (xy 0.509016 -195.1101) (xy 6.441451 -195.1101) (xy 6.445429 -195.010107)
			(xy 6.457339 -194.910747) (xy 6.477106 -194.812646) (xy 6.504605 -194.716427) (xy 6.539661 -194.622696)
			(xy 6.582053 -194.532047) (xy 6.631514 -194.445053) (xy 6.68773 -194.362263) (xy 6.750346 -194.284201)
			(xy 6.818965 -194.211361) (xy 6.893156 -194.144203) (xy 6.972447 -194.083151) (xy 7.056338 -194.028593)
			(xy 7.144299 -193.980872) (xy 7.235773 -193.94029) (xy 7.330182 -193.907104) (xy 7.426929 -193.881524)
			(xy 7.525403 -193.863711) (xy 7.624981 -193.853779) (xy 7.725033 -193.851789) (xy 7.824927 -193.857755)
			(xy 7.924031 -193.871639) (xy 8.021719 -193.893352) (xy 8.117373 -193.922758) (xy 8.210388 -193.959671)
			(xy 8.300176 -194.003857) (xy 8.38617 -194.055038) (xy 8.467826 -194.112888) (xy 8.544627 -194.177044)
			(xy 8.616089 -194.247098) (xy 8.681759 -194.322609) (xy 8.741221 -194.403099) (xy 8.794101 -194.488058)
			(xy 8.840064 -194.57695) (xy 8.878819 -194.669213) (xy 8.910121 -194.764263) (xy 8.933773 -194.8615)
			(xy 8.949624 -194.960309) (xy 8.957574 -195.060064) (xy 8.958072 -195.1101) (xy 8.957574 -195.160136)
			(xy 8.949624 -195.259891) (xy 8.933773 -195.3587) (xy 8.910121 -195.455937) (xy 8.878819 -195.550987)
			(xy 8.840064 -195.64325) (xy 8.794101 -195.732142) (xy 8.741221 -195.817101) (xy 8.681759 -195.897591)
			(xy 8.616089 -195.973102) (xy 8.544627 -196.043156) (xy 8.467826 -196.107312) (xy 8.38617 -196.165162)
			(xy 8.300176 -196.216343) (xy 8.210388 -196.260529) (xy 8.117373 -196.297442) (xy 8.021719 -196.326848)
			(xy 7.924031 -196.348561) (xy 7.824927 -196.362445) (xy 7.725033 -196.368411) (xy 7.624981 -196.366421)
			(xy 7.525403 -196.356489) (xy 7.426929 -196.338676) (xy 7.330182 -196.313096) (xy 7.235773 -196.27991)
			(xy 7.144299 -196.239328) (xy 7.056338 -196.191607) (xy 6.972447 -196.137049) (xy 6.893156 -196.075997)
			(xy 6.818965 -196.008839) (xy 6.750346 -195.935999) (xy 6.68773 -195.857937) (xy 6.631514 -195.775147)
			(xy 6.582053 -195.688153) (xy 6.539661 -195.597504) (xy 6.504605 -195.503773) (xy 6.477106 -195.407554)
			(xy 6.457339 -195.309453) (xy 6.445429 -195.210093) (xy 6.441451 -195.1101) (xy 0.509016 -195.1101)
			(xy 0.509016 -196.85) (xy 18.770092 -196.85) (xy 18.770517 -196.810159) (xy 18.777625 -196.730796)
			(xy 18.791803 -196.652386) (xy 18.812936 -196.575558) (xy 18.82648 -196.538088) (xy 18.82915 -196.530146)
			(xy 18.829679 -196.51341) (xy 18.827496 -196.505322) (xy 18.814897 -196.462741) (xy 18.797265 -196.375704)
			(xy 18.788408 -196.287342) (xy 18.787872 -196.24294) (xy 18.788376 -196.200616) (xy 18.796422 -196.11635)
			(xy 18.812442 -196.033231) (xy 18.83629 -195.952012) (xy 18.867751 -195.873427) (xy 18.906539 -195.798188)
			(xy 18.952303 -195.726977) (xy 19.00463 -195.660439) (xy 19.063044 -195.599176) (xy 19.127017 -195.543743)
			(xy 19.19597 -195.494642) (xy 19.269278 -195.452317) (xy 19.346277 -195.417153) (xy 19.42627 -195.389467)
			(xy 19.508532 -195.36951) (xy 19.592319 -195.357464) (xy 19.676872 -195.353436) (xy 19.761425 -195.357464)
			(xy 19.845212 -195.36951) (xy 19.927474 -195.389467) (xy 20.007467 -195.417153) (xy 20.084466 -195.452317)
			(xy 20.157774 -195.494642) (xy 20.226727 -195.543743) (xy 20.2907 -195.599176) (xy 20.349114 -195.660439)
			(xy 20.401441 -195.726977) (xy 20.447205 -195.798188) (xy 20.485993 -195.873427) (xy 20.517454 -195.952012)
			(xy 20.541302 -196.033231) (xy 20.557322 -196.11635) (xy 20.565368 -196.200616) (xy 20.565872 -196.24294)
			(xy 20.56543 -196.282547) (xy 20.558368 -196.361445) (xy 20.544321 -196.439403) (xy 20.5234 -196.515803)
			(xy 20.509992 -196.553074) (xy 20.507444 -196.561045) (xy 20.507049 -196.577762) (xy 20.50923 -196.58584)
			(xy 20.521931 -196.628706) (xy 20.539699 -196.716331) (xy 20.548593 -196.805295) (xy 20.549108 -196.85)
			(xy 20.548604 -196.892348) (xy 20.540553 -196.976662) (xy 20.524524 -197.059828) (xy 20.511555 -197.104)
			(xy 33.121092 -197.104) (xy 33.121603 -197.061427) (xy 33.129737 -196.976671) (xy 33.14593 -196.893079)
			(xy 33.170034 -196.811416) (xy 33.201829 -196.732429) (xy 33.241024 -196.656841) (xy 33.28726 -196.585342)
			(xy 33.340115 -196.518588) (xy 33.36925 -196.487542) (xy 33.37306 -196.48297) (xy 33.398215 -196.450706)
			(xy 33.453548 -196.390439) (xy 33.514184 -196.33551) (xy 33.57961 -196.286385) (xy 33.649272 -196.243477)
			(xy 33.722582 -196.207151) (xy 33.798919 -196.177713) (xy 33.877638 -196.155413) (xy 33.958072 -196.140439)
			(xy 34.039542 -196.132918) (xy 34.08045 -196.13245) (xy 34.12153 -196.132908) (xy 34.203341 -196.140485)
			(xy 34.284103 -196.155578) (xy 34.363128 -196.17806) (xy 34.439742 -196.207737) (xy 34.51329 -196.244358)
			(xy 34.583145 -196.287608) (xy 34.648711 -196.337121) (xy 34.709428 -196.392472) (xy 34.764779 -196.453189)
			(xy 34.814292 -196.518755) (xy 34.857542 -196.58861) (xy 34.894163 -196.662158) (xy 34.92384 -196.738772)
			(xy 34.946322 -196.817797) (xy 34.961415 -196.898559) (xy 34.968992 -196.98037) (xy 34.96945 -197.02145)
			(xy 34.968972 -197.063356) (xy 34.961085 -197.146796) (xy 34.945377 -197.229123) (xy 34.921987 -197.309606)
			(xy 34.891123 -197.387528) (xy 34.85306 -197.462198) (xy 34.808135 -197.532953) (xy 34.756748 -197.599164)
			(xy 34.728404 -197.630034) (xy 34.724848 -197.634352) (xy 34.699744 -197.667357) (xy 34.644308 -197.729035)
			(xy 34.583373 -197.785287) (xy 34.517468 -197.835625) (xy 34.447165 -197.879613) (xy 34.373075 -197.916868)
			(xy 34.295839 -197.947067) (xy 34.216129 -197.969949) (xy 34.134635 -197.985315) (xy 34.052065 -197.993031)
			(xy 34.0106 -197.993508) (xy 33.969498 -197.993033) (xy 33.887643 -197.985448) (xy 33.806838 -197.970343)
			(xy 33.727771 -197.947847) (xy 33.651117 -197.918151) (xy 33.57753 -197.881509) (xy 33.507638 -197.838234)
			(xy 33.442037 -197.788694) (xy 33.381287 -197.733313) (xy 33.325906 -197.672563) (xy 33.276366 -197.606962)
			(xy 33.233091 -197.53707) (xy 33.196449 -197.463483) (xy 33.166753 -197.386829) (xy 33.144257 -197.307762)
			(xy 33.129152 -197.226957) (xy 33.121567 -197.145102) (xy 33.121092 -197.104) (xy 20.511555 -197.104)
			(xy 20.500663 -197.141095) (xy 20.469184 -197.219725) (xy 20.430373 -197.295006) (xy 20.384583 -197.366258)
			(xy 20.332227 -197.432834) (xy 20.273779 -197.494132) (xy 20.209769 -197.549597) (xy 20.140777 -197.598726)
			(xy 20.067427 -197.641075) (xy 19.990384 -197.676259) (xy 19.910345 -197.703961) (xy 19.828036 -197.723929)
			(xy 19.744201 -197.735982) (xy 19.6596 -197.740013) (xy 19.574999 -197.735982) (xy 19.491164 -197.723929)
			(xy 19.408855 -197.703961) (xy 19.328816 -197.676259) (xy 19.251773 -197.641075) (xy 19.178423 -197.598726)
			(xy 19.109431 -197.549597) (xy 19.045421 -197.494132) (xy 18.986973 -197.432834) (xy 18.934617 -197.366258)
			(xy 18.888827 -197.295006) (xy 18.850016 -197.219725) (xy 18.818537 -197.141095) (xy 18.794676 -197.059828)
			(xy 18.778647 -196.976662) (xy 18.770596 -196.892348) (xy 18.770092 -196.85) (xy 0.509016 -196.85)
			(xy 0.509016 -201.010012) (xy 43.677851 -201.010012) (xy 43.681826 -200.907562) (xy 43.693729 -200.805729)
			(xy 43.713487 -200.705124) (xy 43.740982 -200.606353) (xy 43.776048 -200.510009) (xy 43.818474 -200.416673)
			(xy 43.868006 -200.326905) (xy 43.924346 -200.241245) (xy 43.987154 -200.160209) (xy 44.056052 -200.084283)
			(xy 44.130628 -200.013925) (xy 44.210431 -199.949557) (xy 44.294982 -199.891568) (xy 44.383773 -199.840304)
			(xy 44.476269 -199.796076) (xy 44.571914 -199.759148) (xy 44.670134 -199.729743) (xy 44.770337 -199.708038)
			(xy 44.87192 -199.694162) (xy 44.974274 -199.688201) (xy 45.076781 -199.690189) (xy 45.178826 -199.700115)
			(xy 45.279795 -199.717918) (xy 45.379081 -199.743493) (xy 45.476086 -199.776684) (xy 45.570228 -199.817293)
			(xy 45.66094 -199.865075) (xy 45.747676 -199.919743) (xy 45.829915 -199.980967) (xy 45.907162 -200.048381)
			(xy 45.978953 -200.121578) (xy 46.044856 -200.200118) (xy 46.104475 -200.283528) (xy 46.15745 -200.371308)
			(xy 46.203464 -200.46293) (xy 46.24224 -200.557841) (xy 46.273544 -200.655472) (xy 46.297188 -200.755235)
			(xy 46.31303 -200.85653) (xy 46.320975 -200.958749) (xy 46.321472 -201.010012) (xy 46.320975 -201.061275)
			(xy 46.31303 -201.163494) (xy 46.297188 -201.264789) (xy 46.273544 -201.364552) (xy 46.24224 -201.462183)
			(xy 46.203464 -201.557094) (xy 46.15745 -201.648716) (xy 46.104475 -201.736496) (xy 46.044856 -201.819906)
			(xy 45.978953 -201.898446) (xy 45.907162 -201.971643) (xy 45.829915 -202.039057) (xy 45.747676 -202.100281)
			(xy 45.66094 -202.154949) (xy 45.570228 -202.202731) (xy 45.476086 -202.24334) (xy 45.379081 -202.276531)
			(xy 45.279795 -202.302106) (xy 45.178826 -202.319909) (xy 45.076781 -202.329835) (xy 44.974274 -202.331823)
			(xy 44.87192 -202.325862) (xy 44.770337 -202.311986) (xy 44.670134 -202.290281) (xy 44.571914 -202.260876)
			(xy 44.476269 -202.223948) (xy 44.383773 -202.17972) (xy 44.294982 -202.128456) (xy 44.210431 -202.070467)
			(xy 44.130628 -202.006099) (xy 44.056052 -201.935741) (xy 43.987154 -201.859815) (xy 43.924346 -201.778779)
			(xy 43.868006 -201.693119) (xy 43.818474 -201.603351) (xy 43.776048 -201.510015) (xy 43.740982 -201.413671)
			(xy 43.713487 -201.3149) (xy 43.693729 -201.214295) (xy 43.681826 -201.112462) (xy 43.677851 -201.010012)
			(xy 0.509016 -201.010012) (xy 0.509016 -202.715311) (xy 14.350742 -202.715311) (xy 14.350742 -202.630589)
			(xy 14.358795 -202.546252) (xy 14.374829 -202.463062) (xy 14.398697 -202.381772) (xy 14.430185 -202.30312)
			(xy 14.469007 -202.227817) (xy 14.51481 -202.156545) (xy 14.567181 -202.089949) (xy 14.625646 -202.028634)
			(xy 14.689674 -201.973153) (xy 14.758686 -201.92401) (xy 14.832056 -201.88165) (xy 14.909121 -201.846455)
			(xy 14.989183 -201.818746) (xy 15.071516 -201.798772) (xy 15.155375 -201.786715) (xy 15.24 -201.782684)
			(xy 15.324625 -201.786715) (xy 15.408484 -201.798772) (xy 15.490817 -201.818746) (xy 15.570879 -201.846455)
			(xy 15.647944 -201.88165) (xy 15.721314 -201.92401) (xy 15.790326 -201.973153) (xy 15.854354 -202.028634)
			(xy 15.912819 -202.089949) (xy 15.96519 -202.156545) (xy 16.010993 -202.227817) (xy 16.049815 -202.30312)
			(xy 16.081303 -202.381772) (xy 16.105171 -202.463062) (xy 16.121205 -202.546252) (xy 16.129258 -202.630589)
			(xy 16.129762 -202.67295) (xy 16.129258 -202.715311) (xy 16.121205 -202.799648) (xy 16.105171 -202.882838)
			(xy 16.081303 -202.964128) (xy 16.062935 -203.010008) (xy 41.677855 -203.010008) (xy 41.68183 -202.907558)
			(xy 41.693733 -202.805725) (xy 41.713491 -202.70512) (xy 41.740986 -202.606349) (xy 41.776052 -202.510005)
			(xy 41.818478 -202.416669) (xy 41.86801 -202.326901) (xy 41.92435 -202.241241) (xy 41.987158 -202.160205)
			(xy 42.056056 -202.084279) (xy 42.130632 -202.013921) (xy 42.210435 -201.949553) (xy 42.294986 -201.891564)
			(xy 42.383777 -201.8403) (xy 42.476273 -201.796072) (xy 42.571918 -201.759144) (xy 42.670138 -201.729739)
			(xy 42.770341 -201.708034) (xy 42.871924 -201.694158) (xy 42.974278 -201.688197) (xy 43.076785 -201.690185)
			(xy 43.17883 -201.700111) (xy 43.279799 -201.717914) (xy 43.379085 -201.743489) (xy 43.47609 -201.77668)
			(xy 43.570232 -201.817289) (xy 43.660944 -201.865071) (xy 43.74768 -201.919739) (xy 43.829919 -201.980963)
			(xy 43.907166 -202.048377) (xy 43.978957 -202.121574) (xy 44.04486 -202.200114) (xy 44.104479 -202.283524)
			(xy 44.157454 -202.371304) (xy 44.203468 -202.462926) (xy 44.242244 -202.557837) (xy 44.273548 -202.655468)
			(xy 44.297192 -202.755231) (xy 44.313034 -202.856526) (xy 44.320979 -202.958745) (xy 44.321476 -203.010008)
			(xy 44.320979 -203.061271) (xy 44.313034 -203.16349) (xy 44.297192 -203.264785) (xy 44.273548 -203.364548)
			(xy 44.242244 -203.462179) (xy 44.203468 -203.55709) (xy 44.157454 -203.648712) (xy 44.104479 -203.736492)
			(xy 44.04486 -203.819902) (xy 43.978957 -203.898442) (xy 43.907166 -203.971639) (xy 43.829919 -204.039053)
			(xy 43.74768 -204.100277) (xy 43.660944 -204.154945) (xy 43.570232 -204.202727) (xy 43.47609 -204.243336)
			(xy 43.379085 -204.276527) (xy 43.279799 -204.302102) (xy 43.17883 -204.319905) (xy 43.076785 -204.329831)
			(xy 42.974278 -204.331819) (xy 42.871924 -204.325858) (xy 42.770341 -204.311982) (xy 42.670138 -204.290277)
			(xy 42.571918 -204.260872) (xy 42.476273 -204.223944) (xy 42.383777 -204.179716) (xy 42.294986 -204.128452)
			(xy 42.210435 -204.070463) (xy 42.130632 -204.006095) (xy 42.056056 -203.935737) (xy 41.987158 -203.859811)
			(xy 41.92435 -203.778775) (xy 41.86801 -203.693115) (xy 41.818478 -203.603347) (xy 41.776052 -203.510011)
			(xy 41.740986 -203.413667) (xy 41.713491 -203.314896) (xy 41.693733 -203.214291) (xy 41.68183 -203.112458)
			(xy 41.677855 -203.010008) (xy 16.062935 -203.010008) (xy 16.049815 -203.04278) (xy 16.010993 -203.118083)
			(xy 15.96519 -203.189355) (xy 15.912819 -203.255951) (xy 15.854354 -203.317266) (xy 15.790326 -203.372747)
			(xy 15.721314 -203.42189) (xy 15.647944 -203.46425) (xy 15.570879 -203.499445) (xy 15.490817 -203.527154)
			(xy 15.408484 -203.547128) (xy 15.324625 -203.559185) (xy 15.24 -203.563217) (xy 15.155375 -203.559185)
			(xy 15.071516 -203.547128) (xy 14.989183 -203.527154) (xy 14.909121 -203.499445) (xy 14.832056 -203.46425)
			(xy 14.758686 -203.42189) (xy 14.689674 -203.372747) (xy 14.625646 -203.317266) (xy 14.567181 -203.255951)
			(xy 14.51481 -203.189355) (xy 14.469007 -203.118083) (xy 14.430185 -203.04278) (xy 14.398697 -202.964128)
			(xy 14.374829 -202.882838) (xy 14.358795 -202.799648) (xy 14.350742 -202.715311) (xy 0.509016 -202.715311)
			(xy 0.509016 -205.010004) (xy 7.377949 -205.010004) (xy 7.381924 -204.907554) (xy 7.393827 -204.805721)
			(xy 7.413585 -204.705116) (xy 7.44108 -204.606345) (xy 7.476146 -204.510001) (xy 7.518572 -204.416665)
			(xy 7.568104 -204.326897) (xy 7.624444 -204.241237) (xy 7.687252 -204.160201) (xy 7.75615 -204.084275)
			(xy 7.830726 -204.013917) (xy 7.910529 -203.949549) (xy 7.99508 -203.89156) (xy 8.083871 -203.840296)
			(xy 8.176367 -203.796068) (xy 8.272012 -203.75914) (xy 8.370232 -203.729735) (xy 8.470435 -203.70803)
			(xy 8.572018 -203.694154) (xy 8.674372 -203.688193) (xy 8.776879 -203.690181) (xy 8.878924 -203.700107)
			(xy 8.979893 -203.71791) (xy 9.079179 -203.743485) (xy 9.176184 -203.776676) (xy 9.270326 -203.817285)
			(xy 9.361038 -203.865067) (xy 9.447774 -203.919735) (xy 9.530013 -203.980959) (xy 9.60726 -204.048373)
			(xy 9.679051 -204.12157) (xy 9.744954 -204.20011) (xy 9.804573 -204.28352) (xy 9.857548 -204.3713)
			(xy 9.878131 -204.412285) (xy 16.382742 -204.412285) (xy 16.382742 -204.327563) (xy 16.390795 -204.243226)
			(xy 16.406829 -204.160036) (xy 16.430697 -204.078746) (xy 16.462185 -204.000094) (xy 16.501007 -203.924791)
			(xy 16.54681 -203.853519) (xy 16.599181 -203.786923) (xy 16.657646 -203.725608) (xy 16.721674 -203.670127)
			(xy 16.790686 -203.620984) (xy 16.864056 -203.578624) (xy 16.941121 -203.543429) (xy 17.021183 -203.51572)
			(xy 17.103516 -203.495746) (xy 17.187375 -203.483689) (xy 17.272 -203.479658) (xy 17.356625 -203.483689)
			(xy 17.440484 -203.495746) (xy 17.522817 -203.51572) (xy 17.602879 -203.543429) (xy 17.679944 -203.578624)
			(xy 17.753314 -203.620984) (xy 17.822326 -203.670127) (xy 17.886354 -203.725608) (xy 17.944819 -203.786923)
			(xy 17.99719 -203.853519) (xy 18.042993 -203.924791) (xy 18.081815 -204.000094) (xy 18.113303 -204.078746)
			(xy 18.137171 -204.160036) (xy 18.153205 -204.243226) (xy 18.161258 -204.327563) (xy 18.161762 -204.369924)
			(xy 18.161258 -204.412285) (xy 18.153205 -204.496622) (xy 18.137171 -204.579812) (xy 18.113303 -204.661102)
			(xy 18.081815 -204.739754) (xy 18.042993 -204.815057) (xy 17.99719 -204.886329) (xy 17.944819 -204.952925)
			(xy 17.886354 -205.01424) (xy 17.822326 -205.069721) (xy 17.753314 -205.118864) (xy 17.679944 -205.161224)
			(xy 17.602879 -205.196419) (xy 17.522817 -205.224128) (xy 17.440484 -205.244102) (xy 17.356625 -205.256159)
			(xy 17.272 -205.260191) (xy 17.187375 -205.256159) (xy 17.103516 -205.244102) (xy 17.021183 -205.224128)
			(xy 16.941121 -205.196419) (xy 16.864056 -205.161224) (xy 16.790686 -205.118864) (xy 16.721674 -205.069721)
			(xy 16.657646 -205.01424) (xy 16.599181 -204.952925) (xy 16.54681 -204.886329) (xy 16.501007 -204.815057)
			(xy 16.462185 -204.739754) (xy 16.430697 -204.661102) (xy 16.406829 -204.579812) (xy 16.390795 -204.496622)
			(xy 16.382742 -204.412285) (xy 9.878131 -204.412285) (xy 9.903562 -204.462922) (xy 9.942338 -204.557833)
			(xy 9.973642 -204.655464) (xy 9.997286 -204.755227) (xy 10.013128 -204.856522) (xy 10.021073 -204.958741)
			(xy 10.02157 -205.010004) (xy 10.021073 -205.061267) (xy 10.013128 -205.163486) (xy 9.997286 -205.264781)
			(xy 9.973642 -205.364544) (xy 9.942338 -205.462175) (xy 9.903562 -205.557086) (xy 9.857548 -205.648708)
			(xy 9.804573 -205.736488) (xy 9.744954 -205.819898) (xy 9.679051 -205.898438) (xy 9.60726 -205.971635)
			(xy 9.530013 -206.039049) (xy 9.447774 -206.100273) (xy 9.361038 -206.154941) (xy 9.270326 -206.202723)
			(xy 9.176184 -206.243332) (xy 9.079179 -206.276523) (xy 8.979893 -206.302098) (xy 8.878924 -206.319901)
			(xy 8.776879 -206.329827) (xy 8.674372 -206.331815) (xy 8.572018 -206.325854) (xy 8.470435 -206.311978)
			(xy 8.370232 -206.290273) (xy 8.272012 -206.260868) (xy 8.176367 -206.22394) (xy 8.083871 -206.179712)
			(xy 7.99508 -206.128448) (xy 7.910529 -206.070459) (xy 7.830726 -206.006091) (xy 7.75615 -205.935733)
			(xy 7.687252 -205.859807) (xy 7.624444 -205.778771) (xy 7.568104 -205.693111) (xy 7.518572 -205.603343)
			(xy 7.476146 -205.510007) (xy 7.44108 -205.413663) (xy 7.413585 -205.314892) (xy 7.393827 -205.214287)
			(xy 7.381924 -205.112454) (xy 7.377949 -205.010004) (xy 0.509016 -205.010004) (xy 0.509016 -207.01)
			(xy 5.377953 -207.01) (xy 5.381928 -206.90755) (xy 5.393831 -206.805717) (xy 5.413589 -206.705112)
			(xy 5.441084 -206.606341) (xy 5.47615 -206.509997) (xy 5.518576 -206.416661) (xy 5.568108 -206.326893)
			(xy 5.624448 -206.241233) (xy 5.687256 -206.160197) (xy 5.756154 -206.084271) (xy 5.83073 -206.013913)
			(xy 5.910533 -205.949545) (xy 5.995084 -205.891556) (xy 6.083875 -205.840292) (xy 6.176371 -205.796064)
			(xy 6.272016 -205.759136) (xy 6.370236 -205.729731) (xy 6.470439 -205.708026) (xy 6.572022 -205.69415)
			(xy 6.674376 -205.688189) (xy 6.776883 -205.690177) (xy 6.878928 -205.700103) (xy 6.979897 -205.717906)
			(xy 7.079183 -205.743481) (xy 7.176188 -205.776672) (xy 7.27033 -205.817281) (xy 7.361042 -205.865063)
			(xy 7.447778 -205.919731) (xy 7.530017 -205.980955) (xy 7.607264 -206.048369) (xy 7.679055 -206.121566)
			(xy 7.744958 -206.200106) (xy 7.804577 -206.283516) (xy 7.857552 -206.371296) (xy 7.903566 -206.462918)
			(xy 7.942342 -206.557829) (xy 7.973646 -206.65546) (xy 7.99729 -206.755223) (xy 8.013132 -206.856518)
			(xy 8.021077 -206.958737) (xy 8.021574 -207.01) (xy 8.021077 -207.061263) (xy 8.013132 -207.163482)
			(xy 7.99729 -207.264777) (xy 7.973646 -207.36454) (xy 7.942342 -207.462171) (xy 7.903566 -207.557082)
			(xy 7.857552 -207.648704) (xy 7.804577 -207.736484) (xy 7.744958 -207.819894) (xy 7.679055 -207.898434)
			(xy 7.607264 -207.971631) (xy 7.530017 -208.039045) (xy 7.447778 -208.100269) (xy 7.361042 -208.154937)
			(xy 7.27033 -208.202719) (xy 7.176188 -208.243328) (xy 7.079183 -208.276519) (xy 6.979897 -208.302094)
			(xy 6.878928 -208.319897) (xy 6.776883 -208.329823) (xy 6.674376 -208.331811) (xy 6.572022 -208.32585)
			(xy 6.470439 -208.311974) (xy 6.370236 -208.290269) (xy 6.272016 -208.260864) (xy 6.176371 -208.223936)
			(xy 6.083875 -208.179708) (xy 5.995084 -208.128444) (xy 5.910533 -208.070455) (xy 5.83073 -208.006087)
			(xy 5.756154 -207.935729) (xy 5.687256 -207.859803) (xy 5.624448 -207.778767) (xy 5.568108 -207.693107)
			(xy 5.518576 -207.603339) (xy 5.47615 -207.510003) (xy 5.441084 -207.413659) (xy 5.413589 -207.314888)
			(xy 5.393831 -207.214283) (xy 5.381928 -207.11245) (xy 5.377953 -207.01) (xy 0.509016 -207.01) (xy 0.509016 -209.169)
			(xy 18.668492 -209.169) (xy 18.668996 -209.126652) (xy 18.677047 -209.042338) (xy 18.693076 -208.959172)
			(xy 18.716937 -208.877905) (xy 18.748416 -208.799275) (xy 18.787227 -208.723994) (xy 18.833017 -208.652742)
			(xy 18.885373 -208.586166) (xy 18.943821 -208.524868) (xy 19.007831 -208.469403) (xy 19.076823 -208.420274)
			(xy 19.150173 -208.377925) (xy 19.227216 -208.342741) (xy 19.307255 -208.315039) (xy 19.389564 -208.295071)
			(xy 19.473399 -208.283018) (xy 19.558 -208.278988) (xy 19.642601 -208.283018) (xy 19.726436 -208.295071)
			(xy 19.808745 -208.315039) (xy 19.888784 -208.342741) (xy 19.965827 -208.377925) (xy 20.039177 -208.420274)
			(xy 20.108169 -208.469403) (xy 20.172179 -208.524868) (xy 20.230627 -208.586166) (xy 20.282983 -208.652742)
			(xy 20.328773 -208.723994) (xy 20.367584 -208.799275) (xy 20.399063 -208.877905) (xy 20.422924 -208.959172)
			(xy 20.438953 -209.042338) (xy 20.447004 -209.126652) (xy 20.447508 -209.169) (xy 20.446968 -209.213971)
			(xy 20.437959 -209.30346) (xy 20.419974 -209.391585) (xy 20.407122 -209.434684) (xy 20.40382 -209.445352)
			(xy 20.40636 -209.466434) (xy 20.456652 -209.550508) (xy 20.474178 -209.5627) (xy 20.4851 -209.564732)
			(xy 20.525354 -209.572796) (xy 20.604278 -209.595425) (xy 20.680781 -209.625228) (xy 20.754213 -209.661953)
			(xy 20.82395 -209.705287) (xy 20.889398 -209.75486) (xy 20.950001 -209.810252) (xy 21.005244 -209.870992)
			(xy 21.054656 -209.936562) (xy 21.097817 -210.006405) (xy 21.13436 -210.079928) (xy 21.163975 -210.156505)
			(xy 21.186409 -210.235484) (xy 21.201472 -210.316194) (xy 21.209036 -210.397948) (xy 21.209508 -210.439)
			(xy 21.209033 -210.480102) (xy 21.201448 -210.561957) (xy 21.187361 -210.637317) (xy 30.352742 -210.637317)
			(xy 30.352742 -210.552595) (xy 30.360795 -210.468258) (xy 30.376829 -210.385068) (xy 30.400697 -210.303778)
			(xy 30.432185 -210.225126) (xy 30.471007 -210.149823) (xy 30.51681 -210.078551) (xy 30.569181 -210.011955)
			(xy 30.627646 -209.95064) (xy 30.691674 -209.895159) (xy 30.760686 -209.846016) (xy 30.834056 -209.803656)
			(xy 30.911121 -209.768461) (xy 30.991183 -209.740752) (xy 31.073516 -209.720778) (xy 31.157375 -209.708721)
			(xy 31.242 -209.70469) (xy 31.326625 -209.708721) (xy 31.410484 -209.720778) (xy 31.492817 -209.740752)
			(xy 31.572879 -209.768461) (xy 31.649944 -209.803656) (xy 31.723314 -209.846016) (xy 31.792326 -209.895159)
			(xy 31.856354 -209.95064) (xy 31.914819 -210.011955) (xy 31.96719 -210.078551) (xy 32.012993 -210.149823)
			(xy 32.051815 -210.225126) (xy 32.083303 -210.303778) (xy 32.107171 -210.385068) (xy 32.123205 -210.468258)
			(xy 32.131258 -210.552595) (xy 32.131762 -210.594956) (xy 32.131258 -210.637317) (xy 32.123205 -210.721654)
			(xy 32.107171 -210.804844) (xy 32.083303 -210.886134) (xy 32.051815 -210.964786) (xy 32.012993 -211.040089)
			(xy 31.96719 -211.111361) (xy 31.914819 -211.177957) (xy 31.856354 -211.239272) (xy 31.792326 -211.294753)
			(xy 31.723314 -211.343896) (xy 31.649944 -211.386256) (xy 31.572879 -211.421451) (xy 31.492817 -211.44916)
			(xy 31.410484 -211.469134) (xy 31.326625 -211.481191) (xy 31.242 -211.485223) (xy 31.157375 -211.481191)
			(xy 31.073516 -211.469134) (xy 30.991183 -211.44916) (xy 30.911121 -211.421451) (xy 30.834056 -211.386256)
			(xy 30.760686 -211.343896) (xy 30.691674 -211.294753) (xy 30.627646 -211.239272) (xy 30.569181 -211.177957)
			(xy 30.51681 -211.111361) (xy 30.471007 -211.040089) (xy 30.432185 -210.964786) (xy 30.400697 -210.886134)
			(xy 30.376829 -210.804844) (xy 30.360795 -210.721654) (xy 30.352742 -210.637317) (xy 21.187361 -210.637317)
			(xy 21.186343 -210.642762) (xy 21.163847 -210.721829) (xy 21.134151 -210.798483) (xy 21.097509 -210.87207)
			(xy 21.054234 -210.941962) (xy 21.004694 -211.007563) (xy 20.949313 -211.068313) (xy 20.888563 -211.123694)
			(xy 20.822962 -211.173234) (xy 20.75307 -211.216509) (xy 20.679483 -211.253151) (xy 20.602829 -211.282847)
			(xy 20.523762 -211.305343) (xy 20.442957 -211.320448) (xy 20.361102 -211.328033) (xy 20.32 -211.328508)
			(xy 20.277374 -211.328032) (xy 20.19251 -211.319904) (xy 20.108813 -211.303692) (xy 20.027052 -211.279546)
			(xy 19.947976 -211.247687) (xy 19.872311 -211.208408) (xy 19.800752 -211.16207) (xy 19.767042 -211.135976)
			(xy 19.758192 -211.129547) (xy 19.736981 -211.124292) (xy 19.726148 -211.125816) (xy 19.685631 -211.132951)
			(xy 19.60371 -211.140583) (xy 19.562572 -211.141056) (xy 19.521492 -211.140598) (xy 19.439683 -211.133017)
			(xy 19.358923 -211.117921) (xy 19.279899 -211.095437) (xy 19.203288 -211.065757) (xy 19.129742 -211.029136)
			(xy 19.059888 -210.985884) (xy 18.994324 -210.936372) (xy 18.933607 -210.881022) (xy 18.878257 -210.820305)
			(xy 18.828745 -210.75474) (xy 18.785493 -210.684887) (xy 18.748872 -210.61134) (xy 18.719193 -210.534729)
			(xy 18.696709 -210.455706) (xy 18.681612 -210.374945) (xy 18.674032 -210.293136) (xy 18.673572 -210.252056)
			(xy 18.674149 -210.206906) (xy 18.6833 -210.117071) (xy 18.701515 -210.028627) (xy 18.728605 -209.942487)
			(xy 18.764291 -209.859537) (xy 18.808204 -209.780634) (xy 18.833592 -209.743294) (xy 18.839012 -209.734401)
			(xy 18.843033 -209.713991) (xy 18.83869 -209.693648) (xy 18.833084 -209.684874) (xy 18.810683 -209.652572)
			(xy 18.770969 -209.584728) (xy 18.737391 -209.513647) (xy 18.710212 -209.439881) (xy 18.689642 -209.364007)
			(xy 18.675842 -209.286614) (xy 18.668919 -209.208307) (xy 18.668492 -209.169) (xy 0.509016 -209.169)
			(xy 0.509016 -212.909912) (xy 42.741353 -212.909912) (xy 42.745331 -212.809919) (xy 42.757241 -212.710559)
			(xy 42.777008 -212.612458) (xy 42.804507 -212.516239) (xy 42.839563 -212.422508) (xy 42.881955 -212.331859)
			(xy 42.931416 -212.244865) (xy 42.987632 -212.162075) (xy 43.050248 -212.084013) (xy 43.118867 -212.011173)
			(xy 43.193058 -211.944015) (xy 43.272349 -211.882963) (xy 43.35624 -211.828405) (xy 43.444201 -211.780684)
			(xy 43.535675 -211.740102) (xy 43.630084 -211.706916) (xy 43.726831 -211.681336) (xy 43.825305 -211.663523)
			(xy 43.924883 -211.653591) (xy 44.024935 -211.651601) (xy 44.124829 -211.657567) (xy 44.223933 -211.671451)
			(xy 44.321621 -211.693164) (xy 44.417275 -211.72257) (xy 44.51029 -211.759483) (xy 44.600078 -211.803669)
			(xy 44.686072 -211.85485) (xy 44.767728 -211.9127) (xy 44.844529 -211.976856) (xy 44.915991 -212.04691)
			(xy 44.981661 -212.122421) (xy 45.041123 -212.202911) (xy 45.094003 -212.28787) (xy 45.139966 -212.376762)
			(xy 45.178721 -212.469025) (xy 45.210023 -212.564075) (xy 45.233675 -212.661312) (xy 45.249526 -212.760121)
			(xy 45.257476 -212.859876) (xy 45.257974 -212.909912) (xy 45.257476 -212.959948) (xy 45.249526 -213.059703)
			(xy 45.233675 -213.158512) (xy 45.210023 -213.255749) (xy 45.178721 -213.350799) (xy 45.139966 -213.443062)
			(xy 45.094003 -213.531954) (xy 45.041123 -213.616913) (xy 44.981661 -213.697403) (xy 44.915991 -213.772914)
			(xy 44.844529 -213.842968) (xy 44.767728 -213.907124) (xy 44.686072 -213.964974) (xy 44.600078 -214.016155)
			(xy 44.51029 -214.060341) (xy 44.417275 -214.097254) (xy 44.321621 -214.12666) (xy 44.223933 -214.148373)
			(xy 44.124829 -214.162257) (xy 44.024935 -214.168223) (xy 43.924883 -214.166233) (xy 43.825305 -214.156301)
			(xy 43.726831 -214.138488) (xy 43.630084 -214.112908) (xy 43.535675 -214.079722) (xy 43.444201 -214.03914)
			(xy 43.35624 -213.991419) (xy 43.272349 -213.936861) (xy 43.193058 -213.875809) (xy 43.118867 -213.808651)
			(xy 43.050248 -213.735811) (xy 42.987632 -213.657749) (xy 42.931416 -213.574959) (xy 42.881955 -213.487965)
			(xy 42.839563 -213.397316) (xy 42.804507 -213.303585) (xy 42.777008 -213.207366) (xy 42.757241 -213.109265)
			(xy 42.745331 -213.009905) (xy 42.741353 -212.909912) (xy 0.509016 -212.909912) (xy 0.509016 -214.659661)
			(xy 20.446742 -214.659661) (xy 20.446742 -214.574939) (xy 20.454795 -214.490602) (xy 20.470829 -214.407412)
			(xy 20.494697 -214.326122) (xy 20.526185 -214.24747) (xy 20.565007 -214.172167) (xy 20.61081 -214.100895)
			(xy 20.663181 -214.034299) (xy 20.721646 -213.972984) (xy 20.785674 -213.917503) (xy 20.854686 -213.86836)
			(xy 20.928056 -213.826) (xy 21.005121 -213.790805) (xy 21.085183 -213.763096) (xy 21.167516 -213.743122)
			(xy 21.251375 -213.731065) (xy 21.336 -213.727034) (xy 21.420625 -213.731065) (xy 21.504484 -213.743122)
			(xy 21.586817 -213.763096) (xy 21.666879 -213.790805) (xy 21.743944 -213.826) (xy 21.817314 -213.86836)
			(xy 21.886326 -213.917503) (xy 21.950354 -213.972984) (xy 22.008819 -214.034299) (xy 22.06119 -214.100895)
			(xy 22.106993 -214.172167) (xy 22.145815 -214.24747) (xy 22.177303 -214.326122) (xy 22.201171 -214.407412)
			(xy 22.217205 -214.490602) (xy 22.225258 -214.574939) (xy 22.225762 -214.6173) (xy 22.225258 -214.659661)
			(xy 22.217205 -214.743998) (xy 22.201171 -214.827188) (xy 22.177303 -214.908478) (xy 22.145815 -214.98713)
			(xy 22.106993 -215.062433) (xy 22.06119 -215.133705) (xy 22.008819 -215.200301) (xy 21.950354 -215.261616)
			(xy 21.886326 -215.317097) (xy 21.817314 -215.36624) (xy 21.743944 -215.4086) (xy 21.666879 -215.443795)
			(xy 21.586817 -215.471504) (xy 21.504484 -215.491478) (xy 21.420625 -215.503535) (xy 21.336 -215.507567)
			(xy 21.251375 -215.503535) (xy 21.167516 -215.491478) (xy 21.085183 -215.471504) (xy 21.005121 -215.443795)
			(xy 20.928056 -215.4086) (xy 20.854686 -215.36624) (xy 20.785674 -215.317097) (xy 20.721646 -215.261616)
			(xy 20.663181 -215.200301) (xy 20.61081 -215.133705) (xy 20.565007 -215.062433) (xy 20.526185 -214.98713)
			(xy 20.494697 -214.908478) (xy 20.470829 -214.827188) (xy 20.454795 -214.743998) (xy 20.446742 -214.659661)
			(xy 0.509016 -214.659661) (xy 0.509016 -216.577361) (xy 18.287742 -216.577361) (xy 18.287742 -216.492639)
			(xy 18.295795 -216.408302) (xy 18.311829 -216.325112) (xy 18.335697 -216.243822) (xy 18.367185 -216.16517)
			(xy 18.406007 -216.089867) (xy 18.45181 -216.018595) (xy 18.504181 -215.951999) (xy 18.562646 -215.890684)
			(xy 18.626674 -215.835203) (xy 18.695686 -215.78606) (xy 18.769056 -215.7437) (xy 18.846121 -215.708505)
			(xy 18.926183 -215.680796) (xy 19.008516 -215.660822) (xy 19.092375 -215.648765) (xy 19.177 -215.644734)
			(xy 19.261625 -215.648765) (xy 19.345484 -215.660822) (xy 19.427817 -215.680796) (xy 19.507879 -215.708505)
			(xy 19.584944 -215.7437) (xy 19.658314 -215.78606) (xy 19.727326 -215.835203) (xy 19.791354 -215.890684)
			(xy 19.849819 -215.951999) (xy 19.90219 -216.018595) (xy 19.947993 -216.089867) (xy 19.986815 -216.16517)
			(xy 20.018303 -216.243822) (xy 20.042171 -216.325112) (xy 20.058205 -216.408302) (xy 20.066258 -216.492639)
			(xy 20.066762 -216.535) (xy 20.066258 -216.577361) (xy 20.058205 -216.661698) (xy 20.042171 -216.744888)
			(xy 20.018303 -216.826178) (xy 19.986815 -216.90483) (xy 19.947993 -216.980133) (xy 19.90219 -217.051405)
			(xy 19.849819 -217.118001) (xy 19.791354 -217.179316) (xy 19.727326 -217.234797) (xy 19.658314 -217.28394)
			(xy 19.584944 -217.3263) (xy 19.507879 -217.361495) (xy 19.427817 -217.389204) (xy 19.345484 -217.409178)
			(xy 19.261625 -217.421235) (xy 19.177 -217.425267) (xy 19.092375 -217.421235) (xy 19.008516 -217.409178)
			(xy 18.926183 -217.389204) (xy 18.846121 -217.361495) (xy 18.769056 -217.3263) (xy 18.695686 -217.28394)
			(xy 18.626674 -217.234797) (xy 18.562646 -217.179316) (xy 18.504181 -217.118001) (xy 18.45181 -217.051405)
			(xy 18.406007 -216.980133) (xy 18.367185 -216.90483) (xy 18.335697 -216.826178) (xy 18.311829 -216.744888)
			(xy 18.295795 -216.661698) (xy 18.287742 -216.577361) (xy 0.509016 -216.577361) (xy 0.509016 -219.117361)
			(xy 2.539742 -219.117361) (xy 2.539742 -219.032639) (xy 2.547795 -218.948302) (xy 2.563829 -218.865112)
			(xy 2.587697 -218.783822) (xy 2.619185 -218.70517) (xy 2.658007 -218.629867) (xy 2.70381 -218.558595)
			(xy 2.756181 -218.491999) (xy 2.814646 -218.430684) (xy 2.878674 -218.375203) (xy 2.947686 -218.32606)
			(xy 3.021056 -218.2837) (xy 3.098121 -218.248505) (xy 3.178183 -218.220796) (xy 3.260516 -218.200822)
			(xy 3.344375 -218.188765) (xy 3.429 -218.184734) (xy 3.513625 -218.188765) (xy 3.597484 -218.200822)
			(xy 3.679817 -218.220796) (xy 3.759879 -218.248505) (xy 3.836944 -218.2837) (xy 3.910314 -218.32606)
			(xy 3.979326 -218.375203) (xy 4.043354 -218.430684) (xy 4.101819 -218.491999) (xy 4.15419 -218.558595)
			(xy 4.199993 -218.629867) (xy 4.238815 -218.70517) (xy 4.270303 -218.783822) (xy 4.294171 -218.865112)
			(xy 4.310205 -218.948302) (xy 4.318258 -219.032639) (xy 4.318762 -219.075) (xy 4.318258 -219.117361)
			(xy 4.310205 -219.201698) (xy 4.294171 -219.284888) (xy 4.270303 -219.366178) (xy 4.238815 -219.44483)
			(xy 4.199993 -219.520133) (xy 4.15419 -219.591405) (xy 4.101819 -219.658001) (xy 4.043354 -219.719316)
			(xy 3.979326 -219.774797) (xy 3.910314 -219.82394) (xy 3.836944 -219.8663) (xy 3.759879 -219.901495)
			(xy 3.679817 -219.929204) (xy 3.597484 -219.949178) (xy 3.513625 -219.961235) (xy 3.429 -219.965267)
			(xy 3.344375 -219.961235) (xy 3.260516 -219.949178) (xy 3.178183 -219.929204) (xy 3.098121 -219.901495)
			(xy 3.021056 -219.8663) (xy 2.947686 -219.82394) (xy 2.878674 -219.774797) (xy 2.814646 -219.719316)
			(xy 2.756181 -219.658001) (xy 2.70381 -219.591405) (xy 2.658007 -219.520133) (xy 2.619185 -219.44483)
			(xy 2.587697 -219.366178) (xy 2.563829 -219.284888) (xy 2.547795 -219.201698) (xy 2.539742 -219.117361)
			(xy 0.509016 -219.117361) (xy 0.509016 -224.38741) (xy 11.380724 -224.38741) (xy 11.381308 -224.341014)
			(xy 11.390952 -224.248726) (xy 11.410148 -224.157942) (xy 11.438686 -224.069649) (xy 11.456924 -224.026984)
			(xy 11.460722 -224.01704) (xy 11.460725 -223.995778) (xy 11.456924 -223.985836) (xy 11.438684 -223.943172)
			(xy 11.410139 -223.85488) (xy 11.390944 -223.764096) (xy 11.381309 -223.671806) (xy 11.380724 -223.62541)
			(xy 11.381308 -223.579014) (xy 11.390952 -223.486726) (xy 11.410148 -223.395942) (xy 11.438686 -223.307649)
			(xy 11.456924 -223.264984) (xy 11.460722 -223.25504) (xy 11.460725 -223.233778) (xy 11.456924 -223.223836)
			(xy 11.438684 -223.181172) (xy 11.410139 -223.09288) (xy 11.390944 -223.002096) (xy 11.381309 -222.909806)
			(xy 11.380724 -222.86341) (xy 11.381222 -222.822304) (xy 11.388805 -222.740442) (xy 11.403908 -222.659629)
			(xy 11.426402 -222.580553) (xy 11.456094 -222.50389) (xy 11.492732 -222.430293) (xy 11.536004 -222.36039)
			(xy 11.585539 -222.294777) (xy 11.640916 -222.234013) (xy 11.701663 -222.178617) (xy 11.767261 -222.129061)
			(xy 11.83715 -222.085768) (xy 11.910736 -222.049106) (xy 11.98739 -222.01939) (xy 12.066458 -221.996872)
			(xy 12.147266 -221.981744) (xy 12.229126 -221.974135) (xy 12.270232 -221.973648) (xy 12.308522 -221.974043)
			(xy 12.384816 -221.980654) (xy 12.460259 -221.993806) (xy 12.53429 -222.013402) (xy 12.57046 -222.025972)
			(xy 12.578897 -222.028623) (xy 12.596567 -222.028623) (xy 12.605004 -222.025972) (xy 12.641177 -222.013416)
			(xy 12.715212 -221.993846) (xy 12.790653 -221.980703) (xy 12.866944 -221.974082) (xy 12.905232 -221.973648)
			(xy 12.946343 -221.974111) (xy 13.028213 -221.981698) (xy 13.109033 -221.996809) (xy 13.188115 -222.019314)
			(xy 13.264781 -222.049021) (xy 13.33838 -222.085677) (xy 13.408281 -222.128967) (xy 13.473889 -222.178524)
			(xy 13.534644 -222.233924) (xy 13.590027 -222.294695) (xy 13.639565 -222.360317) (xy 13.682836 -222.430231)
			(xy 13.719471 -222.503839) (xy 13.749156 -222.580515) (xy 13.771638 -222.659602) (xy 13.786726 -222.740427)
			(xy 13.794291 -222.822299) (xy 13.79474 -222.86341) (xy 13.794166 -222.909806) (xy 13.78452 -223.002095)
			(xy 13.765321 -223.092879) (xy 13.73678 -223.181172) (xy 13.71854 -223.223836) (xy 13.714727 -223.233776)
			(xy 13.714731 -223.255042) (xy 13.71854 -223.264984) (xy 13.73679 -223.307644) (xy 13.765332 -223.395937)
			(xy 13.784524 -223.486723) (xy 13.794156 -223.579014) (xy 13.79474 -223.62541) (xy 13.794166 -223.671806)
			(xy 13.78452 -223.764095) (xy 13.765321 -223.854879) (xy 13.73678 -223.943172) (xy 13.71854 -223.985836)
			(xy 13.714727 -223.995776) (xy 13.714731 -224.017042) (xy 13.71854 -224.026984) (xy 13.73679 -224.069644)
			(xy 13.765332 -224.157937) (xy 13.784524 -224.248723) (xy 13.794156 -224.341014) (xy 13.79474 -224.38741)
			(xy 13.794297 -224.428518) (xy 13.786712 -224.510382) (xy 13.771606 -224.591198) (xy 13.74911 -224.670275)
			(xy 13.719414 -224.74694) (xy 13.682773 -224.820538) (xy 13.639498 -224.890443) (xy 13.589959 -224.956057)
			(xy 13.534578 -225.016821) (xy 13.473828 -225.072217) (xy 13.408226 -225.121773) (xy 13.338333 -225.165065)
			(xy 13.264743 -225.201725) (xy 13.188086 -225.231439) (xy 13.109014 -225.253955) (xy 13.028202 -225.269081)
			(xy 12.946339 -225.276687) (xy 12.905232 -225.277172) (xy 12.866942 -225.276757) (xy 12.790648 -225.270152)
			(xy 12.715206 -225.257005) (xy 12.641175 -225.237415) (xy 12.605004 -225.224848) (xy 12.596567 -225.222197)
			(xy 12.578897 -225.222197) (xy 12.57046 -225.224848) (xy 12.534281 -225.237387) (xy 12.460248 -225.256961)
			(xy 12.384809 -225.270109) (xy 12.30852 -225.276735) (xy 12.270232 -225.277172) (xy 12.229122 -225.276706)
			(xy 12.147251 -225.269118) (xy 12.066431 -225.254007) (xy 11.98735 -225.231503) (xy 11.910683 -225.201796)
			(xy 11.837085 -225.165141) (xy 11.767183 -225.121851) (xy 11.701575 -225.072294) (xy 11.64082 -225.016894)
			(xy 11.585437 -224.956124) (xy 11.535899 -224.890502) (xy 11.492628 -224.820589) (xy 11.455993 -224.74698)
			(xy 11.426308 -224.670305) (xy 11.403826 -224.591218) (xy 11.388738 -224.510393) (xy 11.381173 -224.428521)
			(xy 11.380724 -224.38741) (xy 0.509016 -224.38741) (xy 0.509016 -227.61321) (xy 37.175948 -227.61321)
			(xy 37.17653 -227.566814) (xy 37.186174 -227.474526) (xy 37.20537 -227.383742) (xy 37.23391 -227.295449)
			(xy 37.252148 -227.252784) (xy 37.25595 -227.24284) (xy 37.255954 -227.221578) (xy 37.252148 -227.211636)
			(xy 37.23391 -227.168971) (xy 37.205363 -227.08068) (xy 37.186168 -226.989896) (xy 37.176533 -226.897606)
			(xy 37.175948 -226.85121) (xy 37.17653 -226.804814) (xy 37.186174 -226.712526) (xy 37.20537 -226.621742)
			(xy 37.23391 -226.533449) (xy 37.252148 -226.490784) (xy 37.25595 -226.48084) (xy 37.255954 -226.459578)
			(xy 37.252148 -226.449636) (xy 37.23391 -226.406971) (xy 37.205363 -226.31868) (xy 37.186168 -226.227896)
			(xy 37.176533 -226.135606) (xy 37.175948 -226.08921) (xy 37.176422 -226.048103) (xy 37.184006 -225.96624)
			(xy 37.199109 -225.885425) (xy 37.221603 -225.806349) (xy 37.251297 -225.729684) (xy 37.287936 -225.656086)
			(xy 37.331209 -225.586182) (xy 37.380746 -225.520568) (xy 37.436125 -225.459804) (xy 37.496873 -225.404408)
			(xy 37.562473 -225.354852) (xy 37.632364 -225.31156) (xy 37.705952 -225.274899) (xy 37.782608 -225.245184)
			(xy 37.861678 -225.222667) (xy 37.942488 -225.207541) (xy 38.024349 -225.199934) (xy 38.065456 -225.199448)
			(xy 38.103746 -225.199866) (xy 38.180039 -225.20647) (xy 38.255482 -225.219616) (xy 38.329513 -225.239206)
			(xy 38.365684 -225.251772) (xy 38.374121 -225.254423) (xy 38.391791 -225.254423) (xy 38.400228 -225.251772)
			(xy 38.436409 -225.239237) (xy 38.51044 -225.219662) (xy 38.585879 -225.206512) (xy 38.662168 -225.199885)
			(xy 38.700456 -225.199448) (xy 38.741565 -225.199994) (xy 38.823431 -225.207578) (xy 38.904249 -225.222684)
			(xy 38.983327 -225.245184) (xy 39.059992 -225.274885) (xy 39.133589 -225.311535) (xy 39.203489 -225.354821)
			(xy 39.269096 -225.404372) (xy 39.329851 -225.459767) (xy 39.385234 -225.520531) (xy 39.434773 -225.586148)
			(xy 39.478046 -225.656056) (xy 39.514682 -225.72966) (xy 39.544369 -225.80633) (xy 39.566854 -225.885413)
			(xy 39.581945 -225.966233) (xy 39.589513 -226.048101) (xy 39.589964 -226.08921) (xy 39.589388 -226.135606)
			(xy 39.579742 -226.227895) (xy 39.560544 -226.318678) (xy 39.532003 -226.406972) (xy 39.513764 -226.449636)
			(xy 39.50995 -226.459576) (xy 39.509953 -226.480842) (xy 39.513764 -226.490784) (xy 39.532009 -226.533446)
			(xy 39.560554 -226.621738) (xy 39.579747 -226.712523) (xy 39.58938 -226.804814) (xy 39.589964 -226.85121)
			(xy 39.589388 -226.897606) (xy 39.579742 -226.989895) (xy 39.560544 -227.080678) (xy 39.532003 -227.168972)
			(xy 39.513764 -227.211636) (xy 39.50995 -227.221576) (xy 39.509953 -227.242842) (xy 39.513764 -227.252784)
			(xy 39.532009 -227.295446) (xy 39.560554 -227.383738) (xy 39.579747 -227.474523) (xy 39.58938 -227.566814)
			(xy 39.589964 -227.61321) (xy 39.589497 -227.654317) (xy 39.581912 -227.73618) (xy 39.566807 -227.816994)
			(xy 39.544311 -227.89607) (xy 39.514617 -227.972734) (xy 39.477977 -228.046332) (xy 39.434703 -228.116235)
			(xy 39.385166 -228.181849) (xy 39.329787 -228.242613) (xy 39.269038 -228.298009) (xy 39.203438 -228.347564)
			(xy 39.133547 -228.390857) (xy 39.059959 -228.427518) (xy 38.983304 -228.457233) (xy 38.904234 -228.479751)
			(xy 38.823424 -228.494878) (xy 38.741563 -228.502486) (xy 38.700456 -228.502972) (xy 38.662167 -228.50255)
			(xy 38.585873 -228.495947) (xy 38.51043 -228.482802) (xy 38.436399 -228.463214) (xy 38.400228 -228.450648)
			(xy 38.391791 -228.447997) (xy 38.374121 -228.447997) (xy 38.365684 -228.450648) (xy 38.329503 -228.46318)
			(xy 38.255471 -228.482756) (xy 38.180032 -228.495906) (xy 38.103744 -228.502534) (xy 38.065456 -228.502972)
			(xy 38.024344 -228.502589) (xy 37.94247 -228.494997) (xy 37.861646 -228.479882) (xy 37.782563 -228.457372)
			(xy 37.705894 -228.42766) (xy 37.632294 -228.391) (xy 37.562391 -228.347704) (xy 37.496782 -228.298142)
			(xy 37.436027 -228.242736) (xy 37.380645 -228.18196) (xy 37.331107 -228.116333) (xy 37.287837 -228.046414)
			(xy 37.251205 -227.972801) (xy 37.221522 -227.89612) (xy 37.199042 -227.817028) (xy 37.183957 -227.736199)
			(xy 37.176395 -227.654323) (xy 37.175948 -227.61321) (xy 0.509016 -227.61321) (xy 0.509016 -230.439214)
			(xy 7.371588 -230.439214) (xy 7.372184 -230.392811) (xy 7.381883 -230.300513) (xy 7.401145 -230.209727)
			(xy 7.429762 -230.121443) (xy 7.448042 -230.078788) (xy 7.451842 -230.068844) (xy 7.451847 -230.047582)
			(xy 7.448042 -230.03764) (xy 7.429785 -229.994977) (xy 7.40119 -229.90669) (xy 7.381932 -229.815908)
			(xy 7.372218 -229.723615) (xy 7.371588 -229.677214) (xy 7.372092 -229.634853) (xy 7.380145 -229.550516)
			(xy 7.396179 -229.467326) (xy 7.420047 -229.386036) (xy 7.451535 -229.307384) (xy 7.490357 -229.232081)
			(xy 7.53616 -229.160809) (xy 7.588531 -229.094213) (xy 7.646996 -229.032898) (xy 7.711024 -228.977417)
			(xy 7.780036 -228.928274) (xy 7.853406 -228.885914) (xy 7.930471 -228.850719) (xy 8.010533 -228.82301)
			(xy 8.092866 -228.803036) (xy 8.176725 -228.790979) (xy 8.26135 -228.786948) (xy 8.345975 -228.790979)
			(xy 8.429834 -228.803036) (xy 8.512167 -228.82301) (xy 8.592229 -228.850719) (xy 8.669294 -228.885914)
			(xy 8.742664 -228.928274) (xy 8.811676 -228.977417) (xy 8.875704 -229.032898) (xy 8.934169 -229.094213)
			(xy 8.98654 -229.160809) (xy 9.032343 -229.232081) (xy 9.071165 -229.307384) (xy 9.102653 -229.386036)
			(xy 9.126521 -229.467326) (xy 9.142555 -229.550516) (xy 9.150608 -229.634853) (xy 9.151112 -229.677214)
			(xy 9.150491 -229.723616) (xy 9.140799 -229.815914) (xy 9.121544 -229.906699) (xy 9.092935 -229.994984)
			(xy 9.074658 -230.03764) (xy 9.070842 -230.047579) (xy 9.070847 -230.068846) (xy 9.074658 -230.078788)
			(xy 9.092924 -230.121447) (xy 9.121516 -230.209736) (xy 9.140772 -230.300519) (xy 9.150484 -230.392813)
			(xy 9.151112 -230.439214) (xy 9.150608 -230.481575) (xy 9.142555 -230.565912) (xy 9.126521 -230.649102)
			(xy 9.102653 -230.730392) (xy 9.071165 -230.809044) (xy 9.032343 -230.884347) (xy 8.98654 -230.955619)
			(xy 8.934169 -231.022215) (xy 8.875704 -231.08353) (xy 8.811676 -231.139011) (xy 8.742664 -231.188154)
			(xy 8.669294 -231.230514) (xy 8.592229 -231.265709) (xy 8.512167 -231.293418) (xy 8.429834 -231.313392)
			(xy 8.345975 -231.325449) (xy 8.26135 -231.329481) (xy 8.176725 -231.325449) (xy 8.092866 -231.313392)
			(xy 8.010533 -231.293418) (xy 7.930471 -231.265709) (xy 7.853406 -231.230514) (xy 7.780036 -231.188154)
			(xy 7.711024 -231.139011) (xy 7.646996 -231.08353) (xy 7.588531 -231.022215) (xy 7.53616 -230.955619)
			(xy 7.490357 -230.884347) (xy 7.451535 -230.809044) (xy 7.420047 -230.730392) (xy 7.396179 -230.649102)
			(xy 7.380145 -230.565912) (xy 7.372092 -230.481575) (xy 7.371588 -230.439214) (xy 0.509016 -230.439214)
			(xy 0.509016 -235.773214) (xy 7.396988 -235.773214) (xy 7.397584 -235.726811) (xy 7.407283 -235.634513)
			(xy 7.426545 -235.543727) (xy 7.455162 -235.455443) (xy 7.473442 -235.412788) (xy 7.477242 -235.402844)
			(xy 7.477247 -235.381582) (xy 7.473442 -235.37164) (xy 7.455185 -235.328977) (xy 7.42659 -235.24069)
			(xy 7.407332 -235.149908) (xy 7.397618 -235.057615) (xy 7.396988 -235.011214) (xy 7.397531 -234.967564)
			(xy 7.406089 -234.880683) (xy 7.423114 -234.795059) (xy 7.448444 -234.711514) (xy 7.481834 -234.63085)
			(xy 7.522962 -234.553845) (xy 7.571435 -234.481238) (xy 7.626786 -234.413727) (xy 7.688482 -234.351961)
			(xy 7.75593 -234.296534) (xy 7.828483 -234.247979) (xy 7.905442 -234.206764) (xy 7.986067 -234.173283)
			(xy 8.02767 -234.16006) (xy 8.043418 -234.155234) (xy 8.06323 -234.129326) (xy 8.066786 -234.00004)
			(xy 8.048498 -233.973116) (xy 8.033004 -233.967528) (xy 7.993889 -233.952766) (xy 7.918359 -233.916908)
			(xy 7.846527 -233.874123) (xy 7.779025 -233.824787) (xy 7.716449 -233.769336) (xy 7.659352 -233.708258)
			(xy 7.608237 -233.642093) (xy 7.563555 -233.571424) (xy 7.5257 -233.496875) (xy 7.495006 -233.419104)
			(xy 7.471744 -233.338795) (xy 7.456119 -233.256659) (xy 7.448269 -233.173419) (xy 7.447788 -233.131614)
			(xy 7.448384 -233.085211) (xy 7.458083 -232.992913) (xy 7.477345 -232.902127) (xy 7.505962 -232.813843)
			(xy 7.524242 -232.771188) (xy 7.528042 -232.761244) (xy 7.528047 -232.739982) (xy 7.524242 -232.73004)
			(xy 7.505985 -232.687377) (xy 7.47739 -232.59909) (xy 7.458132 -232.508308) (xy 7.448418 -232.416015)
			(xy 7.447788 -232.369614) (xy 7.448292 -232.327253) (xy 7.456345 -232.242916) (xy 7.472379 -232.159726)
			(xy 7.496247 -232.078436) (xy 7.527735 -231.999784) (xy 7.566557 -231.924481) (xy 7.61236 -231.853209)
			(xy 7.664731 -231.786613) (xy 7.723196 -231.725298) (xy 7.787224 -231.669817) (xy 7.856236 -231.620674)
			(xy 7.929606 -231.578314) (xy 8.006671 -231.543119) (xy 8.086733 -231.51541) (xy 8.169066 -231.495436)
			(xy 8.252925 -231.483379) (xy 8.33755 -231.479348) (xy 8.422175 -231.483379) (xy 8.506034 -231.495436)
			(xy 8.588367 -231.51541) (xy 8.668429 -231.543119) (xy 8.745494 -231.578314) (xy 8.818864 -231.620674)
			(xy 8.887876 -231.669817) (xy 8.951904 -231.725298) (xy 9.010369 -231.786613) (xy 9.06274 -231.853209)
			(xy 9.108543 -231.924481) (xy 9.147365 -231.999784) (xy 9.159062 -232.029) (xy 40.480996 -232.029)
			(xy 40.481621 -231.982598) (xy 40.491311 -231.8903) (xy 40.510566 -231.799515) (xy 40.539174 -231.71123)
			(xy 40.55745 -231.668574) (xy 40.561258 -231.658632) (xy 40.561258 -231.637368) (xy 40.55745 -231.627426)
			(xy 40.539189 -231.584765) (xy 40.510595 -231.496477) (xy 40.491338 -231.405694) (xy 40.481625 -231.313401)
			(xy 40.480996 -231.267) (xy 40.4815 -231.224639) (xy 40.489553 -231.140302) (xy 40.505587 -231.057112)
			(xy 40.529455 -230.975822) (xy 40.560943 -230.89717) (xy 40.599765 -230.821867) (xy 40.645568 -230.750595)
			(xy 40.697939 -230.683999) (xy 40.756404 -230.622684) (xy 40.820432 -230.567203) (xy 40.889444 -230.51806)
			(xy 40.962814 -230.4757) (xy 41.039879 -230.440505) (xy 41.119941 -230.412796) (xy 41.202274 -230.392822)
			(xy 41.286133 -230.380765) (xy 41.370758 -230.376734) (xy 41.455383 -230.380765) (xy 41.539242 -230.392822)
			(xy 41.621575 -230.412796) (xy 41.701637 -230.440505) (xy 41.778702 -230.4757) (xy 41.852072 -230.51806)
			(xy 41.921084 -230.567203) (xy 41.985112 -230.622684) (xy 42.043577 -230.683999) (xy 42.095948 -230.750595)
			(xy 42.141751 -230.821867) (xy 42.180573 -230.89717) (xy 42.212061 -230.975822) (xy 42.235929 -231.057112)
			(xy 42.251963 -231.140302) (xy 42.260016 -231.224639) (xy 42.26052 -231.267) (xy 42.259893 -231.313402)
			(xy 42.250203 -231.405699) (xy 42.23095 -231.496485) (xy 42.202342 -231.58477) (xy 42.184066 -231.627426)
			(xy 42.180257 -231.637368) (xy 42.180257 -231.658632) (xy 42.184066 -231.668574) (xy 42.202328 -231.711235)
			(xy 42.230921 -231.799523) (xy 42.250178 -231.890306) (xy 42.259891 -231.982599) (xy 42.26052 -232.029)
			(xy 42.260016 -232.071361) (xy 42.251963 -232.155698) (xy 42.235929 -232.238888) (xy 42.212061 -232.320178)
			(xy 42.180573 -232.39883) (xy 42.141751 -232.474133) (xy 42.095948 -232.545405) (xy 42.043577 -232.612001)
			(xy 41.985112 -232.673316) (xy 41.921084 -232.728797) (xy 41.852072 -232.77794) (xy 41.778702 -232.8203)
			(xy 41.701637 -232.855495) (xy 41.621575 -232.883204) (xy 41.539242 -232.903178) (xy 41.455383 -232.915235)
			(xy 41.370758 -232.919267) (xy 41.286133 -232.915235) (xy 41.202274 -232.903178) (xy 41.119941 -232.883204)
			(xy 41.039879 -232.855495) (xy 40.962814 -232.8203) (xy 40.889444 -232.77794) (xy 40.820432 -232.728797)
			(xy 40.756404 -232.673316) (xy 40.697939 -232.612001) (xy 40.645568 -232.545405) (xy 40.599765 -232.474133)
			(xy 40.560943 -232.39883) (xy 40.529455 -232.320178) (xy 40.505587 -232.238888) (xy 40.489553 -232.155698)
			(xy 40.4815 -232.071361) (xy 40.480996 -232.029) (xy 9.159062 -232.029) (xy 9.178853 -232.078436)
			(xy 9.202721 -232.159726) (xy 9.218755 -232.242916) (xy 9.226808 -232.327253) (xy 9.227312 -232.369614)
			(xy 9.226691 -232.416016) (xy 9.216999 -232.508314) (xy 9.197744 -232.599099) (xy 9.169135 -232.687384)
			(xy 9.150858 -232.73004) (xy 9.147042 -232.739979) (xy 9.147047 -232.761246) (xy 9.150858 -232.771188)
			(xy 9.169124 -232.813847) (xy 9.197716 -232.902136) (xy 9.216972 -232.992919) (xy 9.226684 -233.085213)
			(xy 9.227312 -233.131614) (xy 9.226795 -233.175265) (xy 9.218234 -233.262146) (xy 9.201206 -233.347771)
			(xy 9.175874 -233.431317) (xy 9.142482 -233.51198) (xy 9.10135 -233.588986) (xy 9.052876 -233.661593)
			(xy 8.997523 -233.729104) (xy 8.935825 -233.790869) (xy 8.868375 -233.846295) (xy 8.795821 -233.89485)
			(xy 8.71886 -233.936065) (xy 8.638233 -233.969545) (xy 8.59663 -233.982768) (xy 8.580882 -233.987594)
			(xy 8.56107 -234.013502) (xy 8.557514 -234.142788) (xy 8.575802 -234.169712) (xy 8.591296 -234.1753)
			(xy 8.630413 -234.190055) (xy 8.705944 -234.225913) (xy 8.777777 -234.268699) (xy 8.845279 -234.318036)
			(xy 8.907854 -234.373488) (xy 8.964951 -234.434566) (xy 9.016066 -234.500731) (xy 9.060748 -234.571401)
			(xy 9.098603 -234.64595) (xy 9.129296 -234.723723) (xy 9.152558 -234.804031) (xy 9.168182 -234.886168)
			(xy 9.176032 -234.969409) (xy 9.176512 -235.011214) (xy 9.175891 -235.057616) (xy 9.166199 -235.149914)
			(xy 9.146944 -235.240699) (xy 9.118335 -235.328984) (xy 9.100058 -235.37164) (xy 9.096242 -235.381579)
			(xy 9.096247 -235.402846) (xy 9.100058 -235.412788) (xy 9.118324 -235.455447) (xy 9.146916 -235.543736)
			(xy 9.166172 -235.634519) (xy 9.175884 -235.726813) (xy 9.176512 -235.773214) (xy 9.176008 -235.815575)
			(xy 9.167955 -235.899912) (xy 9.151921 -235.983102) (xy 9.128053 -236.064392) (xy 9.096565 -236.143044)
			(xy 9.057743 -236.218347) (xy 9.01194 -236.289619) (xy 8.959569 -236.356215) (xy 8.901104 -236.41753)
			(xy 8.837076 -236.473011) (xy 8.768064 -236.522154) (xy 8.694694 -236.564514) (xy 8.617629 -236.599709)
			(xy 8.537567 -236.627418) (xy 8.455234 -236.647392) (xy 8.371375 -236.659449) (xy 8.28675 -236.663481)
			(xy 8.202125 -236.659449) (xy 8.118266 -236.647392) (xy 8.035933 -236.627418) (xy 7.955871 -236.599709)
			(xy 7.878806 -236.564514) (xy 7.805436 -236.522154) (xy 7.736424 -236.473011) (xy 7.672396 -236.41753)
			(xy 7.613931 -236.356215) (xy 7.56156 -236.289619) (xy 7.515757 -236.218347) (xy 7.476935 -236.143044)
			(xy 7.445447 -236.064392) (xy 7.421579 -235.983102) (xy 7.405545 -235.899912) (xy 7.397492 -235.815575)
			(xy 7.396988 -235.773214) (xy 0.509016 -235.773214) (xy 0.509016 -238.20501) (xy 6.117336 -238.20501)
			(xy 6.11797 -238.158608) (xy 6.127658 -238.066311) (xy 6.14691 -237.975526) (xy 6.175516 -237.88724)
			(xy 6.19379 -237.844584) (xy 6.19759 -237.83464) (xy 6.197594 -237.813378) (xy 6.19379 -237.803436)
			(xy 6.175528 -237.760775) (xy 6.146936 -237.672487) (xy 6.127679 -237.581704) (xy 6.117965 -237.489411)
			(xy 6.117336 -237.44301) (xy 6.11784 -237.400649) (xy 6.125893 -237.316312) (xy 6.141927 -237.233122)
			(xy 6.165795 -237.151832) (xy 6.197283 -237.07318) (xy 6.236105 -236.997877) (xy 6.281908 -236.926605)
			(xy 6.334279 -236.860009) (xy 6.392744 -236.798694) (xy 6.456772 -236.743213) (xy 6.525784 -236.69407)
			(xy 6.599154 -236.65171) (xy 6.676219 -236.616515) (xy 6.756281 -236.588806) (xy 6.838614 -236.568832)
			(xy 6.922473 -236.556775) (xy 7.007098 -236.552744) (xy 7.091723 -236.556775) (xy 7.175582 -236.568832)
			(xy 7.257915 -236.588806) (xy 7.337977 -236.616515) (xy 7.415042 -236.65171) (xy 7.488412 -236.69407)
			(xy 7.557424 -236.743213) (xy 7.621452 -236.798694) (xy 7.679917 -236.860009) (xy 7.732288 -236.926605)
			(xy 7.778091 -236.997877) (xy 7.816913 -237.07318) (xy 7.848401 -237.151832) (xy 7.872269 -237.233122)
			(xy 7.888303 -237.316312) (xy 7.892761 -237.363) (xy 40.480996 -237.363) (xy 40.481621 -237.316598)
			(xy 40.491311 -237.2243) (xy 40.510566 -237.133515) (xy 40.539174 -237.04523) (xy 40.55745 -237.002574)
			(xy 40.561258 -236.992632) (xy 40.561258 -236.971368) (xy 40.55745 -236.961426) (xy 40.539189 -236.918765)
			(xy 40.510595 -236.830477) (xy 40.491338 -236.739694) (xy 40.481625 -236.647401) (xy 40.480996 -236.601)
			(xy 40.481468 -236.559748) (xy 40.489125 -236.477599) (xy 40.504354 -236.396513) (xy 40.527026 -236.317184)
			(xy 40.556944 -236.240295) (xy 40.593852 -236.166506) (xy 40.637433 -236.096451) (xy 40.687313 -236.030732)
			(xy 40.743063 -235.969913) (xy 40.804204 -235.914517) (xy 40.870211 -235.865019) (xy 40.940518 -235.821845)
			(xy 40.977312 -235.803186) (xy 40.985606 -235.798599) (xy 40.998363 -235.784607) (xy 41.005163 -235.766935)
			(xy 41.005506 -235.757466) (xy 41.005506 -235.666534) (xy 41.005102 -235.657069) (xy 40.998326 -235.639398)
			(xy 40.985608 -235.625383) (xy 40.977312 -235.620814) (xy 40.940537 -235.60212) (xy 40.870235 -235.558945)
			(xy 40.804231 -235.509448) (xy 40.743093 -235.454053) (xy 40.687345 -235.393236) (xy 40.637466 -235.327521)
			(xy 40.593884 -235.25747) (xy 40.556974 -235.183685) (xy 40.527053 -235.106801) (xy 40.504377 -235.027477)
			(xy 40.489141 -234.946395) (xy 40.481477 -234.864251) (xy 40.480996 -234.823) (xy 40.481621 -234.776598)
			(xy 40.491311 -234.6843) (xy 40.510566 -234.593515) (xy 40.539174 -234.50523) (xy 40.55745 -234.462574)
			(xy 40.561258 -234.452632) (xy 40.561258 -234.431368) (xy 40.55745 -234.421426) (xy 40.539189 -234.378765)
			(xy 40.510595 -234.290477) (xy 40.491338 -234.199694) (xy 40.481625 -234.107401) (xy 40.480996 -234.061)
			(xy 40.4815 -234.018639) (xy 40.489553 -233.934302) (xy 40.505587 -233.851112) (xy 40.529455 -233.769822)
			(xy 40.560943 -233.69117) (xy 40.599765 -233.615867) (xy 40.645568 -233.544595) (xy 40.697939 -233.477999)
			(xy 40.756404 -233.416684) (xy 40.820432 -233.361203) (xy 40.889444 -233.31206) (xy 40.962814 -233.2697)
			(xy 41.039879 -233.234505) (xy 41.119941 -233.206796) (xy 41.202274 -233.186822) (xy 41.286133 -233.174765)
			(xy 41.370758 -233.170734) (xy 41.455383 -233.174765) (xy 41.539242 -233.186822) (xy 41.621575 -233.206796)
			(xy 41.701637 -233.234505) (xy 41.778702 -233.2697) (xy 41.852072 -233.31206) (xy 41.921084 -233.361203)
			(xy 41.985112 -233.416684) (xy 42.043577 -233.477999) (xy 42.095948 -233.544595) (xy 42.141751 -233.615867)
			(xy 42.180573 -233.69117) (xy 42.212061 -233.769822) (xy 42.235929 -233.851112) (xy 42.251963 -233.934302)
			(xy 42.260016 -234.018639) (xy 42.26052 -234.061) (xy 42.259893 -234.107402) (xy 42.250203 -234.199699)
			(xy 42.23095 -234.290485) (xy 42.202342 -234.37877) (xy 42.184066 -234.421426) (xy 42.180257 -234.431368)
			(xy 42.180257 -234.452632) (xy 42.184066 -234.462574) (xy 42.202328 -234.505235) (xy 42.230921 -234.593523)
			(xy 42.250178 -234.684306) (xy 42.259891 -234.776599) (xy 42.26052 -234.823) (xy 42.260039 -234.864252)
			(xy 42.252382 -234.9464) (xy 42.237153 -235.027486) (xy 42.214483 -235.106814) (xy 42.184565 -235.183703)
			(xy 42.147658 -235.257492) (xy 42.104077 -235.327546) (xy 42.054198 -235.393266) (xy 41.998449 -235.454085)
			(xy 41.937309 -235.509482) (xy 41.871303 -235.55898) (xy 41.800998 -235.602155) (xy 41.764204 -235.620814)
			(xy 41.755914 -235.625406) (xy 41.743154 -235.639395) (xy 41.736353 -235.657065) (xy 41.73601 -235.666534)
			(xy 41.73601 -235.757466) (xy 41.736405 -235.766932) (xy 41.743184 -235.784604) (xy 41.755906 -235.798619)
			(xy 41.764204 -235.803186) (xy 41.800983 -235.821872) (xy 41.871285 -235.865049) (xy 41.937288 -235.914547)
			(xy 41.998426 -235.969943) (xy 42.054173 -236.03076) (xy 42.104052 -236.096477) (xy 42.147633 -236.166528)
			(xy 42.184542 -236.240313) (xy 42.214464 -236.317198) (xy 42.237139 -236.396522) (xy 42.252375 -236.477604)
			(xy 42.260039 -236.559749) (xy 42.26052 -236.601) (xy 42.259893 -236.647402) (xy 42.250203 -236.739699)
			(xy 42.23095 -236.830485) (xy 42.202342 -236.91877) (xy 42.184066 -236.961426) (xy 42.180257 -236.971368)
			(xy 42.180257 -236.992632) (xy 42.184066 -237.002574) (xy 42.202328 -237.045235) (xy 42.230921 -237.133523)
			(xy 42.250178 -237.224306) (xy 42.259891 -237.316599) (xy 42.26052 -237.363) (xy 42.260016 -237.405361)
			(xy 42.251963 -237.489698) (xy 42.235929 -237.572888) (xy 42.212061 -237.654178) (xy 42.180573 -237.73283)
			(xy 42.141751 -237.808133) (xy 42.095948 -237.879405) (xy 42.043577 -237.946001) (xy 41.985112 -238.007316)
			(xy 41.921084 -238.062797) (xy 41.852072 -238.11194) (xy 41.778702 -238.1543) (xy 41.701637 -238.189495)
			(xy 41.621575 -238.217204) (xy 41.539242 -238.237178) (xy 41.455383 -238.249235) (xy 41.370758 -238.253267)
			(xy 41.286133 -238.249235) (xy 41.202274 -238.237178) (xy 41.119941 -238.217204) (xy 41.039879 -238.189495)
			(xy 40.962814 -238.1543) (xy 40.889444 -238.11194) (xy 40.820432 -238.062797) (xy 40.756404 -238.007316)
			(xy 40.697939 -237.946001) (xy 40.645568 -237.879405) (xy 40.599765 -237.808133) (xy 40.560943 -237.73283)
			(xy 40.529455 -237.654178) (xy 40.505587 -237.572888) (xy 40.489553 -237.489698) (xy 40.4815 -237.405361)
			(xy 40.480996 -237.363) (xy 7.892761 -237.363) (xy 7.896356 -237.400649) (xy 7.89686 -237.44301)
			(xy 7.896234 -237.489412) (xy 7.886543 -237.581709) (xy 7.867289 -237.672495) (xy 7.838682 -237.76078)
			(xy 7.820406 -237.803436) (xy 7.816595 -237.813376) (xy 7.816599 -237.834642) (xy 7.820406 -237.844584)
			(xy 7.838674 -237.887242) (xy 7.867265 -237.975532) (xy 7.88652 -238.066315) (xy 7.896232 -238.158609)
			(xy 7.89686 -238.20501) (xy 7.896356 -238.247371) (xy 7.888303 -238.331708) (xy 7.872269 -238.414898)
			(xy 7.848401 -238.496188) (xy 7.816913 -238.57484) (xy 7.778091 -238.650143) (xy 7.732288 -238.721415)
			(xy 7.679917 -238.788011) (xy 7.621452 -238.849326) (xy 7.557424 -238.904807) (xy 7.488412 -238.95395)
			(xy 7.415042 -238.99631) (xy 7.337977 -239.031505) (xy 7.257915 -239.059214) (xy 7.175582 -239.079188)
			(xy 7.091723 -239.091245) (xy 7.007098 -239.095277) (xy 6.922473 -239.091245) (xy 6.838614 -239.079188)
			(xy 6.756281 -239.059214) (xy 6.676219 -239.031505) (xy 6.599154 -238.99631) (xy 6.525784 -238.95395)
			(xy 6.456772 -238.904807) (xy 6.392744 -238.849326) (xy 6.334279 -238.788011) (xy 6.281908 -238.721415)
			(xy 6.236105 -238.650143) (xy 6.197283 -238.57484) (xy 6.165795 -238.496188) (xy 6.141927 -238.414898)
			(xy 6.125893 -238.331708) (xy 6.11784 -238.247371) (xy 6.117336 -238.20501) (xy 0.509016 -238.20501)
			(xy 0.509016 -239.5474) (xy 41.827196 -239.5474) (xy 41.827821 -239.500998) (xy 41.837511 -239.4087)
			(xy 41.856766 -239.317915) (xy 41.885374 -239.22963) (xy 41.90365 -239.186974) (xy 41.907458 -239.177032)
			(xy 41.907458 -239.155768) (xy 41.90365 -239.145826) (xy 41.885389 -239.103165) (xy 41.856795 -239.014877)
			(xy 41.837538 -238.924094) (xy 41.827825 -238.831801) (xy 41.827196 -238.7854) (xy 41.8277 -238.743039)
			(xy 41.835753 -238.658702) (xy 41.851787 -238.575512) (xy 41.875655 -238.494222) (xy 41.907143 -238.41557)
			(xy 41.945965 -238.340267) (xy 41.991768 -238.268995) (xy 42.044139 -238.202399) (xy 42.102604 -238.141084)
			(xy 42.166632 -238.085603) (xy 42.235644 -238.03646) (xy 42.309014 -237.9941) (xy 42.386079 -237.958905)
			(xy 42.466141 -237.931196) (xy 42.548474 -237.911222) (xy 42.632333 -237.899165) (xy 42.716958 -237.895134)
			(xy 42.801583 -237.899165) (xy 42.885442 -237.911222) (xy 42.967775 -237.931196) (xy 43.047837 -237.958905)
			(xy 43.124902 -237.9941) (xy 43.198272 -238.03646) (xy 43.267284 -238.085603) (xy 43.331312 -238.141084)
			(xy 43.389777 -238.202399) (xy 43.442148 -238.268995) (xy 43.487951 -238.340267) (xy 43.526773 -238.41557)
			(xy 43.558261 -238.494222) (xy 43.582129 -238.575512) (xy 43.598163 -238.658702) (xy 43.606216 -238.743039)
			(xy 43.60672 -238.7854) (xy 43.606093 -238.831802) (xy 43.596403 -238.924099) (xy 43.57715 -239.014885)
			(xy 43.548542 -239.10317) (xy 43.530266 -239.145826) (xy 43.526457 -239.155768) (xy 43.526457 -239.177032)
			(xy 43.530266 -239.186974) (xy 43.548528 -239.229635) (xy 43.577121 -239.317923) (xy 43.596378 -239.408706)
			(xy 43.606091 -239.500999) (xy 43.60672 -239.5474) (xy 43.606216 -239.589761) (xy 43.598163 -239.674098)
			(xy 43.582129 -239.757288) (xy 43.558261 -239.838578) (xy 43.526773 -239.91723) (xy 43.487951 -239.992533)
			(xy 43.442148 -240.063805) (xy 43.389777 -240.130401) (xy 43.331312 -240.191716) (xy 43.267284 -240.247197)
			(xy 43.198272 -240.29634) (xy 43.124902 -240.3387) (xy 43.047837 -240.373895) (xy 42.967775 -240.401604)
			(xy 42.885442 -240.421578) (xy 42.801583 -240.433635) (xy 42.716958 -240.437667) (xy 42.632333 -240.433635)
			(xy 42.548474 -240.421578) (xy 42.466141 -240.401604) (xy 42.386079 -240.373895) (xy 42.309014 -240.3387)
			(xy 42.235644 -240.29634) (xy 42.166632 -240.247197) (xy 42.102604 -240.191716) (xy 42.044139 -240.130401)
			(xy 41.991768 -240.063805) (xy 41.945965 -239.992533) (xy 41.907143 -239.91723) (xy 41.875655 -239.838578)
			(xy 41.851787 -239.757288) (xy 41.835753 -239.674098) (xy 41.8277 -239.589761) (xy 41.827196 -239.5474)
			(xy 0.509016 -239.5474) (xy 0.509016 -243.513864) (xy 2.815336 -243.513864) (xy 2.81576 -243.475575)
			(xy 2.822363 -243.399281) (xy 2.835507 -243.323838) (xy 2.855095 -243.249807) (xy 2.86766 -243.213636)
			(xy 2.870329 -243.205204) (xy 2.870317 -243.187529) (xy 2.86766 -243.179092) (xy 2.855117 -243.142914)
			(xy 2.835544 -243.068881) (xy 2.822396 -242.993442) (xy 2.815772 -242.917152) (xy 2.815336 -242.878864)
			(xy 2.815796 -242.837753) (xy 2.823384 -242.755883) (xy 2.838494 -242.675062) (xy 2.860999 -242.59598)
			(xy 2.890706 -242.519313) (xy 2.927361 -242.445715) (xy 2.970652 -242.375813) (xy 3.020209 -242.310205)
			(xy 3.075609 -242.24945) (xy 3.13638 -242.194067) (xy 3.202003 -242.144528) (xy 3.271917 -242.101257)
			(xy 3.345526 -242.064623) (xy 3.422201 -242.034938) (xy 3.501289 -242.012456) (xy 3.582114 -241.997369)
			(xy 3.663987 -241.989805) (xy 3.705098 -241.989356) (xy 3.744024 -241.989768) (xy 3.821581 -241.996546)
			(xy 3.898248 -242.010077) (xy 3.97344 -242.030258) (xy 4.010152 -242.043204) (xy 4.018701 -242.045968)
			(xy 4.036655 -242.045968) (xy 4.045204 -242.043204) (xy 4.081915 -242.030252) (xy 4.157107 -242.010073)
			(xy 4.233775 -241.996541) (xy 4.311331 -241.98976) (xy 4.350258 -241.989356) (xy 4.389185 -241.98975)
			(xy 4.466742 -241.996534) (xy 4.543409 -242.01007) (xy 4.6186 -242.030255) (xy 4.655312 -242.043204)
			(xy 4.663861 -242.045968) (xy 4.681815 -242.045968) (xy 4.690364 -242.043204) (xy 4.727079 -242.030264)
			(xy 4.802269 -242.010081) (xy 4.878936 -241.996546) (xy 4.956492 -241.989762) (xy 4.995418 -241.989356)
			(xy 5.036525 -241.989834) (xy 5.118387 -241.997419) (xy 5.199201 -242.012522) (xy 5.278278 -242.035017)
			(xy 5.354941 -242.06471) (xy 5.428539 -242.10135) (xy 5.498442 -242.144622) (xy 5.564056 -242.194159)
			(xy 5.62482 -242.249538) (xy 5.680216 -242.310285) (xy 5.729772 -242.375885) (xy 5.773065 -242.445776)
			(xy 5.809725 -242.519363) (xy 5.839441 -242.596018) (xy 5.861959 -242.675087) (xy 5.877086 -242.755897)
			(xy 5.884694 -242.837757) (xy 5.88518 -242.878864) (xy 5.884763 -242.917154) (xy 5.878158 -242.993447)
			(xy 5.865012 -243.06889) (xy 5.845422 -243.142921) (xy 5.832856 -243.179092) (xy 5.830223 -243.187533)
			(xy 5.830211 -243.2052) (xy 5.832856 -243.213636) (xy 5.839714 -243.233448) (xy 5.84454 -243.247926)
			(xy 5.868162 -243.266722) (xy 5.991098 -243.277898) (xy 6.017768 -243.263674) (xy 6.025134 -243.250466)
			(xy 6.046357 -243.212807) (xy 6.095112 -243.141417) (xy 6.150562 -243.075093) (xy 6.212185 -243.014462)
			(xy 6.279399 -242.960095) (xy 6.35157 -242.912504) (xy 6.428018 -242.872139) (xy 6.508021 -242.839381)
			(xy 6.590824 -242.814539) (xy 6.675647 -242.797846) (xy 6.761689 -242.789461) (xy 6.804914 -242.788948)
			(xy 6.843846 -242.789385) (xy 6.921408 -242.796228) (xy 6.998076 -242.809824) (xy 7.073261 -242.830071)
			(xy 7.109968 -242.84305) (xy 7.118517 -242.845814) (xy 7.136471 -242.845814) (xy 7.14502 -242.84305)
			(xy 7.181726 -242.830069) (xy 7.256913 -242.809829) (xy 7.333581 -242.796233) (xy 7.411142 -242.789386)
			(xy 7.450074 -242.788948) (xy 7.489005 -242.789397) (xy 7.566568 -242.796236) (xy 7.643235 -242.809829)
			(xy 7.718421 -242.830072) (xy 7.755128 -242.84305) (xy 7.763677 -242.845814) (xy 7.781631 -242.845814)
			(xy 7.79018 -242.84305) (xy 7.82689 -242.83008) (xy 7.902075 -242.809837) (xy 7.978742 -242.796238)
			(xy 8.056303 -242.789388) (xy 8.095234 -242.788948) (xy 8.136013 -242.789411) (xy 8.217227 -242.796893)
			(xy 8.297415 -242.811775) (xy 8.375904 -242.833935) (xy 8.452036 -242.863185) (xy 8.525172 -242.899281)
			(xy 8.594697 -242.941918) (xy 8.660027 -242.99074) (xy 8.720615 -243.045336) (xy 8.775952 -243.105249)
			(xy 8.825574 -243.169974) (xy 8.869063 -243.238969) (xy 8.887968 -243.275104) (xy 8.895334 -243.289582)
			(xy 8.923782 -243.304568) (xy 9.051036 -243.28755) (xy 9.074658 -243.26596) (xy 9.07796 -243.249958)
			(xy 9.087414 -243.207692) (xy 9.113452 -243.125083) (xy 9.147396 -243.045396) (xy 9.188925 -242.969386)
			(xy 9.237644 -242.897772) (xy 9.293094 -242.831232) (xy 9.354748 -242.770397) (xy 9.422023 -242.715842)
			(xy 9.494283 -242.668084) (xy 9.570842 -242.627576) (xy 9.650975 -242.5947) (xy 9.733925 -242.569769)
			(xy 9.818905 -242.553018) (xy 9.90511 -242.544606) (xy 9.948418 -242.544092) (xy 9.994814 -242.544669)
			(xy 10.087102 -242.554315) (xy 10.177886 -242.573513) (xy 10.266179 -242.602053) (xy 10.308844 -242.620292)
			(xy 10.318786 -242.624098) (xy 10.34005 -242.624098) (xy 10.349992 -242.620292) (xy 10.392652 -242.602041)
			(xy 10.480945 -242.573499) (xy 10.571731 -242.554307) (xy 10.664022 -242.544676) (xy 10.710418 -242.544092)
			(xy 10.751224 -242.544561) (xy 10.832494 -242.552036) (xy 10.912738 -242.566922) (xy 10.991281 -242.589094)
			(xy 11.067464 -242.618366) (xy 11.140647 -242.654491) (xy 11.210213 -242.697166) (xy 11.27558 -242.746032)
			(xy 11.336197 -242.800678) (xy 11.364214 -242.83035) (xy 11.373612 -242.84051) (xy 11.398758 -242.848384)
			(xy 11.511026 -242.824508) (xy 11.530838 -242.806982) (xy 11.535156 -242.794028) (xy 11.549272 -242.753862)
			(xy 11.584191 -242.676207) (xy 11.626369 -242.602243) (xy 11.67542 -242.532648) (xy 11.730896 -242.468056)
			(xy 11.792289 -242.409061) (xy 11.859037 -242.3562) (xy 11.93053 -242.309958) (xy 12.006114 -242.270758)
			(xy 12.085097 -242.238958) (xy 12.166757 -242.21485) (xy 12.250347 -242.198653) (xy 12.335102 -242.190516)
			(xy 12.377674 -242.190016) (xy 12.418788 -242.190489) (xy 12.500666 -242.198077) (xy 12.581494 -242.213186)
			(xy 12.660584 -242.235689) (xy 12.737259 -242.265394) (xy 12.810867 -242.302047) (xy 12.880779 -242.345334)
			(xy 12.946399 -242.394888) (xy 13.007166 -242.450285) (xy 13.062563 -242.511053) (xy 13.112117 -242.576673)
			(xy 13.155404 -242.646585) (xy 13.192057 -242.720193) (xy 13.221761 -242.796868) (xy 13.244264 -242.875958)
			(xy 13.259374 -242.956786) (xy 13.266961 -243.038664) (xy 13.267436 -243.079778) (xy 13.267025 -243.118068)
			(xy 13.260419 -243.194362) (xy 13.247271 -243.269804) (xy 13.227679 -243.343835) (xy 13.215112 -243.380006)
			(xy 13.212473 -243.388446) (xy 13.212466 -243.406113) (xy 13.215112 -243.41455) (xy 13.227652 -243.450729)
			(xy 13.247226 -243.524761) (xy 13.260374 -243.600201) (xy 13.267 -243.67649) (xy 13.267436 -243.714778)
			(xy 13.266846 -243.759) (xy 13.258017 -243.847003) (xy 13.240503 -243.933696) (xy 13.214478 -244.018225)
			(xy 13.19784 -244.059202) (xy 13.194714 -244.067772) (xy 13.194063 -244.085991) (xy 13.19657 -244.094762)
			(xy 13.211007 -244.140085) (xy 13.231231 -244.233036) (xy 13.239913 -244.31371) (xy 34.233104 -244.31371)
			(xy 34.233494 -244.275426) (xy 34.240032 -244.199137) (xy 34.253113 -244.123695) (xy 34.272639 -244.049658)
			(xy 34.285174 -244.013482) (xy 34.287819 -244.005044) (xy 34.287822 -243.987375) (xy 34.285174 -243.978938)
			(xy 34.272652 -243.942758) (xy 34.253143 -243.868719) (xy 34.240062 -243.793278) (xy 34.233506 -243.716993)
			(xy 34.233104 -243.67871) (xy 34.233622 -243.637604) (xy 34.241205 -243.555744) (xy 34.256307 -243.474932)
			(xy 34.2788 -243.395857) (xy 34.308492 -243.319195) (xy 34.345129 -243.245599) (xy 34.388399 -243.175696)
			(xy 34.437933 -243.110083) (xy 34.493309 -243.04932) (xy 34.554054 -242.993924) (xy 34.61965 -242.944368)
			(xy 34.689538 -242.901074) (xy 34.763122 -242.864412) (xy 34.839775 -242.834695) (xy 34.918841 -242.812176)
			(xy 34.999648 -242.797046) (xy 35.081507 -242.789436) (xy 35.122612 -242.788948) (xy 35.161544 -242.789386)
			(xy 35.239106 -242.796228) (xy 35.315774 -242.809825) (xy 35.390959 -242.830071) (xy 35.427666 -242.84305)
			(xy 35.436215 -242.845814) (xy 35.454169 -242.845814) (xy 35.462718 -242.84305) (xy 35.499424 -242.830069)
			(xy 35.574611 -242.809829) (xy 35.651279 -242.796234) (xy 35.72884 -242.789386) (xy 35.767772 -242.788948)
			(xy 35.806703 -242.789398) (xy 35.884266 -242.796237) (xy 35.960933 -242.80983) (xy 36.036119 -242.830072)
			(xy 36.072826 -242.84305) (xy 36.081375 -242.845814) (xy 36.099329 -242.845814) (xy 36.107878 -242.84305)
			(xy 36.144588 -242.830081) (xy 36.219774 -242.809837) (xy 36.29644 -242.796239) (xy 36.374001 -242.789388)
			(xy 36.412932 -242.788948) (xy 36.454042 -242.789422) (xy 36.535911 -242.797012) (xy 36.616729 -242.812125)
			(xy 36.695809 -242.834631) (xy 36.733923 -242.8494) (xy 44.997624 -242.8494) (xy 44.998043 -242.809633)
			(xy 45.005083 -242.730411) (xy 45.01917 -242.652134) (xy 45.040191 -242.575428) (xy 45.067978 -242.500906)
			(xy 45.084746 -242.464844) (xy 45.089077 -242.454343) (xy 45.089077 -242.431657) (xy 45.084746 -242.421156)
			(xy 45.068005 -242.385083) (xy 45.040224 -242.31056) (xy 45.019201 -242.233857) (xy 45.005104 -242.155584)
			(xy 44.998046 -242.076366) (xy 44.997624 -242.0366) (xy 44.998052 -241.995496) (xy 45.005638 -241.913638)
			(xy 45.020744 -241.83283) (xy 45.043241 -241.75376) (xy 45.072939 -241.677104) (xy 45.109583 -241.603514)
			(xy 45.152861 -241.53362) (xy 45.202404 -241.468017) (xy 45.257788 -241.407265) (xy 45.318542 -241.351883)
			(xy 45.384146 -241.302343) (xy 45.454042 -241.259068) (xy 45.527633 -241.222426) (xy 45.604291 -241.192731)
			(xy 45.683361 -241.170236) (xy 45.76417 -241.155133) (xy 45.846028 -241.147551) (xy 45.887132 -241.147092)
			(xy 45.928456 -241.147551) (xy 46.010751 -241.155163) (xy 46.091986 -241.170375) (xy 46.17146 -241.193055)
			(xy 46.248489 -241.223009) (xy 46.285658 -241.241072) (xy 46.295718 -241.245566) (xy 46.317716 -241.24635)
			(xy 46.328076 -241.242596) (xy 46.369278 -241.225801) (xy 46.454293 -241.199539) (xy 46.541505 -241.181888)
			(xy 46.630042 -241.173025) (xy 46.674532 -241.172492) (xy 46.715492 -241.17292) (xy 46.797069 -241.180391)
			(xy 46.877612 -241.195338) (xy 46.956438 -241.217636) (xy 46.994826 -241.231928) (xy 47.004522 -241.235225)
			(xy 47.024976 -241.234552) (xy 47.03445 -241.230658) (xy 47.069871 -241.214574) (xy 47.142968 -241.187937)
			(xy 47.218112 -241.167784) (xy 47.294728 -241.154269) (xy 47.372232 -241.147496) (xy 47.411132 -241.147092)
			(xy 47.452235 -241.147536) (xy 47.53409 -241.155124) (xy 47.614896 -241.170232) (xy 47.693963 -241.192731)
			(xy 47.770617 -241.222429) (xy 47.844204 -241.259074) (xy 47.914096 -241.302351) (xy 47.979697 -241.351893)
			(xy 48.040447 -241.407276) (xy 48.095828 -241.468028) (xy 48.145367 -241.53363) (xy 48.188642 -241.603524)
			(xy 48.225284 -241.677112) (xy 48.254979 -241.753767) (xy 48.277476 -241.832835) (xy 48.292581 -241.913642)
			(xy 48.300165 -241.995497) (xy 48.30064 -242.0366) (xy 48.300225 -242.076368) (xy 48.293184 -242.15559)
			(xy 48.279097 -242.233866) (xy 48.258075 -242.310572) (xy 48.230286 -242.385094) (xy 48.213518 -242.421156)
			(xy 48.209183 -242.431657) (xy 48.209183 -242.454343) (xy 48.213518 -242.464844) (xy 48.230264 -242.500915)
			(xy 48.258043 -242.575438) (xy 48.279064 -242.652142) (xy 48.29316 -242.730415) (xy 48.300218 -242.809634)
			(xy 48.30064 -242.8494) (xy 48.300133 -242.890502) (xy 48.292549 -242.972354) (xy 48.277444 -243.053158)
			(xy 48.254949 -243.132223) (xy 48.225254 -243.208875) (xy 48.188614 -243.282461) (xy 48.145341 -243.352352)
			(xy 48.095803 -243.417952) (xy 48.040424 -243.478702) (xy 47.979677 -243.534083) (xy 47.914078 -243.583623)
			(xy 47.844189 -243.626899) (xy 47.770604 -243.663541) (xy 47.693953 -243.693239) (xy 47.614889 -243.715737)
			(xy 47.534086 -243.730844) (xy 47.452234 -243.738432) (xy 47.411132 -243.738908) (xy 47.370172 -243.738491)
			(xy 47.288594 -243.731017) (xy 47.208051 -243.716067) (xy 47.129226 -243.693765) (xy 47.090838 -243.679472)
			(xy 47.081132 -243.676212) (xy 47.060688 -243.676861) (xy 47.051214 -243.680742) (xy 47.015798 -243.696839)
			(xy 46.9427 -243.723473) (xy 46.867555 -243.743624) (xy 46.790937 -243.757135) (xy 46.713432 -243.763905)
			(xy 46.674532 -243.764308) (xy 46.633208 -243.763863) (xy 46.550912 -243.756248) (xy 46.469677 -243.741033)
			(xy 46.390203 -243.718349) (xy 46.313175 -243.688393) (xy 46.276006 -243.670328) (xy 46.265932 -243.665873)
			(xy 46.243947 -243.665065) (xy 46.233588 -243.668804) (xy 46.192391 -243.685611) (xy 46.107373 -243.71187)
			(xy 46.020161 -243.729517) (xy 45.931622 -243.738377) (xy 45.887132 -243.738908) (xy 45.846029 -243.738417)
			(xy 45.764175 -243.730835) (xy 45.683368 -243.715733) (xy 45.604301 -243.693238) (xy 45.527646 -243.663544)
			(xy 45.454058 -243.626904) (xy 45.384164 -243.58363) (xy 45.318562 -243.534092) (xy 45.257811 -243.478712)
			(xy 45.202428 -243.417962) (xy 45.152888 -243.352362) (xy 45.109611 -243.28247) (xy 45.072968 -243.208884)
			(xy 45.043272 -243.13223) (xy 45.020775 -243.053163) (xy 45.005669 -242.972357) (xy 44.998084 -242.890503)
			(xy 44.997624 -242.8494) (xy 36.733923 -242.8494) (xy 36.772474 -242.864338) (xy 36.846071 -242.900994)
			(xy 36.915971 -242.944284) (xy 36.981578 -242.993841) (xy 37.042332 -243.04924) (xy 37.097714 -243.110009)
			(xy 37.147252 -243.175629) (xy 37.190524 -243.245541) (xy 37.227159 -243.319147) (xy 37.256846 -243.395821)
			(xy 37.279331 -243.474906) (xy 37.294421 -243.555729) (xy 37.301989 -243.6376) (xy 37.30244 -243.67871)
			(xy 37.302053 -243.716994) (xy 37.295514 -243.793283) (xy 37.282432 -243.868725) (xy 37.262905 -243.942762)
			(xy 37.25037 -243.978938) (xy 37.247713 -243.987373) (xy 37.247717 -244.005045) (xy 37.25037 -244.013482)
			(xy 37.262871 -244.049668) (xy 37.282385 -244.123705) (xy 37.295472 -244.199144) (xy 37.302035 -244.275427)
			(xy 37.30244 -244.31371) (xy 37.301997 -244.354818) (xy 37.294412 -244.436682) (xy 37.279306 -244.517498)
			(xy 37.25681 -244.596575) (xy 37.227114 -244.67324) (xy 37.190473 -244.746838) (xy 37.147198 -244.816743)
			(xy 37.097659 -244.882357) (xy 37.042278 -244.943121) (xy 36.981528 -244.998517) (xy 36.915926 -245.048073)
			(xy 36.846033 -245.091365) (xy 36.801488 -245.113556) (xy 37.48532 -245.113556) (xy 37.485699 -245.075271)
			(xy 37.492241 -244.998983) (xy 37.505325 -244.92354) (xy 37.524854 -244.849504) (xy 37.53739 -244.813328)
			(xy 37.540061 -244.804897) (xy 37.540047 -244.787221) (xy 37.53739 -244.778784) (xy 37.524882 -244.7426)
			(xy 37.505369 -244.668562) (xy 37.492284 -244.593123) (xy 37.485724 -244.516839) (xy 37.48532 -244.478556)
			(xy 37.485725 -244.437452) (xy 37.493314 -244.355595) (xy 37.508423 -244.274787) (xy 37.530924 -244.195718)
			(xy 37.560625 -244.119063) (xy 37.597271 -244.045475) (xy 37.640551 -243.975582) (xy 37.690096 -243.909981)
			(xy 37.745481 -243.84923) (xy 37.806236 -243.79385) (xy 37.871841 -243.744311) (xy 37.941738 -243.701036)
			(xy 38.015329 -243.664396) (xy 38.091987 -243.634701) (xy 38.171057 -243.612207) (xy 38.251866 -243.597104)
			(xy 38.333724 -243.589521) (xy 38.374828 -243.589048) (xy 38.413754 -243.589452) (xy 38.491311 -243.596232)
			(xy 38.567979 -243.609766) (xy 38.64317 -243.629948) (xy 38.679882 -243.642896) (xy 38.688431 -243.64566)
			(xy 38.706385 -243.64566) (xy 38.714934 -243.642896) (xy 38.751642 -243.629935) (xy 38.826835 -243.609758)
			(xy 38.903504 -243.596229) (xy 38.981061 -243.589451) (xy 39.019988 -243.589048) (xy 39.058914 -243.589464)
			(xy 39.136471 -243.596241) (xy 39.213138 -243.609771) (xy 39.288329 -243.62995) (xy 39.325042 -243.642896)
			(xy 39.333591 -243.64566) (xy 39.351545 -243.64566) (xy 39.360094 -243.642896) (xy 39.396806 -243.629947)
			(xy 39.471997 -243.609767) (xy 39.548665 -243.596234) (xy 39.626222 -243.589453) (xy 39.665148 -243.589048)
			(xy 39.70625 -243.589521) (xy 39.788103 -243.59711) (xy 39.868907 -243.612218) (xy 39.947972 -243.634717)
			(xy 40.024624 -243.664415) (xy 40.098209 -243.701058) (xy 40.1681 -243.744334) (xy 40.233699 -243.793874)
			(xy 40.294448 -243.849254) (xy 40.349829 -243.910004) (xy 40.399368 -243.975604) (xy 40.442644 -244.045494)
			(xy 40.479287 -244.11908) (xy 40.508984 -244.195732) (xy 40.531483 -244.274797) (xy 40.535672 -244.2972)
			(xy 40.983872 -244.2972) (xy 40.987902 -244.212596) (xy 40.999957 -244.128757) (xy 41.019926 -244.046445)
			(xy 41.047629 -243.966403) (xy 41.082816 -243.889357) (xy 41.125167 -243.816005) (xy 41.174299 -243.747011)
			(xy 41.229767 -243.682999) (xy 41.291069 -243.62455) (xy 41.357649 -243.572193) (xy 41.428904 -243.526402)
			(xy 41.50419 -243.487592) (xy 41.582824 -243.456115) (xy 41.664094 -243.432254) (xy 41.747265 -243.416227)
			(xy 41.831582 -243.408179) (xy 41.873932 -243.407692) (xy 41.920327 -243.408299) (xy 42.012615 -243.417937)
			(xy 42.103398 -243.437126) (xy 42.191693 -243.465657) (xy 42.234358 -243.483892) (xy 42.2443 -243.487698)
			(xy 42.265564 -243.487698) (xy 42.275506 -243.483892) (xy 42.318164 -243.465637) (xy 42.406458 -243.437095)
			(xy 42.497244 -243.417905) (xy 42.589536 -243.408275) (xy 42.635932 -243.407692) (xy 42.67828 -243.408197)
			(xy 42.762591 -243.416251) (xy 42.845755 -243.432282) (xy 42.927018 -243.456146) (xy 43.005646 -243.487626)
			(xy 43.080925 -243.526437) (xy 43.152174 -243.572228) (xy 43.218747 -243.624585) (xy 43.280043 -243.683032)
			(xy 43.335505 -243.747041) (xy 43.384632 -243.816033) (xy 43.426979 -243.889381) (xy 43.462162 -243.966423)
			(xy 43.489862 -244.04646) (xy 43.50983 -244.128768) (xy 43.521883 -244.212601) (xy 43.525913 -244.2972)
			(xy 43.521883 -244.381799) (xy 43.50983 -244.465632) (xy 43.489862 -244.54794) (xy 43.462162 -244.627977)
			(xy 43.426979 -244.705019) (xy 43.384632 -244.778367) (xy 43.335505 -244.847359) (xy 43.280043 -244.911368)
			(xy 43.218747 -244.969815) (xy 43.152174 -245.022172) (xy 43.080925 -245.067963) (xy 43.005646 -245.106774)
			(xy 42.927018 -245.138254) (xy 42.845755 -245.162118) (xy 42.762591 -245.178149) (xy 42.67828 -245.186203)
			(xy 42.635932 -245.186708) (xy 42.589537 -245.186114) (xy 42.497249 -245.176472) (xy 42.406465 -245.157279)
			(xy 42.318171 -245.128744) (xy 42.275506 -245.110508) (xy 42.265564 -245.106702) (xy 42.2443 -245.106702)
			(xy 42.234358 -245.110508) (xy 42.191691 -245.128742) (xy 42.103401 -245.157289) (xy 42.012617 -245.176485)
			(xy 41.920328 -245.186121) (xy 41.873932 -245.186708) (xy 41.831582 -245.186221) (xy 41.747265 -245.178173)
			(xy 41.664094 -245.162146) (xy 41.582824 -245.138285) (xy 41.50419 -245.106808) (xy 41.428904 -245.067998)
			(xy 41.357649 -245.022207) (xy 41.291069 -244.96985) (xy 41.229767 -244.911401) (xy 41.174299 -244.847389)
			(xy 41.125167 -244.778395) (xy 41.082816 -244.705043) (xy 41.047629 -244.627997) (xy 41.019926 -244.547955)
			(xy 40.999957 -244.465643) (xy 40.987902 -244.381804) (xy 40.983872 -244.2972) (xy 40.535672 -244.2972)
			(xy 40.546591 -244.355601) (xy 40.554179 -244.437454) (xy 40.554656 -244.478556) (xy 40.554282 -244.516841)
			(xy 40.547738 -244.593129) (xy 40.534653 -244.668572) (xy 40.515123 -244.742608) (xy 40.502586 -244.778784)
			(xy 40.499956 -244.787226) (xy 40.499941 -244.804892) (xy 40.502586 -244.813328) (xy 40.515097 -244.849511)
			(xy 40.534609 -244.923549) (xy 40.547693 -244.998989) (xy 40.554252 -245.075273) (xy 40.554656 -245.113556)
			(xy 40.554091 -245.154656) (xy 40.546511 -245.236507) (xy 40.531411 -245.317309) (xy 40.508919 -245.396372)
			(xy 40.479229 -245.473024) (xy 40.442593 -245.546609) (xy 40.399323 -245.616499) (xy 40.34979 -245.682099)
			(xy 40.294414 -245.742849) (xy 40.23367 -245.798231) (xy 40.168075 -245.847771) (xy 40.098189 -245.891048)
			(xy 40.024608 -245.927692) (xy 39.94796 -245.95739) (xy 39.868898 -245.97989) (xy 39.788098 -245.994998)
			(xy 39.706248 -246.002587) (xy 39.665148 -246.003064) (xy 39.625578 -246.00265) (xy 39.54675 -245.995641)
			(xy 39.468856 -245.981657) (xy 39.392513 -245.960808) (xy 39.355268 -245.947438) (xy 39.346599 -245.944608)
			(xy 39.328377 -245.944608) (xy 39.319708 -245.947438) (xy 39.282465 -245.960813) (xy 39.206121 -245.981658)
			(xy 39.128226 -245.995639) (xy 39.049398 -246.002645) (xy 39.009828 -246.003064) (xy 38.971543 -246.002694)
			(xy 38.895254 -245.996149) (xy 38.819812 -245.983063) (xy 38.745776 -245.963531) (xy 38.7096 -245.950994)
			(xy 38.701163 -245.948343) (xy 38.683493 -245.948343) (xy 38.675056 -245.950994) (xy 38.638874 -245.96351)
			(xy 38.564836 -245.98302) (xy 38.489396 -245.996103) (xy 38.413111 -246.002661) (xy 38.374828 -246.003064)
			(xy 38.333724 -246.002621) (xy 38.251867 -245.995038) (xy 38.171058 -245.979934) (xy 38.091988 -245.957438)
			(xy 38.015331 -245.927742) (xy 37.941741 -245.8911) (xy 37.871846 -245.847823) (xy 37.806243 -245.798281)
			(xy 37.745491 -245.742898) (xy 37.690108 -245.682145) (xy 37.640568 -245.616541) (xy 37.597293 -245.546645)
			(xy 37.560651 -245.473055) (xy 37.530957 -245.396397) (xy 37.508462 -245.317326) (xy 37.49336 -245.236518)
			(xy 37.485778 -245.15466) (xy 37.48532 -245.113556) (xy 36.801488 -245.113556) (xy 36.772443 -245.128025)
			(xy 36.695786 -245.157739) (xy 36.616714 -245.180255) (xy 36.535902 -245.195381) (xy 36.454039 -245.202987)
			(xy 36.412932 -245.203472) (xy 36.373357 -245.203012) (xy 36.294524 -245.195946) (xy 36.21663 -245.181902)
			(xy 36.140292 -245.160992) (xy 36.103052 -245.147592) (xy 36.094383 -245.144762) (xy 36.076161 -245.144762)
			(xy 36.067492 -245.147592) (xy 36.030254 -245.160998) (xy 35.953915 -245.181902) (xy 35.87602 -245.195946)
			(xy 35.797187 -245.203018) (xy 35.757612 -245.203472) (xy 35.719322 -245.203063) (xy 35.643028 -245.196456)
			(xy 35.567586 -245.183308) (xy 35.493555 -245.163716) (xy 35.457384 -245.151148) (xy 35.448947 -245.148497)
			(xy 35.431277 -245.148497) (xy 35.42284 -245.151148) (xy 35.386663 -245.163693) (xy 35.31263 -245.183265)
			(xy 35.23719 -245.196412) (xy 35.1609 -245.203036) (xy 35.122612 -245.203472) (xy 35.081501 -245.203036)
			(xy 34.999628 -245.195449) (xy 34.918806 -245.180338) (xy 34.839723 -245.157833) (xy 34.763054 -245.128126)
			(xy 34.689454 -245.09147) (xy 34.619551 -245.048177) (xy 34.553942 -244.998619) (xy 34.493187 -244.943216)
			(xy 34.437804 -244.882444) (xy 34.388265 -244.816819) (xy 34.344995 -244.746903) (xy 34.308362 -244.673292)
			(xy 34.278678 -244.596614) (xy 34.256198 -244.517523) (xy 34.241113 -244.436696) (xy 34.233551 -244.354822)
			(xy 34.233104 -244.31371) (xy 13.239913 -244.31371) (xy 13.241409 -244.327615) (xy 13.242036 -244.375178)
			(xy 13.241625 -244.413468) (xy 13.235019 -244.489762) (xy 13.221871 -244.565204) (xy 13.202279 -244.639235)
			(xy 13.189712 -244.675406) (xy 13.187073 -244.683846) (xy 13.187066 -244.701513) (xy 13.189712 -244.70995)
			(xy 13.202252 -244.746129) (xy 13.221826 -244.820161) (xy 13.234974 -244.895601) (xy 13.2416 -244.97189)
			(xy 13.242036 -245.010178) (xy 13.2416 -245.050088) (xy 13.234447 -245.129586) (xy 13.220204 -245.208124)
			(xy 13.198987 -245.285072) (xy 13.185394 -245.322598) (xy 13.182566 -245.331268) (xy 13.182559 -245.349491)
			(xy 13.185394 -245.358158) (xy 13.198976 -245.395688) (xy 13.220195 -245.472634) (xy 13.234438 -245.551171)
			(xy 13.241589 -245.630669) (xy 13.242036 -245.670578) (xy 13.241625 -245.708868) (xy 13.235019 -245.785162)
			(xy 13.221871 -245.860604) (xy 13.202279 -245.934635) (xy 13.189712 -245.970806) (xy 13.187073 -245.979246)
			(xy 13.187066 -245.996913) (xy 13.189712 -246.00535) (xy 13.202252 -246.041529) (xy 13.221826 -246.115561)
			(xy 13.223645 -246.126) (xy 44.997072 -246.126) (xy 45.001102 -246.041396) (xy 45.013157 -245.957557)
			(xy 45.033126 -245.875245) (xy 45.060829 -245.795203) (xy 45.096016 -245.718157) (xy 45.138367 -245.644805)
			(xy 45.187499 -245.575811) (xy 45.242967 -245.511799) (xy 45.304269 -245.45335) (xy 45.370849 -245.400993)
			(xy 45.442104 -245.355202) (xy 45.51739 -245.316392) (xy 45.596024 -245.284915) (xy 45.677294 -245.261054)
			(xy 45.760465 -245.245027) (xy 45.844782 -245.236979) (xy 45.887132 -245.236492) (xy 45.928456 -245.236951)
			(xy 46.010751 -245.244563) (xy 46.091986 -245.259775) (xy 46.17146 -245.282455) (xy 46.248489 -245.312409)
			(xy 46.285658 -245.330472) (xy 46.295718 -245.334966) (xy 46.317716 -245.33575) (xy 46.328076 -245.331996)
			(xy 46.369278 -245.315201) (xy 46.454293 -245.288939) (xy 46.541505 -245.271288) (xy 46.630042 -245.262425)
			(xy 46.674532 -245.261892) (xy 46.715492 -245.26232) (xy 46.797069 -245.269791) (xy 46.877612 -245.284738)
			(xy 46.956438 -245.307036) (xy 46.994826 -245.321328) (xy 47.004522 -245.324625) (xy 47.024976 -245.323952)
			(xy 47.03445 -245.320058) (xy 47.069871 -245.303974) (xy 47.142968 -245.277337) (xy 47.218112 -245.257184)
			(xy 47.294728 -245.243669) (xy 47.372232 -245.236896) (xy 47.411132 -245.236492) (xy 47.45348 -245.236997)
			(xy 47.537791 -245.245051) (xy 47.620955 -245.261082) (xy 47.702218 -245.284946) (xy 47.780846 -245.316426)
			(xy 47.856125 -245.355237) (xy 47.927374 -245.401028) (xy 47.993947 -245.453385) (xy 48.055243 -245.511832)
			(xy 48.110705 -245.575841) (xy 48.159832 -245.644833) (xy 48.202179 -245.718181) (xy 48.237362 -245.795223)
			(xy 48.265062 -245.87526) (xy 48.28503 -245.957568) (xy 48.297083 -246.041401) (xy 48.301113 -246.126)
			(xy 48.297083 -246.210599) (xy 48.28503 -246.294432) (xy 48.265062 -246.37674) (xy 48.237362 -246.456777)
			(xy 48.202179 -246.533819) (xy 48.159832 -246.607167) (xy 48.110705 -246.676159) (xy 48.055243 -246.740168)
			(xy 47.993947 -246.798615) (xy 47.927374 -246.850972) (xy 47.856125 -246.896763) (xy 47.780846 -246.935574)
			(xy 47.702218 -246.967054) (xy 47.620955 -246.990918) (xy 47.537791 -247.006949) (xy 47.45348 -247.015003)
			(xy 47.411132 -247.015508) (xy 47.370172 -247.015091) (xy 47.288594 -247.007617) (xy 47.208051 -246.992667)
			(xy 47.129226 -246.970365) (xy 47.090838 -246.956072) (xy 47.081132 -246.952812) (xy 47.060688 -246.953461)
			(xy 47.051214 -246.957342) (xy 47.015798 -246.973439) (xy 46.9427 -247.000073) (xy 46.867555 -247.020224)
			(xy 46.790937 -247.033735) (xy 46.713432 -247.040505) (xy 46.674532 -247.040908) (xy 46.633208 -247.040463)
			(xy 46.550912 -247.032848) (xy 46.469677 -247.017633) (xy 46.390203 -246.994949) (xy 46.313175 -246.964993)
			(xy 46.276006 -246.946928) (xy 46.265932 -246.942473) (xy 46.243947 -246.941665) (xy 46.233588 -246.945404)
			(xy 46.192391 -246.962211) (xy 46.107373 -246.98847) (xy 46.020161 -247.006117) (xy 45.931622 -247.014977)
			(xy 45.887132 -247.015508) (xy 45.844782 -247.015021) (xy 45.760465 -247.006973) (xy 45.677294 -246.990946)
			(xy 45.596024 -246.967085) (xy 45.51739 -246.935608) (xy 45.442104 -246.896798) (xy 45.370849 -246.851007)
			(xy 45.304269 -246.79865) (xy 45.242967 -246.740201) (xy 45.187499 -246.676189) (xy 45.138367 -246.607195)
			(xy 45.096016 -246.533843) (xy 45.060829 -246.456797) (xy 45.033126 -246.376755) (xy 45.013157 -246.294443)
			(xy 45.001102 -246.210604) (xy 44.997072 -246.126) (xy 13.223645 -246.126) (xy 13.234974 -246.191001)
			(xy 13.2416 -246.26729) (xy 13.242036 -246.305578) (xy 13.241386 -246.353139) (xy 13.231193 -246.447714)
			(xy 13.210984 -246.540665) (xy 13.19657 -246.585994) (xy 13.194034 -246.594763) (xy 13.194681 -246.61299)
			(xy 13.19784 -246.621554) (xy 13.214499 -246.662524) (xy 13.240533 -246.747053) (xy 13.258047 -246.833748)
			(xy 13.266869 -246.921755) (xy 13.267436 -246.965978) (xy 13.267025 -247.004268) (xy 13.260419 -247.080562)
			(xy 13.247271 -247.156004) (xy 13.227679 -247.230035) (xy 13.215112 -247.266206) (xy 13.212473 -247.274646)
			(xy 13.212466 -247.292313) (xy 13.215112 -247.30075) (xy 13.227652 -247.336929) (xy 13.247226 -247.410961)
			(xy 13.260374 -247.486401) (xy 13.267 -247.56269) (xy 13.267436 -247.600978) (xy 13.266932 -247.643339)
			(xy 13.258879 -247.727676) (xy 13.242845 -247.810866) (xy 13.218977 -247.892156) (xy 13.187489 -247.970808)
			(xy 13.148667 -248.046111) (xy 13.102864 -248.117383) (xy 13.050493 -248.183979) (xy 12.992028 -248.245294)
			(xy 12.928 -248.300775) (xy 12.858988 -248.349918) (xy 12.785618 -248.392278) (xy 12.708553 -248.427473)
			(xy 12.628491 -248.455182) (xy 12.546158 -248.475156) (xy 12.462299 -248.487213) (xy 12.377674 -248.491245)
			(xy 12.293049 -248.487213) (xy 12.20919 -248.475156) (xy 12.126857 -248.455182) (xy 12.046795 -248.427473)
			(xy 11.96973 -248.392278) (xy 11.89636 -248.349918) (xy 11.827348 -248.300775) (xy 11.76332 -248.245294)
			(xy 11.704855 -248.183979) (xy 11.652484 -248.117383) (xy 11.606681 -248.046111) (xy 11.567859 -247.970808)
			(xy 11.536371 -247.892156) (xy 11.512503 -247.810866) (xy 11.496469 -247.727676) (xy 11.488416 -247.643339)
			(xy 11.487912 -247.600978) (xy 11.488312 -247.562688) (xy 11.494922 -247.486394) (xy 11.508073 -247.410951)
			(xy 11.527667 -247.336921) (xy 11.540236 -247.30075) (xy 11.542898 -247.292316) (xy 11.542891 -247.274643)
			(xy 11.540236 -247.266206) (xy 11.527681 -247.230032) (xy 11.508111 -247.155998) (xy 11.494968 -247.080557)
			(xy 11.488346 -247.004266) (xy 11.487912 -246.965978) (xy 11.488553 -246.918417) (xy 11.498751 -246.823842)
			(xy 11.518963 -246.730891) (xy 11.533378 -246.685562) (xy 11.535934 -246.676798) (xy 11.535273 -246.658566)
			(xy 11.532108 -246.650002) (xy 11.515464 -246.609027) (xy 11.489427 -246.5245) (xy 11.471908 -246.437806)
			(xy 11.463082 -246.349801) (xy 11.462512 -246.305578) (xy 11.462912 -246.267288) (xy 11.469522 -246.190994)
			(xy 11.482673 -246.115551) (xy 11.502267 -246.041521) (xy 11.514836 -246.00535) (xy 11.517498 -245.996916)
			(xy 11.517491 -245.979243) (xy 11.514836 -245.970806) (xy 11.502281 -245.934632) (xy 11.482711 -245.860598)
			(xy 11.469568 -245.785157) (xy 11.462946 -245.708866) (xy 11.462512 -245.670578) (xy 11.462968 -245.630669)
			(xy 11.470116 -245.551171) (xy 11.484353 -245.472633) (xy 11.505564 -245.395685) (xy 11.519154 -245.358158)
			(xy 11.522007 -245.349494) (xy 11.522 -245.331265) (xy 11.519154 -245.322598) (xy 11.505557 -245.285074)
			(xy 11.484342 -245.208125) (xy 11.470104 -245.129586) (xy 11.462957 -245.050088) (xy 11.462512 -245.010178)
			(xy 11.462912 -244.971888) (xy 11.469522 -244.895594) (xy 11.482673 -244.820151) (xy 11.502267 -244.746121)
			(xy 11.514836 -244.70995) (xy 11.517498 -244.701516) (xy 11.517491 -244.683843) (xy 11.514836 -244.675406)
			(xy 11.502281 -244.639232) (xy 11.482711 -244.565198) (xy 11.469568 -244.489757) (xy 11.462946 -244.413466)
			(xy 11.462512 -244.375178) (xy 11.463091 -244.330956) (xy 11.471924 -244.242953) (xy 11.489441 -244.156259)
			(xy 11.515469 -244.07173) (xy 11.532108 -244.030754) (xy 11.535258 -244.022191) (xy 11.535895 -244.003966)
			(xy 11.533378 -243.995194) (xy 11.533378 -243.99494) (xy 11.530034 -243.986358) (xy 11.518403 -243.972098)
			(xy 11.502505 -243.962831) (xy 11.4935 -243.960904) (xy 11.465052 -243.956078) (xy 11.455924 -243.954901)
			(xy 11.437871 -243.958431) (xy 11.422217 -243.968089) (xy 11.416284 -243.975128) (xy 11.391096 -244.007189)
			(xy 11.335751 -244.067065) (xy 11.275157 -244.121624) (xy 11.209823 -244.170407) (xy 11.140298 -244.213004)
			(xy 11.067165 -244.249058) (xy 10.991039 -244.278267) (xy 10.912559 -244.300383) (xy 10.832384 -244.315223)
			(xy 10.751187 -244.322661) (xy 10.710418 -244.323108) (xy 10.664023 -244.322519) (xy 10.571734 -244.312876)
			(xy 10.480951 -244.293681) (xy 10.392657 -244.265145) (xy 10.349992 -244.246908) (xy 10.34005 -244.243102)
			(xy 10.318786 -244.243102) (xy 10.308844 -244.246908) (xy 10.266179 -244.265147) (xy 10.177888 -244.293692)
			(xy 10.087104 -244.312887) (xy 9.994814 -244.322522) (xy 9.948418 -244.323108) (xy 9.907644 -244.32266)
			(xy 9.826438 -244.315206) (xy 9.746255 -244.300349) (xy 9.667768 -244.278214) (xy 9.591638 -244.248988)
			(xy 9.518502 -244.212915) (xy 9.448976 -244.170299) (xy 9.383643 -244.121497) (xy 9.323052 -244.066919)
			(xy 9.267711 -244.007024) (xy 9.218085 -243.942315) (xy 9.174592 -243.873334) (xy 9.155684 -243.837206)
			(xy 9.148318 -243.822728) (xy 9.11987 -243.807742) (xy 8.992616 -243.82476) (xy 8.968994 -243.84635)
			(xy 8.965692 -243.862352) (xy 8.959187 -243.891967) (xy 8.942666 -243.950312) (xy 8.932672 -243.978938)
			(xy 8.930015 -243.987373) (xy 8.930019 -244.005045) (xy 8.932672 -244.013482) (xy 8.94522 -244.049658)
			(xy 8.964792 -244.123692) (xy 8.977938 -244.199132) (xy 8.984561 -244.275422) (xy 8.984996 -244.31371)
			(xy 8.984517 -244.354824) (xy 8.97693 -244.436702) (xy 8.961821 -244.51753) (xy 8.939318 -244.596619)
			(xy 8.909614 -244.673294) (xy 8.872962 -244.746902) (xy 8.829674 -244.816814) (xy 8.780121 -244.882434)
			(xy 8.724724 -244.943201) (xy 8.663957 -244.998598) (xy 8.598337 -245.048152) (xy 8.528426 -245.09144)
			(xy 8.454818 -245.128092) (xy 8.378143 -245.157797) (xy 8.299054 -245.1803) (xy 8.218226 -245.19541)
			(xy 8.136348 -245.202997) (xy 8.095234 -245.203472) (xy 8.055659 -245.203011) (xy 7.976826 -245.195945)
			(xy 7.898932 -245.181902) (xy 7.822594 -245.160992) (xy 7.785354 -245.147592) (xy 7.776685 -245.144762)
			(xy 7.758463 -245.144762) (xy 7.749794 -245.147592) (xy 7.712556 -245.160997) (xy 7.636216 -245.181901)
			(xy 7.558322 -245.195945) (xy 7.479489 -245.203018) (xy 7.439914 -245.203472) (xy 7.401624 -245.203062)
			(xy 7.32533 -245.196455) (xy 7.249888 -245.183307) (xy 7.175857 -245.163715) (xy 7.139686 -245.151148)
			(xy 7.131249 -245.148497) (xy 7.113579 -245.148497) (xy 7.105142 -245.151148) (xy 7.068965 -245.163692)
			(xy 6.994931 -245.183265) (xy 6.919492 -245.196412) (xy 6.843202 -245.203036) (xy 6.804914 -245.203472)
			(xy 6.763799 -245.203008) (xy 6.68192 -245.195421) (xy 6.601091 -245.180312) (xy 6.522 -245.157809)
			(xy 6.445323 -245.128104) (xy 6.371714 -245.091451) (xy 6.301801 -245.048163) (xy 6.23618 -244.998609)
			(xy 6.175411 -244.943211) (xy 6.120013 -244.882443) (xy 6.070459 -244.816823) (xy 6.02717 -244.74691)
			(xy 5.990517 -244.673301) (xy 5.960813 -244.596624) (xy 5.938309 -244.517533) (xy 5.9232 -244.436704)
			(xy 5.915612 -244.354825) (xy 5.915152 -244.31371) (xy 5.915559 -244.27542) (xy 5.922167 -244.199126)
			(xy 5.935315 -244.123684) (xy 5.954908 -244.049653) (xy 5.967476 -244.013482) (xy 5.970121 -244.005044)
			(xy 5.970124 -243.987375) (xy 5.967476 -243.978938) (xy 5.960618 -243.959126) (xy 5.955792 -243.944648)
			(xy 5.93217 -243.925852) (xy 5.809234 -243.914676) (xy 5.782564 -243.9289) (xy 5.775198 -243.942108)
			(xy 5.753931 -243.979733) (xy 5.705158 -244.051088) (xy 5.649695 -244.117378) (xy 5.588065 -244.177977)
			(xy 5.52085 -244.232315) (xy 5.448683 -244.279879) (xy 5.372244 -244.320221) (xy 5.292253 -244.352961)
			(xy 5.209464 -244.377791) (xy 5.124658 -244.394475) (xy 5.038634 -244.402858) (xy 4.995418 -244.403372)
			(xy 4.955849 -244.402936) (xy 4.877021 -244.395934) (xy 4.799127 -244.381956) (xy 4.722783 -244.361113)
			(xy 4.685538 -244.347746) (xy 4.676869 -244.344916) (xy 4.658647 -244.344916) (xy 4.649978 -244.347746)
			(xy 4.612728 -244.361101) (xy 4.536386 -244.381951) (xy 4.458494 -244.395938) (xy 4.379667 -244.402949)
			(xy 4.340098 -244.403372) (xy 4.301814 -244.402981) (xy 4.225525 -244.396442) (xy 4.150083 -244.383362)
			(xy 4.076046 -244.363836) (xy 4.03987 -244.351302) (xy 4.031433 -244.348651) (xy 4.013763 -244.348651)
			(xy 4.005326 -244.351302) (xy 3.969138 -244.363798) (xy 3.895102 -244.383314) (xy 3.819664 -244.396402)
			(xy 3.743381 -244.402966) (xy 3.705098 -244.403372) (xy 3.663991 -244.402899) (xy 3.582128 -244.395315)
			(xy 3.501314 -244.380211) (xy 3.422238 -244.357716) (xy 3.345574 -244.328022) (xy 3.271976 -244.291382)
			(xy 3.202073 -244.248109) (xy 3.136459 -244.198572) (xy 3.075695 -244.143193) (xy 3.020299 -244.082445)
			(xy 2.970743 -244.016845) (xy 2.927451 -243.946954) (xy 2.89079 -243.873367) (xy 2.861074 -243.796711)
			(xy 2.838557 -243.717641) (xy 2.82343 -243.636831) (xy 2.815822 -243.554971) (xy 2.815336 -243.513864)
			(xy 0.509016 -243.513864) (xy 0.509016 -248.835361) (xy 25.145742 -248.835361) (xy 25.145742 -248.750639)
			(xy 25.153795 -248.666302) (xy 25.169829 -248.583112) (xy 25.193697 -248.501822) (xy 25.225185 -248.42317)
			(xy 25.264007 -248.347867) (xy 25.30981 -248.276595) (xy 25.362181 -248.209999) (xy 25.420646 -248.148684)
			(xy 25.484674 -248.093203) (xy 25.553686 -248.04406) (xy 25.627056 -248.0017) (xy 25.704121 -247.966505)
			(xy 25.784183 -247.938796) (xy 25.866516 -247.918822) (xy 25.950375 -247.906765) (xy 26.035 -247.902734)
			(xy 26.119625 -247.906765) (xy 26.203484 -247.918822) (xy 26.285817 -247.938796) (xy 26.365879 -247.966505)
			(xy 26.442944 -248.0017) (xy 26.516314 -248.04406) (xy 26.585326 -248.093203) (xy 26.649354 -248.148684)
			(xy 26.707819 -248.209999) (xy 26.76019 -248.276595) (xy 26.805993 -248.347867) (xy 26.844815 -248.42317)
			(xy 26.876303 -248.501822) (xy 26.900171 -248.583112) (xy 26.916205 -248.666302) (xy 26.924258 -248.750639)
			(xy 26.924762 -248.793) (xy 26.924258 -248.835361) (xy 26.916205 -248.919698) (xy 26.900171 -249.002888)
			(xy 26.876303 -249.084178) (xy 26.844815 -249.16283) (xy 26.805993 -249.238133) (xy 26.76019 -249.309405)
			(xy 26.707819 -249.376001) (xy 26.649354 -249.437316) (xy 26.585326 -249.492797) (xy 26.516314 -249.54194)
			(xy 26.442944 -249.5843) (xy 26.365879 -249.619495) (xy 26.285817 -249.647204) (xy 26.203484 -249.667178)
			(xy 26.119625 -249.679235) (xy 26.035 -249.683267) (xy 25.950375 -249.679235) (xy 25.866516 -249.667178)
			(xy 25.784183 -249.647204) (xy 25.704121 -249.619495) (xy 25.627056 -249.5843) (xy 25.553686 -249.54194)
			(xy 25.484674 -249.492797) (xy 25.420646 -249.437316) (xy 25.362181 -249.376001) (xy 25.30981 -249.309405)
			(xy 25.264007 -249.238133) (xy 25.225185 -249.16283) (xy 25.193697 -249.084178) (xy 25.169829 -249.002888)
			(xy 25.153795 -248.919698) (xy 25.145742 -248.835361) (xy 0.509016 -248.835361) (xy 0.509016 -263.977374)
			(xy 0.508 -263.977374) (xy 0.508 -264.249916) (xy 0.509016 -264.249916) (xy 0.509016 -267.146024)
			(xy 2.53746 -267.146024) (xy 2.537827 -267.107739) (xy 2.544373 -267.03145) (xy 2.55746 -266.956008)
			(xy 2.576992 -266.881972) (xy 2.58953 -266.845796) (xy 2.59217 -266.837356) (xy 2.592178 -266.819688)
			(xy 2.58953 -266.811252) (xy 2.57702 -266.775068) (xy 2.557508 -266.701031) (xy 2.544424 -266.625591)
			(xy 2.537864 -266.549307) (xy 2.53746 -266.511024) (xy 2.537865 -266.471454) (xy 2.544876 -266.392626)
			(xy 2.558863 -266.314732) (xy 2.579715 -266.238389) (xy 2.593086 -266.201144) (xy 2.595933 -266.19248)
			(xy 2.595921 -266.174253) (xy 2.593086 -266.165584) (xy 2.579718 -266.128339) (xy 2.558871 -266.051995)
			(xy 2.544889 -265.974101) (xy 2.537881 -265.895273) (xy 2.53746 -265.855704) (xy 2.537926 -265.814601)
			(xy 2.545511 -265.732746) (xy 2.560616 -265.651939) (xy 2.583112 -265.572871) (xy 2.612808 -265.496216)
			(xy 2.64945 -265.422628) (xy 2.692726 -265.352735) (xy 2.742266 -265.287133) (xy 2.797647 -265.226382)
			(xy 2.858398 -265.171) (xy 2.924 -265.121459) (xy 2.993893 -265.078183) (xy 3.067481 -265.04154)
			(xy 3.144135 -265.011844) (xy 3.223203 -264.989347) (xy 3.30401 -264.974241) (xy 3.385865 -264.966656)
			(xy 3.426968 -264.966196) (xy 3.462095 -264.966499) (xy 3.532135 -264.971964) (xy 3.601524 -264.98295)
			(xy 3.635756 -264.990834) (xy 3.648964 -264.994136) (xy 3.674618 -264.98677) (xy 3.754628 -264.905236)
			(xy 3.761486 -264.879836) (xy 3.75793 -264.866628) (xy 3.748818 -264.829992) (xy 3.736061 -264.755577)
			(xy 3.729642 -264.68035) (xy 3.729228 -264.6426) (xy 3.729859 -264.596198) (xy 3.739548 -264.503901)
			(xy 3.758801 -264.413116) (xy 3.787407 -264.32483) (xy 3.805682 -264.282174) (xy 3.809488 -264.272232)
			(xy 3.809488 -264.250968) (xy 3.805682 -264.241026) (xy 3.787417 -264.198367) (xy 3.758825 -264.110078)
			(xy 3.739569 -264.019294) (xy 3.729857 -263.927001) (xy 3.729228 -263.8806) (xy 3.729692 -263.839489)
			(xy 3.73728 -263.757619) (xy 3.752391 -263.676799) (xy 3.774896 -263.597718) (xy 3.804602 -263.521051)
			(xy 3.841258 -263.447453) (xy 3.884548 -263.377551) (xy 3.934105 -263.311943) (xy 3.989505 -263.251188)
			(xy 4.050275 -263.195805) (xy 4.115897 -263.146267) (xy 4.185811 -263.102996) (xy 4.25942 -263.066361)
			(xy 4.336095 -263.036676) (xy 4.415182 -263.014194) (xy 4.496007 -262.999106) (xy 4.577879 -262.991541)
			(xy 4.61899 -262.991092) (xy 4.658757 -262.991518) (xy 4.737979 -262.998557) (xy 4.816255 -263.012642)
			(xy 4.892961 -263.033662) (xy 4.967484 -263.061447) (xy 5.003546 -263.078214) (xy 5.014047 -263.082546)
			(xy 5.036733 -263.082546) (xy 5.047234 -263.078214) (xy 5.083292 -263.061438) (xy 5.157819 -263.033665)
			(xy 5.234526 -263.01265) (xy 5.312802 -262.99856) (xy 5.392023 -262.99151) (xy 5.43179 -262.991092)
			(xy 5.470213 -262.991484) (xy 5.546776 -262.998075) (xy 5.622485 -263.011252) (xy 5.696772 -263.030916)
			(xy 5.769085 -263.05692) (xy 5.804154 -263.072626) (xy 5.815113 -263.077005) (xy 5.838675 -263.076351)
			(xy 5.849366 -263.071356) (xy 5.888227 -263.051102) (xy 5.969164 -263.017487) (xy 6.05301 -262.991984)
			(xy 6.138956 -262.97484) (xy 6.22617 -262.966221) (xy 6.26999 -262.965692) (xy 6.311097 -262.966163)
			(xy 6.39296 -262.973747) (xy 6.473774 -262.988851) (xy 6.552851 -263.011346) (xy 6.629515 -263.04104)
			(xy 6.703113 -263.07768) (xy 6.773016 -263.120953) (xy 6.83863 -263.17049) (xy 6.899394 -263.225869)
			(xy 6.95479 -263.286617) (xy 7.004346 -263.352217) (xy 7.047639 -263.422109) (xy 7.084299 -263.495696)
			(xy 7.114015 -263.572352) (xy 7.136532 -263.651422) (xy 7.151659 -263.732232) (xy 7.159266 -263.814093)
			(xy 7.159752 -263.8552) (xy 7.159123 -263.901602) (xy 7.149433 -263.993899) (xy 7.13018 -264.084685)
			(xy 7.101573 -264.17297) (xy 7.083298 -264.215626) (xy 7.079493 -264.225568) (xy 7.079493 -264.246832)
			(xy 7.083298 -264.256774) (xy 7.101562 -264.299434) (xy 7.130154 -264.387723) (xy 7.149411 -264.478506)
			(xy 7.150642 -264.4902) (xy 8.656578 -264.4902) (xy 8.660608 -264.405599) (xy 8.672661 -264.321764)
			(xy 8.692629 -264.239455) (xy 8.720331 -264.159416) (xy 8.755515 -264.082373) (xy 8.797864 -264.009023)
			(xy 8.846993 -263.940031) (xy 8.902458 -263.876021) (xy 8.963756 -263.817573) (xy 9.030332 -263.765217)
			(xy 9.101584 -263.719427) (xy 9.176865 -263.680616) (xy 9.255495 -263.649137) (xy 9.336762 -263.625276)
			(xy 9.419928 -263.609247) (xy 9.504242 -263.601196) (xy 9.54659 -263.600692) (xy 9.592985 -263.601278)
			(xy 9.685274 -263.610922) (xy 9.776058 -263.630117) (xy 9.864351 -263.658655) (xy 9.907016 -263.676892)
			(xy 9.916958 -263.680698) (xy 9.938222 -263.680698) (xy 9.948164 -263.676892) (xy 9.990828 -263.658651)
			(xy 10.079119 -263.630106) (xy 10.169904 -263.610912) (xy 10.262194 -263.601277) (xy 10.30859 -263.600692)
			(xy 10.350938 -263.601196) (xy 10.435252 -263.609247) (xy 10.518418 -263.625276) (xy 10.599685 -263.649137)
			(xy 10.678315 -263.680616) (xy 10.753596 -263.719427) (xy 10.824848 -263.765217) (xy 10.891424 -263.817573)
			(xy 10.952722 -263.876021) (xy 11.008187 -263.940031) (xy 11.057316 -264.009023) (xy 11.099665 -264.082373)
			(xy 11.134849 -264.159416) (xy 11.162551 -264.239455) (xy 11.182404 -264.32129) (xy 11.297412 -264.32129)
			(xy 11.297816 -264.283) (xy 11.304424 -264.206706) (xy 11.317574 -264.131264) (xy 11.337168 -264.057233)
			(xy 11.349736 -264.021062) (xy 11.352392 -264.012627) (xy 11.352389 -263.994955) (xy 11.349736 -263.986518)
			(xy 11.337184 -263.950343) (xy 11.317614 -263.876309) (xy 11.304469 -263.800868) (xy 11.297847 -263.724578)
			(xy 11.297412 -263.68629) (xy 11.297903 -263.645176) (xy 11.305491 -263.5633) (xy 11.320601 -263.482473)
			(xy 11.343104 -263.403385) (xy 11.372808 -263.32671) (xy 11.409459 -263.253103) (xy 11.452746 -263.183192)
			(xy 11.502299 -263.117573) (xy 11.557695 -263.056806) (xy 11.618461 -263.001409) (xy 11.684079 -262.951855)
			(xy 11.753989 -262.908567) (xy 11.827595 -262.871914) (xy 11.90427 -262.842209) (xy 11.983357 -262.819704)
			(xy 12.064184 -262.804593) (xy 12.14606 -262.797004) (xy 12.187174 -262.796528) (xy 12.226749 -262.796986)
			(xy 12.305583 -262.804053) (xy 12.383477 -262.818097) (xy 12.459814 -262.839008) (xy 12.497054 -262.852408)
			(xy 12.505723 -262.855238) (xy 12.523945 -262.855238) (xy 12.532614 -262.852408) (xy 12.569851 -262.839)
			(xy 12.646191 -262.818097) (xy 12.724086 -262.804054) (xy 12.802919 -262.796982) (xy 12.842494 -262.796528)
			(xy 12.880784 -262.796936) (xy 12.957078 -262.803543) (xy 13.03252 -262.816692) (xy 13.106551 -262.836284)
			(xy 13.142722 -262.848852) (xy 13.151159 -262.851503) (xy 13.168829 -262.851503) (xy 13.177266 -262.848852)
			(xy 13.213443 -262.836305) (xy 13.287476 -262.816734) (xy 13.362916 -262.803587) (xy 13.439206 -262.796964)
			(xy 13.477494 -262.796528) (xy 13.518608 -262.797019) (xy 13.600485 -262.804605) (xy 13.681312 -262.819714)
			(xy 13.760401 -262.842216) (xy 13.837077 -262.871919) (xy 13.910684 -262.908571) (xy 13.980596 -262.951857)
			(xy 14.046215 -263.00141) (xy 14.106983 -263.056806) (xy 14.16238 -263.117572) (xy 14.211934 -263.183191)
			(xy 14.255221 -263.253102) (xy 14.291874 -263.326709) (xy 14.321579 -263.403384) (xy 14.344083 -263.482472)
			(xy 14.359193 -263.563299) (xy 14.366781 -263.645176) (xy 14.367256 -263.68629) (xy 14.366848 -263.72458)
			(xy 14.360241 -263.800874) (xy 14.347092 -263.876316) (xy 14.3275 -263.950347) (xy 14.314932 -263.986518)
			(xy 14.312287 -263.994956) (xy 14.312283 -264.012625) (xy 14.314932 -264.021062) (xy 14.32179 -264.040874)
			(xy 14.326616 -264.055352) (xy 14.350238 -264.074148) (xy 14.473174 -264.085324) (xy 14.499844 -264.0711)
			(xy 14.50721 -264.057892) (xy 14.528471 -264.020264) (xy 14.577245 -263.948909) (xy 14.632708 -263.882619)
			(xy 14.694338 -263.822019) (xy 14.761554 -263.767682) (xy 14.833722 -263.720118) (xy 14.910162 -263.679776)
			(xy 14.990153 -263.647036) (xy 15.072942 -263.622208) (xy 15.157749 -263.605523) (xy 15.243774 -263.597141)
			(xy 15.28699 -263.596628) (xy 15.326559 -263.597061) (xy 15.405387 -263.604065) (xy 15.483281 -263.618043)
			(xy 15.559625 -263.638887) (xy 15.59687 -263.652254) (xy 15.605539 -263.655084) (xy 15.623761 -263.655084)
			(xy 15.63243 -263.652254) (xy 15.669679 -263.638896) (xy 15.746021 -263.618047) (xy 15.823914 -263.604061)
			(xy 15.902741 -263.59705) (xy 15.94231 -263.596628) (xy 15.980594 -263.597016) (xy 16.056883 -263.603556)
			(xy 16.132325 -263.616637) (xy 16.206362 -263.636163) (xy 16.242538 -263.648698) (xy 16.250975 -263.651349)
			(xy 16.268645 -263.651349) (xy 16.277082 -263.648698) (xy 16.313269 -263.636199) (xy 16.387306 -263.616684)
			(xy 16.462744 -263.603597) (xy 16.539027 -263.597033) (xy 16.57731 -263.596628) (xy 16.618417 -263.597103)
			(xy 16.700279 -263.604688) (xy 16.781093 -263.619793) (xy 16.860169 -263.642288) (xy 16.936832 -263.671982)
			(xy 17.010429 -263.708622) (xy 17.080333 -263.751895) (xy 17.145946 -263.801432) (xy 17.20671 -263.85681)
			(xy 17.262106 -263.917558) (xy 17.311662 -263.983158) (xy 17.354954 -264.053049) (xy 17.391615 -264.126635)
			(xy 17.421331 -264.20329) (xy 17.443849 -264.28236) (xy 17.458977 -264.363169) (xy 17.466585 -264.44503)
			(xy 17.467072 -264.486136) (xy 17.466647 -264.524425) (xy 17.460045 -264.600719) (xy 17.448323 -264.668)
			(xy 31.41472 -264.668) (xy 31.4153 -264.621604) (xy 31.424946 -264.529316) (xy 31.444142 -264.438532)
			(xy 31.472682 -264.350239) (xy 31.49092 -264.307574) (xy 31.494724 -264.297631) (xy 31.494724 -264.276369)
			(xy 31.49092 -264.266426) (xy 31.472677 -264.223763) (xy 31.444132 -264.135471) (xy 31.424938 -264.044686)
			(xy 31.415305 -263.952396) (xy 31.41472 -263.906) (xy 31.415152 -263.864896) (xy 31.422738 -263.783039)
			(xy 31.437844 -263.702231) (xy 31.460341 -263.623161) (xy 31.490039 -263.546505) (xy 31.526683 -263.472915)
			(xy 31.56996 -263.403021) (xy 31.619503 -263.337418) (xy 31.674887 -263.276667) (xy 31.73564 -263.221285)
			(xy 31.801244 -263.171745) (xy 31.87114 -263.128469) (xy 31.94473 -263.091827) (xy 32.021388 -263.062132)
			(xy 32.100458 -263.039637) (xy 32.181266 -263.024534) (xy 32.263124 -263.016951) (xy 32.304228 -263.016492)
			(xy 32.343996 -263.016903) (xy 32.423218 -263.023946) (xy 32.501494 -263.038034) (xy 32.5782 -263.059057)
			(xy 32.652722 -263.086846) (xy 32.688784 -263.103614) (xy 32.699285 -263.107946) (xy 32.721971 -263.107946)
			(xy 32.732472 -263.103614) (xy 32.76854 -263.08686) (xy 32.843064 -263.059082) (xy 32.919768 -263.038063)
			(xy 32.998042 -263.023969) (xy 33.077261 -263.016912) (xy 33.117028 -263.016492) (xy 33.163423 -263.0171)
			(xy 33.255711 -263.026738) (xy 33.346494 -263.045926) (xy 33.434789 -263.074458) (xy 33.477454 -263.092692)
			(xy 33.487396 -263.096498) (xy 33.50866 -263.096498) (xy 33.518602 -263.092692) (xy 33.56126 -263.074438)
			(xy 33.649554 -263.045896) (xy 33.74034 -263.026706) (xy 33.832632 -263.017075) (xy 33.879028 -263.016492)
			(xy 33.920131 -263.01694) (xy 34.001986 -263.024527) (xy 34.082792 -263.039635) (xy 34.161859 -263.062134)
			(xy 34.238513 -263.091832) (xy 34.3121 -263.128476) (xy 34.381992 -263.171753) (xy 34.447593 -263.221294)
			(xy 34.508343 -263.276677) (xy 34.563724 -263.337429) (xy 34.613263 -263.403031) (xy 34.656538 -263.472925)
			(xy 34.69318 -263.546513) (xy 34.722875 -263.623168) (xy 34.745372 -263.702236) (xy 34.760477 -263.783042)
			(xy 34.768061 -263.864897) (xy 34.768536 -263.906) (xy 34.767951 -263.952395) (xy 34.758306 -264.044684)
			(xy 34.739111 -264.135467) (xy 34.710573 -264.223761) (xy 34.692336 -264.266426) (xy 34.688529 -264.276368)
			(xy 34.688529 -264.297632) (xy 34.692336 -264.307574) (xy 34.710582 -264.350235) (xy 34.739126 -264.438528)
			(xy 34.758318 -264.529313) (xy 34.767951 -264.621604) (xy 34.768536 -264.668) (xy 34.768033 -264.709102)
			(xy 34.760449 -264.790954) (xy 34.745344 -264.871758) (xy 34.73105 -264.922) (xy 36.316372 -264.922)
			(xy 36.320402 -264.837396) (xy 36.332457 -264.753558) (xy 36.352426 -264.671245) (xy 36.380129 -264.591204)
			(xy 36.415315 -264.514158) (xy 36.457666 -264.440806) (xy 36.506798 -264.371812) (xy 36.562266 -264.307801)
			(xy 36.623567 -264.249352) (xy 36.690147 -264.196995) (xy 36.761402 -264.151204) (xy 36.836688 -264.112394)
			(xy 36.915321 -264.080916) (xy 36.996591 -264.057055) (xy 37.079761 -264.041028) (xy 37.164078 -264.032979)
			(xy 37.206428 -264.032492) (xy 37.252823 -264.0331) (xy 37.345111 -264.042738) (xy 37.435894 -264.061926)
			(xy 37.524189 -264.090458) (xy 37.566854 -264.108692) (xy 37.576796 -264.112498) (xy 37.59806 -264.112498)
			(xy 37.608002 -264.108692) (xy 37.65066 -264.090438) (xy 37.738954 -264.061896) (xy 37.82974 -264.042706)
			(xy 37.922032 -264.033075) (xy 37.968428 -264.032492) (xy 38.010776 -264.032997) (xy 38.095087 -264.04105)
			(xy 38.178252 -264.057081) (xy 38.259515 -264.080945) (xy 38.338143 -264.112425) (xy 38.413422 -264.151236)
			(xy 38.484672 -264.197027) (xy 38.551246 -264.249383) (xy 38.612542 -264.307831) (xy 38.624204 -264.32129)
			(xy 38.932104 -264.32129) (xy 38.932488 -264.283006) (xy 38.939028 -264.206717) (xy 38.952111 -264.131274)
			(xy 38.971638 -264.057238) (xy 38.984174 -264.021062) (xy 38.986829 -264.012626) (xy 38.986826 -263.994955)
			(xy 38.984174 -263.986518) (xy 38.971674 -263.950331) (xy 38.95216 -263.876294) (xy 38.939073 -263.800856)
			(xy 38.932509 -263.724573) (xy 38.932104 -263.68629) (xy 38.932603 -263.645184) (xy 38.940188 -263.563323)
			(xy 38.955292 -263.48251) (xy 38.977786 -263.403436) (xy 39.00748 -263.326774) (xy 39.044118 -263.253177)
			(xy 39.08739 -263.183275) (xy 39.136925 -263.117662) (xy 39.192302 -263.056899) (xy 39.253048 -263.001503)
			(xy 39.318645 -262.951947) (xy 39.388534 -262.908654) (xy 39.462119 -262.871992) (xy 39.538772 -262.842275)
			(xy 39.61784 -262.819756) (xy 39.698647 -262.804626) (xy 39.780506 -262.797016) (xy 39.821612 -262.796528)
			(xy 39.861187 -262.796975) (xy 39.940021 -262.804045) (xy 40.017915 -262.818092) (xy 40.094253 -262.839006)
			(xy 40.131492 -262.852408) (xy 40.140161 -262.855238) (xy 40.158383 -262.855238) (xy 40.167052 -262.852408)
			(xy 40.204295 -262.839018) (xy 40.280633 -262.81811) (xy 40.358525 -262.804062) (xy 40.437358 -262.796984)
			(xy 40.476932 -262.796528) (xy 40.515222 -262.796924) (xy 40.591516 -262.803535) (xy 40.666959 -262.816687)
			(xy 40.740989 -262.836283) (xy 40.77716 -262.848852) (xy 40.785597 -262.851503) (xy 40.803267 -262.851503)
			(xy 40.811704 -262.848852) (xy 40.847877 -262.836295) (xy 40.921912 -262.816726) (xy 40.997353 -262.803582)
			(xy 41.073644 -262.796962) (xy 41.111932 -262.796528) (xy 41.153044 -262.796922) (xy 41.234918 -262.804513)
			(xy 41.315741 -262.819627) (xy 41.394825 -262.842136) (xy 41.471493 -262.871847) (xy 41.545093 -262.908506)
			(xy 41.614996 -262.951802) (xy 41.680605 -263.001363) (xy 41.74136 -263.056768) (xy 41.796743 -263.117543)
			(xy 41.84628 -263.18317) (xy 41.88955 -263.253088) (xy 41.926183 -263.326701) (xy 41.955866 -263.403381)
			(xy 41.978346 -263.482473) (xy 41.993431 -263.563302) (xy 42.000993 -263.645178) (xy 42.00144 -263.68629)
			(xy 42.001048 -263.724574) (xy 41.994509 -263.800863) (xy 41.981429 -263.876305) (xy 41.961904 -263.950342)
			(xy 41.94937 -263.986518) (xy 41.946723 -263.994956) (xy 41.94672 -264.012625) (xy 41.94937 -264.021062)
			(xy 41.956228 -264.040874) (xy 41.961054 -264.055352) (xy 41.984676 -264.074148) (xy 42.107612 -264.085324)
			(xy 42.134282 -264.0711) (xy 42.141648 -264.057892) (xy 42.162881 -264.020248) (xy 42.211658 -263.948892)
			(xy 42.267124 -263.882602) (xy 42.328757 -263.822003) (xy 42.395975 -263.767666) (xy 42.468146 -263.720104)
			(xy 42.544589 -263.679763) (xy 42.624583 -263.647026) (xy 42.707375 -263.622199) (xy 42.792184 -263.605518)
			(xy 42.878211 -263.59714) (xy 42.921428 -263.596628) (xy 42.960997 -263.59705) (xy 43.039825 -263.604057)
			(xy 43.117719 -263.618038) (xy 43.194063 -263.638885) (xy 43.231308 -263.652254) (xy 43.239977 -263.655084)
			(xy 43.258199 -263.655084) (xy 43.266868 -263.652254) (xy 43.304113 -263.638885) (xy 43.380457 -263.618039)
			(xy 43.458351 -263.604056) (xy 43.537179 -263.597049) (xy 43.576748 -263.596628) (xy 43.615033 -263.597005)
			(xy 43.691321 -263.603548) (xy 43.766764 -263.616633) (xy 43.8408 -263.636162) (xy 43.876976 -263.648698)
			(xy 43.885413 -263.651349) (xy 43.903083 -263.651349) (xy 43.91152 -263.648698) (xy 43.947704 -263.636189)
			(xy 44.021741 -263.616676) (xy 44.097181 -263.603592) (xy 44.173465 -263.597032) (xy 44.211748 -263.596628)
			(xy 44.252852 -263.597021) (xy 44.33471 -263.604611) (xy 44.415518 -263.619721) (xy 44.494587 -263.642222)
			(xy 44.571243 -263.671923) (xy 44.644832 -263.70857) (xy 44.714725 -263.751851) (xy 44.780326 -263.801396)
			(xy 44.841077 -263.856783) (xy 44.896457 -263.917538) (xy 44.945996 -263.983145) (xy 44.98927 -264.053042)
			(xy 45.025911 -264.126634) (xy 45.055605 -264.203292) (xy 45.078099 -264.282364) (xy 45.093201 -264.363173)
			(xy 45.100783 -264.445032) (xy 45.101256 -264.486136) (xy 45.100876 -264.524421) (xy 45.094334 -264.600709)
			(xy 45.08125 -264.676152) (xy 45.061722 -264.750188) (xy 45.049186 -264.786364) (xy 45.046516 -264.794796)
			(xy 45.046527 -264.812471) (xy 45.049186 -264.820908) (xy 45.061691 -264.857093) (xy 45.081205 -264.93113)
			(xy 45.09429 -265.006569) (xy 45.100852 -265.082853) (xy 45.101256 -265.121136) (xy 45.100768 -265.162238)
			(xy 45.09318 -265.24409) (xy 45.078073 -265.324893) (xy 45.055575 -265.403958) (xy 45.025878 -265.48061)
			(xy 44.989236 -265.554195) (xy 44.945961 -265.624085) (xy 44.896423 -265.689685) (xy 44.841043 -265.750434)
			(xy 44.780294 -265.805815) (xy 44.714695 -265.855354) (xy 44.644805 -265.89863) (xy 44.571221 -265.935274)
			(xy 44.49457 -265.964971) (xy 44.415505 -265.98747) (xy 44.334702 -266.002578) (xy 44.25285 -266.010167)
			(xy 44.211748 -266.010644) (xy 44.172821 -266.010248) (xy 44.095264 -266.003465) (xy 44.018597 -265.989929)
			(xy 43.943406 -265.969745) (xy 43.906694 -265.956796) (xy 43.898145 -265.954032) (xy 43.880191 -265.954032)
			(xy 43.871642 -265.956796) (xy 43.834927 -265.969735) (xy 43.759736 -265.989918) (xy 43.68307 -266.003453)
			(xy 43.605514 -266.010238) (xy 43.566588 -266.010644) (xy 43.527662 -266.010236) (xy 43.450105 -266.003457)
			(xy 43.373438 -265.989924) (xy 43.298246 -265.969743) (xy 43.261534 -265.956796) (xy 43.252985 -265.954032)
			(xy 43.235031 -265.954032) (xy 43.226482 -265.956796) (xy 43.189773 -265.969752) (xy 43.11458 -265.98993)
			(xy 43.037912 -266.003461) (xy 42.960355 -266.01024) (xy 42.921428 -266.010644) (xy 42.880327 -266.010107)
			(xy 42.798476 -266.002525) (xy 42.717673 -265.987423) (xy 42.638608 -265.96493) (xy 42.561956 -265.935238)
			(xy 42.488371 -265.8986) (xy 42.41848 -265.855328) (xy 42.352879 -265.805793) (xy 42.292129 -265.750416)
			(xy 42.236748 -265.68967) (xy 42.187208 -265.624073) (xy 42.143932 -265.554185) (xy 42.107288 -265.480603)
			(xy 42.077591 -265.403953) (xy 42.055092 -265.32489) (xy 42.039984 -265.244088) (xy 42.032396 -265.162237)
			(xy 42.03192 -265.121136) (xy 42.032293 -265.082851) (xy 42.038837 -265.006563) (xy 42.051923 -264.93112)
			(xy 42.071453 -264.857084) (xy 42.08399 -264.820908) (xy 42.086622 -264.812467) (xy 42.086633 -264.794801)
			(xy 42.08399 -264.786364) (xy 42.077132 -264.766552) (xy 42.072306 -264.752074) (xy 42.048684 -264.733278)
			(xy 41.925748 -264.722102) (xy 41.899078 -264.736326) (xy 41.891712 -264.749534) (xy 41.870455 -264.787173)
			(xy 41.821704 -264.858563) (xy 41.766257 -264.924886) (xy 41.704637 -264.985518) (xy 41.637427 -265.039887)
			(xy 41.565259 -265.087479) (xy 41.488815 -265.127845) (xy 41.408815 -265.160606) (xy 41.326015 -265.185452)
			(xy 41.241195 -265.202148) (xy 41.155156 -265.210537) (xy 41.111932 -265.211052) (xy 41.073001 -265.210601)
			(xy 40.995438 -265.203762) (xy 40.918771 -265.19017) (xy 40.843585 -265.169927) (xy 40.806878 -265.15695)
			(xy 40.798329 -265.154186) (xy 40.780375 -265.154186) (xy 40.771826 -265.15695) (xy 40.735115 -265.169918)
			(xy 40.65993 -265.190162) (xy 40.583264 -265.203761) (xy 40.505703 -265.210612) (xy 40.466772 -265.211052)
			(xy 40.42784 -265.210619) (xy 40.350278 -265.203775) (xy 40.27361 -265.190177) (xy 40.198425 -265.16993)
			(xy 40.161718 -265.15695) (xy 40.153169 -265.154186) (xy 40.135215 -265.154186) (xy 40.126666 -265.15695)
			(xy 40.089961 -265.169935) (xy 40.014774 -265.190174) (xy 39.938106 -265.203769) (xy 39.860544 -265.210614)
			(xy 39.821612 -265.211052) (xy 39.780503 -265.210536) (xy 39.698635 -265.20295) (xy 39.617817 -265.187841)
			(xy 39.538738 -265.165339) (xy 39.462073 -265.135634) (xy 39.388477 -265.098982) (xy 39.318577 -265.055695)
			(xy 39.252969 -265.006141) (xy 39.192215 -264.950745) (xy 39.136832 -264.889978) (xy 39.087293 -264.82436)
			(xy 39.044021 -264.75445) (xy 39.007386 -264.680845) (xy 38.977699 -264.604174) (xy 38.955214 -264.52509)
			(xy 38.940123 -264.444268) (xy 38.932555 -264.362399) (xy 38.932104 -264.32129) (xy 38.624204 -264.32129)
			(xy 38.668004 -264.37184) (xy 38.717132 -264.440831) (xy 38.759479 -264.51418) (xy 38.794662 -264.591222)
			(xy 38.822362 -264.671259) (xy 38.842329 -264.753567) (xy 38.854383 -264.837401) (xy 38.858413 -264.922)
			(xy 38.854383 -265.006599) (xy 38.842329 -265.090433) (xy 38.822362 -265.172741) (xy 38.794662 -265.252778)
			(xy 38.759479 -265.32982) (xy 38.717132 -265.403169) (xy 38.668004 -265.47216) (xy 38.612542 -265.536169)
			(xy 38.551246 -265.594617) (xy 38.484672 -265.646973) (xy 38.413422 -265.692764) (xy 38.338143 -265.731575)
			(xy 38.259515 -265.763055) (xy 38.178252 -265.786919) (xy 38.095087 -265.80295) (xy 38.010776 -265.811003)
			(xy 37.968428 -265.811508) (xy 37.922033 -265.810915) (xy 37.829745 -265.801273) (xy 37.738961 -265.78208)
			(xy 37.650667 -265.753544) (xy 37.608002 -265.735308) (xy 37.59806 -265.731502) (xy 37.576796 -265.731502)
			(xy 37.566854 -265.735308) (xy 37.524188 -265.753544) (xy 37.435897 -265.78209) (xy 37.345113 -265.801286)
			(xy 37.252824 -265.810922) (xy 37.206428 -265.811508) (xy 37.164078 -265.811021) (xy 37.079761 -265.802972)
			(xy 36.996591 -265.786945) (xy 36.915321 -265.763084) (xy 36.836688 -265.731606) (xy 36.761402 -265.692796)
			(xy 36.690147 -265.647005) (xy 36.623567 -265.594648) (xy 36.562266 -265.536199) (xy 36.506798 -265.472188)
			(xy 36.457666 -265.403194) (xy 36.415315 -265.329842) (xy 36.380129 -265.252796) (xy 36.352426 -265.172755)
			(xy 36.332457 -265.090442) (xy 36.320402 -265.006604) (xy 36.316372 -264.922) (xy 34.73105 -264.922)
			(xy 34.722849 -264.950823) (xy 34.693154 -265.027476) (xy 34.656513 -265.101062) (xy 34.61324 -265.170953)
			(xy 34.563702 -265.236553) (xy 34.508323 -265.297303) (xy 34.447575 -265.352684) (xy 34.381976 -265.402224)
			(xy 34.312086 -265.4455) (xy 34.238502 -265.482143) (xy 34.16185 -265.51184) (xy 34.082785 -265.534338)
			(xy 34.001982 -265.549445) (xy 33.92013 -265.557032) (xy 33.879028 -265.557508) (xy 33.832633 -265.556915)
			(xy 33.740345 -265.547273) (xy 33.649561 -265.52808) (xy 33.561267 -265.499544) (xy 33.518602 -265.481308)
			(xy 33.50866 -265.477502) (xy 33.487396 -265.477502) (xy 33.477454 -265.481308) (xy 33.434788 -265.499544)
			(xy 33.346497 -265.52809) (xy 33.255713 -265.547286) (xy 33.163424 -265.556922) (xy 33.117028 -265.557508)
			(xy 33.077261 -265.557075) (xy 32.998039 -265.550038) (xy 32.919763 -265.535954) (xy 32.843057 -265.514936)
			(xy 32.768534 -265.487152) (xy 32.732472 -265.470386) (xy 32.721971 -265.466054) (xy 32.699285 -265.466054)
			(xy 32.688784 -265.470386) (xy 32.652723 -265.487156) (xy 32.578197 -265.51493) (xy 32.501491 -265.535947)
			(xy 32.423215 -265.550037) (xy 32.343995 -265.557089) (xy 32.304228 -265.557508) (xy 32.263125 -265.557021)
			(xy 32.18127 -265.549439) (xy 32.100464 -265.534336) (xy 32.021396 -265.511841) (xy 31.944741 -265.482147)
			(xy 31.871153 -265.445507) (xy 31.80126 -265.402232) (xy 31.735658 -265.352694) (xy 31.674906 -265.297313)
			(xy 31.619524 -265.236564) (xy 31.569983 -265.170963) (xy 31.526707 -265.101071) (xy 31.490064 -265.027484)
			(xy 31.460368 -264.95083) (xy 31.437871 -264.871763) (xy 31.422765 -264.790957) (xy 31.41518 -264.709103)
			(xy 31.41472 -264.668) (xy 17.448323 -264.668) (xy 17.446901 -264.676162) (xy 17.427313 -264.750193)
			(xy 17.414748 -264.786364) (xy 17.412079 -264.794796) (xy 17.412091 -264.812471) (xy 17.414748 -264.820908)
			(xy 17.427278 -264.85709) (xy 17.446855 -264.931121) (xy 17.460005 -265.00656) (xy 17.466634 -265.082848)
			(xy 17.467072 -265.121136) (xy 17.466682 -265.162248) (xy 17.45909 -265.244122) (xy 17.443976 -265.324945)
			(xy 17.421467 -265.404029) (xy 17.391756 -265.480698) (xy 17.355096 -265.554298) (xy 17.3118 -265.6242)
			(xy 17.262238 -265.689809) (xy 17.206833 -265.750564) (xy 17.146058 -265.805947) (xy 17.080431 -265.855484)
			(xy 17.010513 -265.898754) (xy 16.936899 -265.935387) (xy 16.86022 -265.96507) (xy 16.781128 -265.98755)
			(xy 16.700299 -266.002635) (xy 16.618422 -266.010197) (xy 16.57731 -266.010644) (xy 16.538384 -266.010229)
			(xy 16.460827 -266.003452) (xy 16.38416 -265.989922) (xy 16.308969 -265.969742) (xy 16.272256 -265.956796)
			(xy 16.263707 -265.954032) (xy 16.245753 -265.954032) (xy 16.237204 -265.956796) (xy 16.200492 -265.969745)
			(xy 16.125301 -265.989926) (xy 16.048633 -266.003458) (xy 15.971076 -266.010239) (xy 15.93215 -266.010644)
			(xy 15.893223 -266.010247) (xy 15.815666 -266.003465) (xy 15.738999 -265.989929) (xy 15.663808 -265.969745)
			(xy 15.627096 -265.956796) (xy 15.618547 -265.954032) (xy 15.600593 -265.954032) (xy 15.592044 -265.956796)
			(xy 15.555329 -265.969734) (xy 15.480138 -265.989917) (xy 15.403472 -266.003453) (xy 15.325916 -266.010238)
			(xy 15.28699 -266.010644) (xy 15.245883 -266.010197) (xy 15.164018 -266.002612) (xy 15.083203 -265.987506)
			(xy 15.004126 -265.96501) (xy 14.927461 -265.935315) (xy 14.853863 -265.898674) (xy 14.783958 -265.855399)
			(xy 14.718344 -265.80586) (xy 14.65758 -265.75048) (xy 14.602184 -265.68973) (xy 14.552629 -265.624128)
			(xy 14.509336 -265.554235) (xy 14.472677 -265.480646) (xy 14.442962 -265.403989) (xy 14.420445 -265.324917)
			(xy 14.40532 -265.244106) (xy 14.397713 -265.162243) (xy 14.397228 -265.121136) (xy 14.397645 -265.082846)
			(xy 14.404249 -265.006553) (xy 14.417395 -264.93111) (xy 14.436985 -264.857079) (xy 14.449552 -264.820908)
			(xy 14.452185 -264.812467) (xy 14.452196 -264.7948) (xy 14.449552 -264.786364) (xy 14.442694 -264.766552)
			(xy 14.437868 -264.752074) (xy 14.414246 -264.733278) (xy 14.29131 -264.722102) (xy 14.26464 -264.736326)
			(xy 14.257274 -264.749534) (xy 14.236045 -264.78719) (xy 14.187291 -264.85858) (xy 14.131841 -264.924903)
			(xy 14.070219 -264.985535) (xy 14.003005 -265.039902) (xy 13.930835 -265.087493) (xy 13.854388 -265.127858)
			(xy 13.774385 -265.160617) (xy 13.691583 -265.18546) (xy 13.60676 -265.202153) (xy 13.520719 -265.210539)
			(xy 13.477494 -265.211052) (xy 13.438562 -265.210612) (xy 13.361 -265.20377) (xy 13.284332 -265.190175)
			(xy 13.209147 -265.169929) (xy 13.17244 -265.15695) (xy 13.163891 -265.154186) (xy 13.145937 -265.154186)
			(xy 13.137388 -265.15695) (xy 13.100681 -265.169929) (xy 13.025494 -265.19017) (xy 12.948827 -265.203766)
			(xy 12.871265 -265.210613) (xy 12.832334 -265.211052) (xy 12.793403 -265.2106) (xy 12.715841 -265.203762)
			(xy 12.639173 -265.19017) (xy 12.563987 -265.169927) (xy 12.52728 -265.15695) (xy 12.518731 -265.154186)
			(xy 12.500777 -265.154186) (xy 12.492228 -265.15695) (xy 12.455517 -265.169918) (xy 12.380332 -265.190161)
			(xy 12.303666 -265.203761) (xy 12.226105 -265.210612) (xy 12.187174 -265.211052) (xy 12.146059 -265.210612)
			(xy 12.06418 -265.203022) (xy 11.983351 -265.18791) (xy 11.904261 -265.165405) (xy 11.827584 -265.135698)
			(xy 11.753976 -265.099044) (xy 11.684064 -265.055753) (xy 11.618444 -265.006197) (xy 11.557676 -264.950798)
			(xy 11.50228 -264.890029) (xy 11.452726 -264.824407) (xy 11.409439 -264.754493) (xy 11.372787 -264.680883)
			(xy 11.343083 -264.604205) (xy 11.320581 -264.525114) (xy 11.305473 -264.444284) (xy 11.297886 -264.362405)
			(xy 11.297412 -264.32129) (xy 11.182404 -264.32129) (xy 11.182519 -264.321764) (xy 11.194572 -264.405599)
			(xy 11.198603 -264.4902) (xy 11.194572 -264.574801) (xy 11.182519 -264.658636) (xy 11.162551 -264.740945)
			(xy 11.134849 -264.820984) (xy 11.099665 -264.898027) (xy 11.057316 -264.971377) (xy 11.008187 -265.040369)
			(xy 10.952722 -265.104379) (xy 10.891424 -265.162827) (xy 10.824848 -265.215183) (xy 10.753596 -265.260973)
			(xy 10.678315 -265.299784) (xy 10.599685 -265.331263) (xy 10.518418 -265.355124) (xy 10.435252 -265.371153)
			(xy 10.350938 -265.379204) (xy 10.30859 -265.379708) (xy 10.262194 -265.379129) (xy 10.169906 -265.369483)
			(xy 10.079122 -265.350286) (xy 9.990829 -265.321746) (xy 9.948164 -265.303508) (xy 9.938222 -265.299702)
			(xy 9.916958 -265.299702) (xy 9.907016 -265.303508) (xy 9.864355 -265.321756) (xy 9.776062 -265.350299)
			(xy 9.685277 -265.369491) (xy 9.592986 -265.379124) (xy 9.54659 -265.379708) (xy 9.504242 -265.379204)
			(xy 9.419928 -265.371153) (xy 9.336762 -265.355124) (xy 9.255495 -265.331263) (xy 9.176865 -265.299784)
			(xy 9.101584 -265.260973) (xy 9.030332 -265.215183) (xy 8.963756 -265.162827) (xy 8.902458 -265.104379)
			(xy 8.846993 -265.040369) (xy 8.797864 -264.971377) (xy 8.755515 -264.898027) (xy 8.720331 -264.820984)
			(xy 8.692629 -264.740945) (xy 8.672661 -264.658636) (xy 8.660608 -264.574801) (xy 8.656578 -264.4902)
			(xy 7.150642 -264.4902) (xy 7.159123 -264.570799) (xy 7.159752 -264.6172) (xy 7.159288 -264.658311)
			(xy 7.1517 -264.740181) (xy 7.136589 -264.821001) (xy 7.114084 -264.900082) (xy 7.084378 -264.976749)
			(xy 7.047722 -265.050347) (xy 7.004432 -265.120249) (xy 6.954875 -265.185857) (xy 6.899475 -265.246612)
			(xy 6.838705 -265.301995) (xy 6.773083 -265.351533) (xy 6.703169 -265.394804) (xy 6.62956 -265.431439)
			(xy 6.552885 -265.461124) (xy 6.473798 -265.483606) (xy 6.392973 -265.498694) (xy 6.311101 -265.506259)
			(xy 6.26999 -265.506708) (xy 6.231566 -265.506323) (xy 6.155003 -265.499731) (xy 6.079295 -265.486552)
			(xy 6.005007 -265.466887) (xy 5.932695 -265.44088) (xy 5.897626 -265.425174) (xy 5.886671 -265.420782)
			(xy 5.863105 -265.421444) (xy 5.852414 -265.426444) (xy 5.813556 -265.446705) (xy 5.732619 -265.480319)
			(xy 5.648772 -265.50582) (xy 5.562825 -265.522962) (xy 5.47561 -265.53158) (xy 5.43179 -265.532108)
			(xy 5.392023 -265.53169) (xy 5.312801 -265.524649) (xy 5.234524 -265.510562) (xy 5.157818 -265.489541)
			(xy 5.083296 -265.461754) (xy 5.047234 -265.444986) (xy 5.036733 -265.440654) (xy 5.014047 -265.440654)
			(xy 5.003546 -265.444986) (xy 4.967476 -265.461733) (xy 4.892952 -265.489512) (xy 4.816248 -265.510534)
			(xy 4.737975 -265.524629) (xy 4.658756 -265.531687) (xy 4.61899 -265.532108) (xy 4.583863 -265.531813)
			(xy 4.513823 -265.526345) (xy 4.444434 -265.515356) (xy 4.410202 -265.50747) (xy 4.396994 -265.504168)
			(xy 4.37134 -265.511534) (xy 4.29133 -265.593068) (xy 4.284472 -265.618468) (xy 4.288028 -265.631676)
			(xy 4.297104 -265.668316) (xy 4.309776 -265.742735) (xy 4.316106 -265.817959) (xy 4.316476 -265.855704)
			(xy 4.316047 -265.895273) (xy 4.309042 -265.974101) (xy 4.295062 -266.051995) (xy 4.274218 -266.128339)
			(xy 4.26085 -266.165584) (xy 4.258039 -266.174257) (xy 4.258027 -266.192476) (xy 4.26085 -266.201144)
			(xy 4.274212 -266.238392) (xy 4.29506 -266.314734) (xy 4.309044 -266.392627) (xy 4.316054 -266.471455)
			(xy 4.316476 -266.511024) (xy 4.316091 -266.549308) (xy 4.309551 -266.625597) (xy 4.296468 -266.701039)
			(xy 4.276941 -266.775076) (xy 4.264406 -266.811252) (xy 4.261745 -266.819686) (xy 4.261753 -266.837359)
			(xy 4.264406 -266.845796) (xy 4.276909 -266.881982) (xy 4.296423 -266.956019) (xy 4.309509 -267.031458)
			(xy 4.316071 -267.107741) (xy 4.316476 -267.146024) (xy 4.315972 -267.188372) (xy 4.307921 -267.272686)
			(xy 4.291892 -267.355852) (xy 4.268031 -267.437119) (xy 4.236552 -267.515749) (xy 4.197741 -267.59103)
			(xy 4.151951 -267.662282) (xy 4.099595 -267.728858) (xy 4.041147 -267.790156) (xy 3.977137 -267.845621)
			(xy 3.908145 -267.89475) (xy 3.834795 -267.937099) (xy 3.762751 -267.97) (xy 31.414217 -267.97) (xy 31.418248 -267.885399)
			(xy 31.430301 -267.801564) (xy 31.450269 -267.719255) (xy 31.477971 -267.639216) (xy 31.513155 -267.562173)
			(xy 31.555503 -267.488824) (xy 31.604632 -267.419831) (xy 31.660097 -267.355822) (xy 31.721395 -267.297374)
			(xy 31.787971 -267.245018) (xy 31.859223 -267.199227) (xy 31.934504 -267.160417) (xy 32.013134 -267.128938)
			(xy 32.0944 -267.105076) (xy 32.177566 -267.089047) (xy 32.26188 -267.080996) (xy 32.304228 -267.080492)
			(xy 32.343996 -267.080903) (xy 32.423218 -267.087946) (xy 32.501494 -267.102034) (xy 32.5782 -267.123057)
			(xy 32.652722 -267.150846) (xy 32.688784 -267.167614) (xy 32.699285 -267.171946) (xy 32.721971 -267.171946)
			(xy 32.732472 -267.167614) (xy 32.76854 -267.15086) (xy 32.843064 -267.123082) (xy 32.919768 -267.102063)
			(xy 32.998042 -267.087969) (xy 33.077261 -267.080912) (xy 33.117028 -267.080492) (xy 33.163423 -267.0811)
			(xy 33.255711 -267.090738) (xy 33.346494 -267.109926) (xy 33.434789 -267.138458) (xy 33.477454 -267.156692)
			(xy 33.487396 -267.160498) (xy 33.50866 -267.160498) (xy 33.518602 -267.156692) (xy 33.56126 -267.138438)
			(xy 33.649554 -267.109896) (xy 33.74034 -267.090706) (xy 33.832632 -267.081075) (xy 33.879028 -267.080492)
			(xy 33.921377 -267.08098) (xy 34.005692 -267.089031) (xy 34.08886 -267.10506) (xy 34.170128 -267.128922)
			(xy 34.24876 -267.160401) (xy 34.324043 -267.199212) (xy 34.395296 -267.245004) (xy 34.461874 -267.297361)
			(xy 34.523173 -267.35581) (xy 34.578639 -267.419821) (xy 34.627769 -267.488814) (xy 34.670118 -267.562165)
			(xy 34.705303 -267.63921) (xy 34.733006 -267.71925) (xy 34.752974 -267.801561) (xy 34.765028 -267.885397)
			(xy 34.769058 -267.97) (xy 34.765028 -268.054603) (xy 34.752974 -268.138439) (xy 34.733006 -268.22075)
			(xy 34.705303 -268.30079) (xy 34.670118 -268.377835) (xy 34.627769 -268.451186) (xy 34.578639 -268.520179)
			(xy 34.523173 -268.58419) (xy 34.461874 -268.642639) (xy 34.395296 -268.694996) (xy 34.324043 -268.740788)
			(xy 34.24876 -268.779599) (xy 34.170128 -268.811078) (xy 34.08886 -268.83494) (xy 34.005692 -268.850969)
			(xy 33.921377 -268.85902) (xy 33.879028 -268.859508) (xy 33.832633 -268.858915) (xy 33.740345 -268.849273)
			(xy 33.649561 -268.83008) (xy 33.561267 -268.801544) (xy 33.518602 -268.783308) (xy 33.50866 -268.779502)
			(xy 33.487396 -268.779502) (xy 33.477454 -268.783308) (xy 33.434788 -268.801544) (xy 33.346497 -268.83009)
			(xy 33.255713 -268.849286) (xy 33.163424 -268.858922) (xy 33.117028 -268.859508) (xy 33.077261 -268.859075)
			(xy 32.998039 -268.852038) (xy 32.919763 -268.837954) (xy 32.843057 -268.816936) (xy 32.768534 -268.789152)
			(xy 32.732472 -268.772386) (xy 32.721971 -268.768054) (xy 32.699285 -268.768054) (xy 32.688784 -268.772386)
			(xy 32.652723 -268.789156) (xy 32.578197 -268.81693) (xy 32.501491 -268.837947) (xy 32.423215 -268.852037)
			(xy 32.343995 -268.859089) (xy 32.304228 -268.859508) (xy 32.26188 -268.859004) (xy 32.177566 -268.850953)
			(xy 32.0944 -268.834924) (xy 32.013134 -268.811062) (xy 31.934504 -268.779583) (xy 31.859223 -268.740773)
			(xy 31.787971 -268.694982) (xy 31.721395 -268.642626) (xy 31.660097 -268.584178) (xy 31.604632 -268.520169)
			(xy 31.555503 -268.451176) (xy 31.513155 -268.377827) (xy 31.477971 -268.300784) (xy 31.450269 -268.220745)
			(xy 31.430301 -268.138436) (xy 31.418248 -268.054601) (xy 31.414217 -267.97) (xy 3.762751 -267.97)
			(xy 3.757752 -267.972283) (xy 3.677713 -267.999985) (xy 3.595404 -268.019953) (xy 3.511569 -268.032006)
			(xy 3.426968 -268.036037) (xy 3.342367 -268.032006) (xy 3.258532 -268.019953) (xy 3.176223 -267.999985)
			(xy 3.096184 -267.972283) (xy 3.019141 -267.937099) (xy 2.945791 -267.89475) (xy 2.876799 -267.845621)
			(xy 2.812789 -267.790156) (xy 2.754341 -267.728858) (xy 2.701985 -267.662282) (xy 2.656195 -267.59103)
			(xy 2.617384 -267.515749) (xy 2.585905 -267.437119) (xy 2.562044 -267.355852) (xy 2.546015 -267.272686)
			(xy 2.537964 -267.188372) (xy 2.53746 -267.146024) (xy 0.509016 -267.146024) (xy 0.509016 -274.139406)
			(xy 13.258292 -274.139406) (xy 13.258752 -274.096822) (xy 13.266866 -274.012043) (xy 13.283048 -273.928428)
			(xy 13.30715 -273.846742) (xy 13.338952 -273.767736) (xy 13.358114 -273.729704) (xy 13.36332 -273.718524)
			(xy 13.363324 -273.693891) (xy 13.358114 -273.682714) (xy 13.33897 -273.644674) (xy 13.307179 -273.565667)
			(xy 13.283083 -273.483983) (xy 13.266901 -273.40037) (xy 13.258782 -273.315594) (xy 13.258292 -273.273012)
			(xy 13.258761 -273.230474) (xy 13.26684 -273.145783) (xy 13.282974 -273.062251) (xy 13.307015 -272.980643)
			(xy 13.338744 -272.901705) (xy 13.377869 -272.826159) (xy 13.400532 -272.790158) (xy 13.405487 -272.781745)
			(xy 13.409223 -272.762599) (xy 13.405487 -272.743453) (xy 13.400532 -272.73504) (xy 13.377896 -272.699048)
			(xy 13.338805 -272.623536) (xy 13.307095 -272.54464) (xy 13.283055 -272.463079) (xy 13.266904 -272.379597)
			(xy 13.258789 -272.294955) (xy 13.258292 -272.25244) (xy 13.258811 -272.209852) (xy 13.266975 -272.125067)
			(xy 13.283204 -272.041451) (xy 13.307349 -271.959768) (xy 13.339189 -271.880767) (xy 13.358368 -271.842738)
			(xy 13.363547 -271.831549) (xy 13.363566 -271.806926) (xy 13.358368 -271.795748) (xy 13.339186 -271.757721)
			(xy 13.307343 -271.678719) (xy 13.283196 -271.597036) (xy 13.266967 -271.51342) (xy 13.258803 -271.428634)
			(xy 13.258292 -271.386046) (xy 13.258857 -271.344934) (xy 13.266439 -271.26306) (xy 13.281544 -271.182235)
			(xy 13.304041 -271.103149) (xy 13.33374 -271.026475) (xy 13.370387 -270.952869) (xy 13.413669 -270.882959)
			(xy 13.463216 -270.81734) (xy 13.518607 -270.756572) (xy 13.579369 -270.701175) (xy 13.644983 -270.651621)
			(xy 13.714889 -270.608332) (xy 13.788491 -270.571677) (xy 13.865161 -270.541971) (xy 13.944245 -270.519465)
			(xy 14.025069 -270.504352) (xy 14.106942 -270.496761) (xy 14.148054 -270.496284) (xy 14.19152 -270.496839)
			(xy 14.278031 -270.505397) (xy 14.363297 -270.522339) (xy 14.446508 -270.547503) (xy 14.48689 -270.563594)
			(xy 14.500098 -270.568928) (xy 14.527276 -270.564864) (xy 14.618462 -270.491204) (xy 14.628114 -270.46555)
			(xy 14.625574 -270.45158) (xy 14.619032 -270.412731) (xy 14.612037 -270.334255) (xy 14.611604 -270.294862)
			(xy 14.612142 -270.252274) (xy 14.620303 -270.167491) (xy 14.636528 -270.083875) (xy 14.660669 -270.002192)
			(xy 14.692504 -269.923189) (xy 14.71168 -269.88516) (xy 14.716911 -269.87399) (xy 14.716896 -269.849349)
			(xy 14.71168 -269.83817) (xy 14.692507 -269.800138) (xy 14.660662 -269.721138) (xy 14.636514 -269.639456)
			(xy 14.620282 -269.555841) (xy 14.612116 -269.471056) (xy 14.611604 -269.428468) (xy 14.612108 -269.386107)
			(xy 14.620161 -269.30177) (xy 14.636195 -269.21858) (xy 14.660063 -269.13729) (xy 14.691551 -269.058638)
			(xy 14.730373 -268.983335) (xy 14.776176 -268.912063) (xy 14.828547 -268.845467) (xy 14.887012 -268.784152)
			(xy 14.95104 -268.728671) (xy 15.020052 -268.679528) (xy 15.093422 -268.637168) (xy 15.170487 -268.601973)
			(xy 15.250549 -268.574264) (xy 15.332882 -268.55429) (xy 15.416741 -268.542233) (xy 15.501366 -268.538202)
			(xy 15.585991 -268.542233) (xy 15.66985 -268.55429) (xy 15.752183 -268.574264) (xy 15.832245 -268.601973)
			(xy 15.90931 -268.637168) (xy 15.98268 -268.679528) (xy 16.051692 -268.728671) (xy 16.11572 -268.784152)
			(xy 16.174185 -268.845467) (xy 16.226556 -268.912063) (xy 16.272359 -268.983335) (xy 16.311181 -269.058638)
			(xy 16.342669 -269.13729) (xy 16.366537 -269.21858) (xy 16.382571 -269.30177) (xy 16.390624 -269.386107)
			(xy 16.391128 -269.428468) (xy 16.39061 -269.471056) (xy 16.382445 -269.555841) (xy 16.366216 -269.639457)
			(xy 16.342071 -269.72114) (xy 16.310231 -269.800141) (xy 16.291052 -269.83817) (xy 16.286066 -269.849402)
			(xy 16.286051 -269.873936) (xy 16.291052 -269.88516) (xy 16.310231 -269.923189) (xy 16.342075 -270.00219)
			(xy 16.366223 -270.083872) (xy 16.382453 -270.167489) (xy 16.390617 -270.252274) (xy 16.391128 -270.294862)
			(xy 16.390665 -270.335977) (xy 16.383081 -270.417857) (xy 16.367974 -270.498688) (xy 16.345473 -270.57778)
			(xy 16.31577 -270.654459) (xy 16.279118 -270.728069) (xy 16.23583 -270.797983) (xy 16.186275 -270.863605)
			(xy 16.130877 -270.924375) (xy 16.070108 -270.979773) (xy 16.004487 -271.029328) (xy 15.934573 -271.072616)
			(xy 15.860962 -271.109268) (xy 15.784284 -271.138972) (xy 15.705192 -271.161473) (xy 15.624361 -271.176581)
			(xy 15.542481 -271.184165) (xy 15.501366 -271.184624) (xy 15.4579 -271.184062) (xy 15.37139 -271.175506)
			(xy 15.286124 -271.158566) (xy 15.202912 -271.133404) (xy 15.16253 -271.117314) (xy 15.149322 -271.11198)
			(xy 15.122144 -271.116044) (xy 15.030958 -271.189704) (xy 15.021306 -271.215358) (xy 15.023846 -271.229328)
			(xy 15.030389 -271.268177) (xy 15.037383 -271.346653) (xy 15.037816 -271.386046) (xy 15.03729 -271.428634)
			(xy 15.029128 -271.513418) (xy 15.0129 -271.597034) (xy 14.988757 -271.678717) (xy 14.956918 -271.757719)
			(xy 14.93774 -271.795748) (xy 14.932703 -271.806962) (xy 14.932722 -271.831513) (xy 14.93774 -271.842738)
			(xy 14.956918 -271.880767) (xy 14.957254 -271.8816) (xy 35.06978 -271.8816) (xy 35.070168 -271.843316)
			(xy 35.076707 -271.767027) (xy 35.089789 -271.691585) (xy 35.109315 -271.617548) (xy 35.12185 -271.581372)
			(xy 35.124501 -271.572935) (xy 35.124501 -271.555265) (xy 35.12185 -271.546828) (xy 35.109324 -271.51065)
			(xy 35.089817 -271.43661) (xy 35.076737 -271.361169) (xy 35.070182 -271.284883) (xy 35.06978 -271.2466)
			(xy 35.070284 -271.204252) (xy 35.078335 -271.119938) (xy 35.094364 -271.036772) (xy 35.118225 -270.955505)
			(xy 35.149704 -270.876875) (xy 35.188515 -270.801594) (xy 35.234305 -270.730342) (xy 35.286661 -270.663766)
			(xy 35.345109 -270.602468) (xy 35.409119 -270.547003) (xy 35.478111 -270.497874) (xy 35.551461 -270.455525)
			(xy 35.628504 -270.420341) (xy 35.708543 -270.392639) (xy 35.790852 -270.372671) (xy 35.874687 -270.360618)
			(xy 35.959288 -270.356588) (xy 36.043889 -270.360618) (xy 36.127724 -270.372671) (xy 36.210033 -270.392639)
			(xy 36.290072 -270.420341) (xy 36.367115 -270.455525) (xy 36.440465 -270.497874) (xy 36.509457 -270.547003)
			(xy 36.573467 -270.602468) (xy 36.631915 -270.663766) (xy 36.684271 -270.730342) (xy 36.730061 -270.801594)
			(xy 36.768872 -270.876875) (xy 36.800351 -270.955505) (xy 36.824212 -271.036772) (xy 36.840241 -271.119938)
			(xy 36.848292 -271.204252) (xy 36.848796 -271.2466) (xy 36.848409 -271.284884) (xy 36.84187 -271.361173)
			(xy 36.828788 -271.436615) (xy 36.809261 -271.510652) (xy 36.796726 -271.546828) (xy 36.794076 -271.555265)
			(xy 36.794076 -271.572935) (xy 36.796726 -271.581372) (xy 36.808338 -271.614766) (xy 36.826862 -271.683004)
			(xy 36.839896 -271.7525) (xy 36.84397 -271.78762) (xy 36.845629 -271.798121) (xy 36.856273 -271.816498)
			(xy 36.864544 -271.82318) (xy 36.89808 -271.848219) (xy 36.960767 -271.903681) (xy 37.017965 -271.964787)
			(xy 37.06917 -272.030997) (xy 37.113927 -272.101724) (xy 37.151842 -272.176344) (xy 37.182578 -272.254196)
			(xy 37.205864 -272.334591) (xy 37.221494 -272.416818) (xy 37.22933 -272.50015) (xy 37.229796 -272.542)
			(xy 37.229409 -272.580284) (xy 37.22287 -272.656573) (xy 37.209788 -272.732015) (xy 37.190261 -272.806052)
			(xy 37.177726 -272.842228) (xy 37.175076 -272.850665) (xy 37.175076 -272.868335) (xy 37.177726 -272.876772)
			(xy 37.190251 -272.912951) (xy 37.209759 -272.98699) (xy 37.222839 -273.062431) (xy 37.229394 -273.138717)
			(xy 37.229796 -273.177) (xy 37.229409 -273.215284) (xy 37.22287 -273.291573) (xy 37.209788 -273.367015)
			(xy 37.190261 -273.441052) (xy 37.177726 -273.477228) (xy 37.175076 -273.485665) (xy 37.175076 -273.503335)
			(xy 37.177726 -273.511772) (xy 37.190251 -273.547951) (xy 37.209759 -273.62199) (xy 37.222839 -273.697431)
			(xy 37.229394 -273.773717) (xy 37.229796 -273.812) (xy 37.229292 -273.854348) (xy 37.221241 -273.938662)
			(xy 37.205212 -274.021828) (xy 37.181351 -274.103095) (xy 37.149872 -274.181725) (xy 37.111061 -274.257006)
			(xy 37.065271 -274.328258) (xy 37.012915 -274.394834) (xy 36.954467 -274.456132) (xy 36.890457 -274.511597)
			(xy 36.821465 -274.560726) (xy 36.748115 -274.603075) (xy 36.671072 -274.638259) (xy 36.591033 -274.665961)
			(xy 36.508724 -274.685929) (xy 36.424889 -274.697982) (xy 36.340288 -274.702013) (xy 36.255687 -274.697982)
			(xy 36.171852 -274.685929) (xy 36.089543 -274.665961) (xy 36.009504 -274.638259) (xy 35.932461 -274.603075)
			(xy 35.859111 -274.560726) (xy 35.790119 -274.511597) (xy 35.726109 -274.456132) (xy 35.667661 -274.394834)
			(xy 35.615305 -274.328258) (xy 35.569515 -274.257006) (xy 35.530704 -274.181725) (xy 35.499225 -274.103095)
			(xy 35.475364 -274.021828) (xy 35.459335 -273.938662) (xy 35.451284 -273.854348) (xy 35.45078 -273.812)
			(xy 35.451168 -273.773716) (xy 35.457707 -273.697427) (xy 35.470789 -273.621985) (xy 35.490315 -273.547948)
			(xy 35.50285 -273.511772) (xy 35.505501 -273.503335) (xy 35.505501 -273.485665) (xy 35.50285 -273.477228)
			(xy 35.490324 -273.44105) (xy 35.470817 -273.36701) (xy 35.457737 -273.291569) (xy 35.451182 -273.215283)
			(xy 35.45078 -273.177) (xy 35.451168 -273.138716) (xy 35.457707 -273.062427) (xy 35.470789 -272.986985)
			(xy 35.490315 -272.912948) (xy 35.50285 -272.876772) (xy 35.505501 -272.868335) (xy 35.505501 -272.850665)
			(xy 35.50285 -272.842228) (xy 35.491237 -272.808834) (xy 35.472714 -272.740596) (xy 35.45968 -272.6711)
			(xy 35.455606 -272.63598) (xy 35.453956 -272.625477) (xy 35.443306 -272.6071) (xy 35.435032 -272.60042)
			(xy 35.40149 -272.575388) (xy 35.338805 -272.519925) (xy 35.281607 -272.458817) (xy 35.230404 -272.392607)
			(xy 35.185647 -272.321878) (xy 35.147733 -272.247258) (xy 35.116997 -272.169406) (xy 35.093711 -272.08901)
			(xy 35.078081 -272.006782) (xy 35.070246 -271.92345) (xy 35.06978 -271.8816) (xy 14.957254 -271.8816)
			(xy 14.988761 -271.959768) (xy 15.012909 -272.041451) (xy 15.029139 -272.125067) (xy 15.037304 -272.209852)
			(xy 15.037816 -272.25244) (xy 15.037301 -272.294982) (xy 15.029153 -272.379674) (xy 15.012965 -272.463203)
			(xy 14.988883 -272.544808) (xy 14.957128 -272.623744) (xy 14.917989 -272.69929) (xy 14.895322 -272.735294)
			(xy 14.890471 -272.743746) (xy 14.886786 -272.76286) (xy 14.890442 -272.78198) (xy 14.895322 -272.790412)
			(xy 14.917954 -272.8264) (xy 14.957014 -272.901917) (xy 14.988686 -272.980818) (xy 15.012682 -273.062382)
			(xy 15.028783 -273.145864) (xy 15.036841 -273.230501) (xy 15.037308 -273.273012) (xy 15.036814 -273.315595)
			(xy 15.028708 -273.400373) (xy 15.012534 -273.483988) (xy 14.988439 -273.565674) (xy 14.956644 -273.644681)
			(xy 14.937486 -273.682714) (xy 14.932476 -273.693937) (xy 14.93248 -273.718479) (xy 14.937486 -273.729704)
			(xy 14.956636 -273.76774) (xy 14.988426 -273.846749) (xy 15.012521 -273.928434) (xy 15.028702 -274.012047)
			(xy 15.036819 -274.096824) (xy 15.037308 -274.139406) (xy 15.036804 -274.181754) (xy 15.028753 -274.266068)
			(xy 15.012724 -274.349234) (xy 14.988863 -274.430501) (xy 14.957384 -274.509131) (xy 14.918573 -274.584412)
			(xy 14.872783 -274.655664) (xy 14.820427 -274.72224) (xy 14.761979 -274.783538) (xy 14.697969 -274.839003)
			(xy 14.628977 -274.888132) (xy 14.555627 -274.930481) (xy 14.478584 -274.965665) (xy 14.398545 -274.993367)
			(xy 14.316236 -275.013335) (xy 14.232401 -275.025388) (xy 14.1478 -275.029419) (xy 14.063199 -275.025388)
			(xy 13.979364 -275.013335) (xy 13.897055 -274.993367) (xy 13.817016 -274.965665) (xy 13.739973 -274.930481)
			(xy 13.666623 -274.888132) (xy 13.597631 -274.839003) (xy 13.533621 -274.783538) (xy 13.475173 -274.72224)
			(xy 13.422817 -274.655664) (xy 13.377027 -274.584412) (xy 13.338216 -274.509131) (xy 13.306737 -274.430501)
			(xy 13.282876 -274.349234) (xy 13.266847 -274.266068) (xy 13.258796 -274.181754) (xy 13.258292 -274.139406)
			(xy 0.509016 -274.139406) (xy 0.509016 -277.895304) (xy 13.241528 -277.895304) (xy 13.242039 -277.852716)
			(xy 13.250206 -277.767931) (xy 13.266437 -277.684315) (xy 13.290584 -277.602632) (xy 13.322425 -277.523631)
			(xy 13.341604 -277.485602) (xy 13.346812 -277.474423) (xy 13.346815 -277.449789) (xy 13.341604 -277.438612)
			(xy 13.322411 -277.40059) (xy 13.29057 -277.321587) (xy 13.266425 -277.239903) (xy 13.250198 -277.156285)
			(xy 13.242037 -277.071499) (xy 13.241528 -277.02891) (xy 13.242032 -276.986549) (xy 13.250085 -276.902212)
			(xy 13.266119 -276.819022) (xy 13.289987 -276.737732) (xy 13.321475 -276.65908) (xy 13.360297 -276.583777)
			(xy 13.4061 -276.512505) (xy 13.458471 -276.445909) (xy 13.516936 -276.384594) (xy 13.580964 -276.329113)
			(xy 13.649976 -276.27997) (xy 13.723346 -276.23761) (xy 13.800411 -276.202415) (xy 13.880473 -276.174706)
			(xy 13.962806 -276.154732) (xy 14.046665 -276.142675) (xy 14.13129 -276.138644) (xy 14.215915 -276.142675)
			(xy 14.299774 -276.154732) (xy 14.382107 -276.174706) (xy 14.462169 -276.202415) (xy 14.539234 -276.23761)
			(xy 14.612604 -276.27997) (xy 14.681616 -276.329113) (xy 14.745644 -276.384594) (xy 14.804109 -276.445909)
			(xy 14.85648 -276.512505) (xy 14.902283 -276.583777) (xy 14.941105 -276.65908) (xy 14.972593 -276.737732)
			(xy 14.996461 -276.819022) (xy 15.012495 -276.902212) (xy 15.020548 -276.986549) (xy 15.021052 -277.02891)
			(xy 15.020549 -277.071499) (xy 15.01238 -277.156283) (xy 14.996148 -277.2399) (xy 14.971999 -277.321582)
			(xy 14.940156 -277.400583) (xy 14.920976 -277.438612) (xy 14.915968 -277.449836) (xy 14.915971 -277.474377)
			(xy 14.920976 -277.485602) (xy 14.940173 -277.523622) (xy 14.972013 -277.602626) (xy 14.996157 -277.68431)
			(xy 15.012383 -277.767929) (xy 15.020543 -277.852715) (xy 15.021052 -277.895304) (xy 15.020548 -277.937665)
			(xy 15.012495 -278.022002) (xy 14.996461 -278.105192) (xy 14.972593 -278.186482) (xy 14.941105 -278.265134)
			(xy 14.902283 -278.340437) (xy 14.85648 -278.411709) (xy 14.804109 -278.478305) (xy 14.745644 -278.53962)
			(xy 14.681616 -278.595101) (xy 14.612604 -278.644244) (xy 14.539234 -278.686604) (xy 14.462169 -278.721799)
			(xy 14.382107 -278.749508) (xy 14.318249 -278.765) (xy 35.45078 -278.765) (xy 35.451168 -278.726716)
			(xy 35.457707 -278.650427) (xy 35.470789 -278.574985) (xy 35.490315 -278.500948) (xy 35.50285 -278.464772)
			(xy 35.505501 -278.456335) (xy 35.505501 -278.438665) (xy 35.50285 -278.430228) (xy 35.490324 -278.39405)
			(xy 35.470817 -278.32001) (xy 35.457737 -278.244569) (xy 35.451182 -278.168283) (xy 35.45078 -278.13)
			(xy 35.451168 -278.091716) (xy 35.457707 -278.015427) (xy 35.470789 -277.939985) (xy 35.490315 -277.865948)
			(xy 35.50285 -277.829772) (xy 35.505501 -277.821335) (xy 35.505501 -277.803665) (xy 35.50285 -277.795228)
			(xy 35.490324 -277.75905) (xy 35.470817 -277.68501) (xy 35.457737 -277.609569) (xy 35.451182 -277.533283)
			(xy 35.45078 -277.495) (xy 35.451284 -277.452652) (xy 35.459335 -277.368338) (xy 35.475364 -277.285172)
			(xy 35.499225 -277.203905) (xy 35.530704 -277.125275) (xy 35.569515 -277.049994) (xy 35.615305 -276.978742)
			(xy 35.667661 -276.912166) (xy 35.726109 -276.850868) (xy 35.790119 -276.795403) (xy 35.859111 -276.746274)
			(xy 35.932461 -276.703925) (xy 36.009504 -276.668741) (xy 36.089543 -276.641039) (xy 36.171852 -276.621071)
			(xy 36.255687 -276.609018) (xy 36.340288 -276.604988) (xy 36.424889 -276.609018) (xy 36.508724 -276.621071)
			(xy 36.591033 -276.641039) (xy 36.671072 -276.668741) (xy 36.748115 -276.703925) (xy 36.821465 -276.746274)
			(xy 36.890457 -276.795403) (xy 36.954467 -276.850868) (xy 37.012915 -276.912166) (xy 37.065271 -276.978742)
			(xy 37.111061 -277.049994) (xy 37.149872 -277.125275) (xy 37.181351 -277.203905) (xy 37.205212 -277.285172)
			(xy 37.221241 -277.368338) (xy 37.229292 -277.452652) (xy 37.229796 -277.495) (xy 37.229409 -277.533284)
			(xy 37.22287 -277.609573) (xy 37.209788 -277.685015) (xy 37.190261 -277.759052) (xy 37.177726 -277.795228)
			(xy 37.175076 -277.803665) (xy 37.175076 -277.821335) (xy 37.177726 -277.829772) (xy 37.190251 -277.865951)
			(xy 37.209759 -277.93999) (xy 37.222839 -278.015431) (xy 37.229394 -278.091717) (xy 37.229796 -278.13)
			(xy 37.229409 -278.168284) (xy 37.22287 -278.244573) (xy 37.209788 -278.320015) (xy 37.190261 -278.394052)
			(xy 37.177726 -278.430228) (xy 37.175076 -278.438665) (xy 37.175076 -278.456335) (xy 37.177726 -278.464772)
			(xy 37.190251 -278.500951) (xy 37.209759 -278.57499) (xy 37.222839 -278.650431) (xy 37.229394 -278.726717)
			(xy 37.229796 -278.765) (xy 37.229292 -278.807348) (xy 37.221241 -278.891662) (xy 37.205212 -278.974828)
			(xy 37.181351 -279.056095) (xy 37.149872 -279.134725) (xy 37.111061 -279.210006) (xy 37.065271 -279.281258)
			(xy 37.012915 -279.347834) (xy 36.954467 -279.409132) (xy 36.890457 -279.464597) (xy 36.821465 -279.513726)
			(xy 36.748115 -279.556075) (xy 36.671072 -279.591259) (xy 36.591033 -279.618961) (xy 36.508724 -279.638929)
			(xy 36.424889 -279.650982) (xy 36.340288 -279.655013) (xy 36.255687 -279.650982) (xy 36.171852 -279.638929)
			(xy 36.089543 -279.618961) (xy 36.009504 -279.591259) (xy 35.932461 -279.556075) (xy 35.859111 -279.513726)
			(xy 35.790119 -279.464597) (xy 35.726109 -279.409132) (xy 35.667661 -279.347834) (xy 35.615305 -279.281258)
			(xy 35.569515 -279.210006) (xy 35.530704 -279.134725) (xy 35.499225 -279.056095) (xy 35.475364 -278.974828)
			(xy 35.459335 -278.891662) (xy 35.451284 -278.807348) (xy 35.45078 -278.765) (xy 14.318249 -278.765)
			(xy 14.299774 -278.769482) (xy 14.215915 -278.781539) (xy 14.13129 -278.785571) (xy 14.046665 -278.781539)
			(xy 13.962806 -278.769482) (xy 13.880473 -278.749508) (xy 13.800411 -278.721799) (xy 13.723346 -278.686604)
			(xy 13.649976 -278.644244) (xy 13.580964 -278.595101) (xy 13.516936 -278.53962) (xy 13.458471 -278.478305)
			(xy 13.4061 -278.411709) (xy 13.360297 -278.340437) (xy 13.321475 -278.265134) (xy 13.289987 -278.186482)
			(xy 13.266119 -278.105192) (xy 13.250085 -278.022002) (xy 13.242032 -277.937665) (xy 13.241528 -277.895304)
			(xy 0.509016 -277.895304) (xy 0.509016 -281.2542) (xy 3.936492 -281.2542) (xy 3.937075 -281.207804)
			(xy 3.94672 -281.115516) (xy 3.965916 -281.024732) (xy 3.994454 -280.936439) (xy 4.012692 -280.893774)
			(xy 4.016498 -280.883832) (xy 4.016498 -280.862568) (xy 4.012692 -280.852626) (xy 3.994447 -280.809964)
			(xy 3.965903 -280.721671) (xy 3.94671 -280.630886) (xy 3.937077 -280.538596) (xy 3.936492 -280.4922)
			(xy 3.936967 -280.451098) (xy 3.944552 -280.369243) (xy 3.959657 -280.288438) (xy 3.982153 -280.209371)
			(xy 4.011849 -280.132717) (xy 4.048491 -280.05913) (xy 4.091766 -279.989238) (xy 4.141306 -279.923637)
			(xy 4.196687 -279.862887) (xy 4.257437 -279.807506) (xy 4.323038 -279.757966) (xy 4.39293 -279.714691)
			(xy 4.466517 -279.678049) (xy 4.543171 -279.648353) (xy 4.622238 -279.625857) (xy 4.703043 -279.610752)
			(xy 4.784898 -279.603167) (xy 4.826 -279.602692) (xy 4.872396 -279.603275) (xy 4.964684 -279.61292)
			(xy 5.055468 -279.632116) (xy 5.143761 -279.660654) (xy 5.186426 -279.678892) (xy 5.196368 -279.682698)
			(xy 5.217632 -279.682698) (xy 5.227574 -279.678892) (xy 5.270236 -279.660647) (xy 5.358529 -279.632103)
			(xy 5.449314 -279.61291) (xy 5.541604 -279.603277) (xy 5.588 -279.602692) (xy 5.634396 -279.603275)
			(xy 5.726684 -279.61292) (xy 5.817468 -279.632116) (xy 5.905761 -279.660654) (xy 5.948426 -279.678892)
			(xy 5.958368 -279.682698) (xy 5.979632 -279.682698) (xy 5.989574 -279.678892) (xy 6.032236 -279.660647)
			(xy 6.120529 -279.632103) (xy 6.211314 -279.61291) (xy 6.303604 -279.603277) (xy 6.35 -279.602692)
			(xy 6.391102 -279.603167) (xy 6.472957 -279.610752) (xy 6.553762 -279.625857) (xy 6.632829 -279.648353)
			(xy 6.709483 -279.678049) (xy 6.78307 -279.714691) (xy 6.852962 -279.757966) (xy 6.918563 -279.807506)
			(xy 6.979313 -279.862887) (xy 7.034694 -279.923637) (xy 7.084234 -279.989238) (xy 7.127509 -280.05913)
			(xy 7.164151 -280.132717) (xy 7.193847 -280.209371) (xy 7.216343 -280.288438) (xy 7.231448 -280.369243)
			(xy 7.239033 -280.451098) (xy 7.239508 -280.4922) (xy 7.238925 -280.538596) (xy 7.22928 -280.630884)
			(xy 7.210084 -280.721668) (xy 7.181546 -280.809961) (xy 7.163308 -280.852626) (xy 7.159502 -280.862568)
			(xy 7.159502 -280.883832) (xy 7.163308 -280.893774) (xy 7.181553 -280.936436) (xy 7.210097 -281.024729)
			(xy 7.22435 -281.092148) (xy 44.946824 -281.092148) (xy 44.947421 -281.045753) (xy 44.957062 -280.953465)
			(xy 44.976253 -280.862681) (xy 45.004788 -280.774387) (xy 45.023024 -280.731722) (xy 45.026799 -280.721771)
			(xy 45.026818 -280.700516) (xy 45.023024 -280.690574) (xy 45.004797 -280.647904) (xy 44.976248 -280.559615)
			(xy 44.95705 -280.468832) (xy 44.947411 -280.376543) (xy 44.946824 -280.330148) (xy 44.947298 -280.289045)
			(xy 44.954879 -280.207188) (xy 44.969981 -280.126381) (xy 44.992475 -280.047312) (xy 45.022169 -279.970655)
			(xy 45.058809 -279.897066) (xy 45.102084 -279.827172) (xy 45.151623 -279.761568) (xy 45.207005 -279.700816)
			(xy 45.267756 -279.645434) (xy 45.333358 -279.595893) (xy 45.403252 -279.552617) (xy 45.476841 -279.515975)
			(xy 45.553496 -279.48628) (xy 45.632565 -279.463785) (xy 45.713373 -279.448681) (xy 45.795229 -279.441099)
			(xy 45.836332 -279.44064) (xy 45.882727 -279.441243) (xy 45.975015 -279.450881) (xy 46.065799 -279.470071)
			(xy 46.154093 -279.498605) (xy 46.196758 -279.51684) (xy 46.2067 -279.520646) (xy 46.227964 -279.520646)
			(xy 46.237906 -279.51684) (xy 46.280565 -279.498588) (xy 46.368858 -279.470045) (xy 46.459645 -279.450854)
			(xy 46.551936 -279.441223) (xy 46.598332 -279.44064) (xy 46.644727 -279.441243) (xy 46.737015 -279.450881)
			(xy 46.827799 -279.470071) (xy 46.916093 -279.498605) (xy 46.958758 -279.51684) (xy 46.9687 -279.520646)
			(xy 46.989964 -279.520646) (xy 46.999906 -279.51684) (xy 47.042565 -279.498588) (xy 47.130858 -279.470045)
			(xy 47.221645 -279.450854) (xy 47.313936 -279.441223) (xy 47.360332 -279.44064) (xy 47.401437 -279.441022)
			(xy 47.483296 -279.44861) (xy 47.564106 -279.463719) (xy 47.643177 -279.48622) (xy 47.719835 -279.515921)
			(xy 47.793425 -279.552568) (xy 47.86332 -279.595849) (xy 47.928923 -279.645395) (xy 47.989674 -279.700782)
			(xy 48.045056 -279.761539) (xy 48.094596 -279.827146) (xy 48.137871 -279.897045) (xy 48.174511 -279.970638)
			(xy 48.204205 -280.047299) (xy 48.226699 -280.126372) (xy 48.241801 -280.207183) (xy 48.249382 -280.289043)
			(xy 48.24984 -280.330148) (xy 48.249245 -280.376543) (xy 48.239604 -280.468831) (xy 48.220412 -280.559615)
			(xy 48.191877 -280.647909) (xy 48.17364 -280.690574) (xy 48.169804 -280.700507) (xy 48.169823 -280.72178)
			(xy 48.17364 -280.731722) (xy 48.19187 -280.77439) (xy 48.220417 -280.862681) (xy 48.239614 -280.953464)
			(xy 48.249252 -281.045752) (xy 48.24984 -281.092148) (xy 48.249379 -281.13325) (xy 48.24179 -281.215104)
			(xy 48.226682 -281.295908) (xy 48.204182 -281.374974) (xy 48.174484 -281.451627) (xy 48.13784 -281.525212)
			(xy 48.094563 -281.595103) (xy 48.045023 -281.660703) (xy 47.989641 -281.721453) (xy 47.928891 -281.776833)
			(xy 47.86329 -281.826373) (xy 47.793398 -281.869648) (xy 47.719812 -281.906291) (xy 47.643159 -281.935987)
			(xy 47.564093 -281.958485) (xy 47.483288 -281.973593) (xy 47.401434 -281.98118) (xy 47.360332 -281.981656)
			(xy 47.313937 -281.981066) (xy 47.221648 -281.971424) (xy 47.130864 -281.95223) (xy 47.042571 -281.923693)
			(xy 46.999906 -281.905456) (xy 46.989964 -281.90165) (xy 46.9687 -281.90165) (xy 46.958758 -281.905456)
			(xy 46.91609 -281.923687) (xy 46.8278 -281.952235) (xy 46.737017 -281.971432) (xy 46.644728 -281.981069)
			(xy 46.598332 -281.981656) (xy 46.551937 -281.981066) (xy 46.459648 -281.971424) (xy 46.368864 -281.95223)
			(xy 46.280571 -281.923693) (xy 46.237906 -281.905456) (xy 46.227964 -281.90165) (xy 46.2067 -281.90165)
			(xy 46.196758 -281.905456) (xy 46.15409 -281.923687) (xy 46.0658 -281.952235) (xy 45.975017 -281.971432)
			(xy 45.882728 -281.981069) (xy 45.836332 -281.981656) (xy 45.795231 -281.981103) (xy 45.713381 -281.973521)
			(xy 45.632579 -281.95842) (xy 45.553515 -281.935928) (xy 45.476863 -281.906236) (xy 45.403278 -281.869599)
			(xy 45.333388 -281.826329) (xy 45.267788 -281.776795) (xy 45.207038 -281.721419) (xy 45.151657 -281.660674)
			(xy 45.102116 -281.595078) (xy 45.05884 -281.525192) (xy 45.022196 -281.45161) (xy 44.992498 -281.374961)
			(xy 44.969998 -281.295899) (xy 44.95489 -281.215099) (xy 44.947301 -281.133249) (xy 44.946824 -281.092148)
			(xy 7.22435 -281.092148) (xy 7.22929 -281.115514) (xy 7.238923 -281.207804) (xy 7.239508 -281.2542)
			(xy 7.239033 -281.295302) (xy 7.231448 -281.377157) (xy 7.216343 -281.457962) (xy 7.193847 -281.537029)
			(xy 7.164151 -281.613683) (xy 7.127509 -281.68727) (xy 7.084234 -281.757162) (xy 7.034694 -281.822763)
			(xy 6.979313 -281.883513) (xy 6.918563 -281.938894) (xy 6.852962 -281.988434) (xy 6.78307 -282.031709)
			(xy 6.709483 -282.068351) (xy 6.632829 -282.098047) (xy 6.553762 -282.120543) (xy 6.472957 -282.135648)
			(xy 6.391102 -282.143233) (xy 6.35 -282.143708) (xy 6.303604 -282.143125) (xy 6.211316 -282.13348)
			(xy 6.120532 -282.114284) (xy 6.032239 -282.085746) (xy 5.989574 -282.067508) (xy 5.979632 -282.063702)
			(xy 5.958368 -282.063702) (xy 5.948426 -282.067508) (xy 5.905764 -282.085753) (xy 5.817471 -282.114297)
			(xy 5.726686 -282.13349) (xy 5.634396 -282.143123) (xy 5.588 -282.143708) (xy 5.541604 -282.143125)
			(xy 5.449316 -282.13348) (xy 5.358532 -282.114284) (xy 5.270239 -282.085746) (xy 5.227574 -282.067508)
			(xy 5.217632 -282.063702) (xy 5.196368 -282.063702) (xy 5.186426 -282.067508) (xy 5.143764 -282.085753)
			(xy 5.055471 -282.114297) (xy 4.964686 -282.13349) (xy 4.872396 -282.143123) (xy 4.826 -282.143708)
			(xy 4.784898 -282.143233) (xy 4.703043 -282.135648) (xy 4.622238 -282.120543) (xy 4.543171 -282.098047)
			(xy 4.466517 -282.068351) (xy 4.39293 -282.031709) (xy 4.323038 -281.988434) (xy 4.257437 -281.938894)
			(xy 4.196687 -281.883513) (xy 4.141306 -281.822763) (xy 4.091766 -281.757162) (xy 4.048491 -281.68727)
			(xy 4.011849 -281.613683) (xy 3.982153 -281.537029) (xy 3.959657 -281.457962) (xy 3.944552 -281.377157)
			(xy 3.936967 -281.295302) (xy 3.936492 -281.2542) (xy 0.509016 -281.2542) (xy 0.509016 -287.410144)
			(xy 6.441451 -287.410144) (xy 6.445429 -287.310151) (xy 6.457339 -287.210791) (xy 6.477106 -287.11269)
			(xy 6.504605 -287.016471) (xy 6.539661 -286.92274) (xy 6.582053 -286.832091) (xy 6.631514 -286.745097)
			(xy 6.68773 -286.662307) (xy 6.750346 -286.584245) (xy 6.818965 -286.511405) (xy 6.893156 -286.444247)
			(xy 6.972447 -286.383195) (xy 7.056338 -286.328637) (xy 7.144299 -286.280916) (xy 7.235773 -286.240334)
			(xy 7.330182 -286.207148) (xy 7.426929 -286.181568) (xy 7.525403 -286.163755) (xy 7.624981 -286.153823)
			(xy 7.725033 -286.151833) (xy 7.824927 -286.157799) (xy 7.924031 -286.171683) (xy 8.021719 -286.193396)
			(xy 8.117373 -286.222802) (xy 8.210388 -286.259715) (xy 8.300176 -286.303901) (xy 8.38617 -286.355082)
			(xy 8.467826 -286.412932) (xy 8.544627 -286.477088) (xy 8.616089 -286.547142) (xy 8.681759 -286.622653)
			(xy 8.741221 -286.703143) (xy 8.794101 -286.788102) (xy 8.840064 -286.876994) (xy 8.878819 -286.969257)
			(xy 8.910121 -287.064307) (xy 8.933773 -287.161544) (xy 8.949624 -287.260353) (xy 8.957574 -287.360108)
			(xy 8.958072 -287.410144) (xy 8.957574 -287.46018) (xy 8.949624 -287.559935) (xy 8.933773 -287.658744)
			(xy 8.910121 -287.755981) (xy 8.878819 -287.851031) (xy 8.840064 -287.943294) (xy 8.838096 -287.9471)
			(xy 18.94205 -287.9471) (xy 18.94246 -287.906019) (xy 18.950041 -287.824207) (xy 18.965139 -287.743444)
			(xy 18.987625 -287.664418) (xy 19.017306 -287.587805) (xy 19.05393 -287.514257) (xy 19.097185 -287.444402)
			(xy 19.1467 -287.378836) (xy 19.202054 -287.318119) (xy 19.262774 -287.262768) (xy 19.328343 -287.213256)
			(xy 19.3982 -287.170006) (xy 19.47175 -287.133386) (xy 19.548366 -287.103709) (xy 19.627393 -287.081228)
			(xy 19.708157 -287.066135) (xy 19.789969 -287.058558) (xy 19.83105 -287.0581) (xy 19.870063 -287.05851)
			(xy 19.947792 -287.065313) (xy 20.024625 -287.078906) (xy 20.099971 -287.099184) (xy 20.173247 -287.125991)
			(xy 20.208748 -287.142174) (xy 20.213384 -287.144246) (xy 20.223239 -287.146683) (xy 20.228306 -287.147)
			(xy 20.270825 -287.149195) (xy 20.355189 -287.160702) (xy 20.438068 -287.180216) (xy 20.518704 -287.20756)
			(xy 20.596358 -287.242482) (xy 20.670321 -287.284663) (xy 20.739915 -287.333718) (xy 20.804505 -287.389198)
			(xy 20.863498 -287.450595) (xy 20.916356 -287.517347) (xy 20.962594 -287.588843) (xy 21.00179 -287.66443)
			(xy 21.033585 -287.743416) (xy 21.057689 -287.825079) (xy 21.07388 -287.908671) (xy 21.082011 -287.993427)
			(xy 21.082508 -288.036) (xy 21.082033 -288.077102) (xy 21.074448 -288.158957) (xy 21.059343 -288.239762)
			(xy 21.036847 -288.318829) (xy 21.007151 -288.395483) (xy 20.970509 -288.46907) (xy 20.927234 -288.538962)
			(xy 20.877694 -288.604563) (xy 20.822313 -288.665313) (xy 20.761563 -288.720694) (xy 20.695962 -288.770234)
			(xy 20.62607 -288.813509) (xy 20.552483 -288.850151) (xy 20.475829 -288.879847) (xy 20.396762 -288.902343)
			(xy 20.315957 -288.917448) (xy 20.234458 -288.925) (xy 30.478988 -288.925) (xy 30.483018 -288.840399)
			(xy 30.495071 -288.756564) (xy 30.515039 -288.674255) (xy 30.542741 -288.594216) (xy 30.577925 -288.517173)
			(xy 30.620274 -288.443823) (xy 30.669403 -288.374831) (xy 30.724868 -288.310821) (xy 30.786166 -288.252373)
			(xy 30.852742 -288.200017) (xy 30.923994 -288.154227) (xy 30.999275 -288.115416) (xy 31.077905 -288.083937)
			(xy 31.159172 -288.060076) (xy 31.242338 -288.044047) (xy 31.326652 -288.035996) (xy 31.369 -288.035492)
			(xy 31.412701 -288.03601) (xy 31.499683 -288.044548) (xy 31.58541 -288.061571) (xy 31.669056 -288.086916)
			(xy 31.749814 -288.120338) (xy 31.826907 -288.161515) (xy 31.863538 -288.185352) (xy 31.872793 -288.190951)
			(xy 31.894112 -288.194494) (xy 31.904686 -288.19221) (xy 31.94168 -288.18291) (xy 32.01685 -288.169911)
			(xy 32.092857 -288.163397) (xy 32.131 -288.163) (xy 32.173324 -288.163504) (xy 32.25759 -288.17155)
			(xy 32.340709 -288.18757) (xy 32.421928 -288.211418) (xy 32.500513 -288.242879) (xy 32.575752 -288.281667)
			(xy 32.646963 -288.327431) (xy 32.713501 -288.379758) (xy 32.774764 -288.438172) (xy 32.830197 -288.502145)
			(xy 32.879298 -288.571098) (xy 32.921623 -288.644406) (xy 32.956787 -288.721405) (xy 32.984473 -288.801398)
			(xy 33.00443 -288.88366) (xy 33.016476 -288.967447) (xy 33.020504 -289.052) (xy 33.016476 -289.136553)
			(xy 33.00443 -289.22034) (xy 32.984473 -289.302602) (xy 32.956787 -289.382595) (xy 32.921623 -289.459594)
			(xy 32.879298 -289.532902) (xy 32.830197 -289.601855) (xy 32.774764 -289.665828) (xy 32.713501 -289.724242)
			(xy 32.646963 -289.776569) (xy 32.575752 -289.822333) (xy 32.500513 -289.861121) (xy 32.421928 -289.892582)
			(xy 32.340709 -289.91643) (xy 32.25759 -289.93245) (xy 32.173324 -289.940496) (xy 32.131 -289.941)
			(xy 32.087445 -289.940479) (xy 32.000752 -289.931972) (xy 31.915306 -289.915028) (xy 31.831926 -289.889812)
			(xy 31.751411 -289.856563) (xy 31.674532 -289.815601) (xy 31.637986 -289.791902) (xy 31.628726 -289.786315)
			(xy 31.607411 -289.782766) (xy 31.596838 -289.785044) (xy 31.559601 -289.794444) (xy 31.483927 -289.807574)
			(xy 31.407403 -289.814134) (xy 31.369 -289.814508) (xy 31.326652 -289.814004) (xy 31.242338 -289.805953)
			(xy 31.159172 -289.789924) (xy 31.077905 -289.766063) (xy 30.999275 -289.734584) (xy 30.923994 -289.695773)
			(xy 30.852742 -289.649983) (xy 30.786166 -289.597627) (xy 30.724868 -289.539179) (xy 30.669403 -289.475169)
			(xy 30.620274 -289.406177) (xy 30.577925 -289.332827) (xy 30.542741 -289.255784) (xy 30.515039 -289.175745)
			(xy 30.495071 -289.093436) (xy 30.483018 -289.009601) (xy 30.478988 -288.925) (xy 20.234458 -288.925)
			(xy 20.234102 -288.925033) (xy 20.193 -288.925508) (xy 20.153679 -288.925088) (xy 20.075343 -288.918178)
			(xy 19.997922 -288.904376) (xy 19.922024 -288.88379) (xy 19.84824 -288.856581) (xy 19.812508 -288.840164)
			(xy 19.807876 -288.838082) (xy 19.798019 -288.835651) (xy 19.79295 -288.835338) (xy 19.750554 -288.833021)
			(xy 19.666452 -288.821301) (xy 19.583852 -288.801616) (xy 19.503504 -288.774146) (xy 19.426142 -288.73914)
			(xy 19.352469 -288.696918) (xy 19.283158 -288.647865) (xy 19.218839 -288.592426) (xy 19.160098 -288.531108)
			(xy 19.107471 -288.464469) (xy 19.061438 -288.393116) (xy 19.022417 -288.317699) (xy 18.990764 -288.238905)
			(xy 18.966767 -288.157453) (xy 18.950646 -288.074083) (xy 18.942546 -287.989557) (xy 18.94205 -287.9471)
			(xy 8.838096 -287.9471) (xy 8.794101 -288.032186) (xy 8.741221 -288.117145) (xy 8.681759 -288.197635)
			(xy 8.616089 -288.273146) (xy 8.544627 -288.3432) (xy 8.467826 -288.407356) (xy 8.38617 -288.465206)
			(xy 8.300176 -288.516387) (xy 8.210388 -288.560573) (xy 8.117373 -288.597486) (xy 8.021719 -288.626892)
			(xy 7.924031 -288.648605) (xy 7.824927 -288.662489) (xy 7.725033 -288.668455) (xy 7.624981 -288.666465)
			(xy 7.525403 -288.656533) (xy 7.426929 -288.63872) (xy 7.330182 -288.61314) (xy 7.235773 -288.579954)
			(xy 7.144299 -288.539372) (xy 7.056338 -288.491651) (xy 6.972447 -288.437093) (xy 6.893156 -288.376041)
			(xy 6.818965 -288.308883) (xy 6.750346 -288.236043) (xy 6.68773 -288.157981) (xy 6.631514 -288.075191)
			(xy 6.582053 -287.988197) (xy 6.539661 -287.897548) (xy 6.504605 -287.803817) (xy 6.477106 -287.707598)
			(xy 6.457339 -287.609497) (xy 6.445429 -287.510137) (xy 6.441451 -287.410144) (xy 0.509016 -287.410144)
			(xy 0.509016 -293.310056) (xy 43.677851 -293.310056) (xy 43.681826 -293.207606) (xy 43.693729 -293.105773)
			(xy 43.713487 -293.005168) (xy 43.740982 -292.906397) (xy 43.776048 -292.810053) (xy 43.818474 -292.716717)
			(xy 43.868006 -292.626949) (xy 43.924346 -292.541289) (xy 43.987154 -292.460253) (xy 44.056052 -292.384327)
			(xy 44.130628 -292.313969) (xy 44.210431 -292.249601) (xy 44.294982 -292.191612) (xy 44.383773 -292.140348)
			(xy 44.476269 -292.09612) (xy 44.571914 -292.059192) (xy 44.670134 -292.029787) (xy 44.770337 -292.008082)
			(xy 44.87192 -291.994206) (xy 44.974274 -291.988245) (xy 45.076781 -291.990233) (xy 45.178826 -292.000159)
			(xy 45.279795 -292.017962) (xy 45.379081 -292.043537) (xy 45.476086 -292.076728) (xy 45.570228 -292.117337)
			(xy 45.66094 -292.165119) (xy 45.747676 -292.219787) (xy 45.829915 -292.281011) (xy 45.907162 -292.348425)
			(xy 45.978953 -292.421622) (xy 46.044856 -292.500162) (xy 46.104475 -292.583572) (xy 46.15745 -292.671352)
			(xy 46.203464 -292.762974) (xy 46.24224 -292.857885) (xy 46.273544 -292.955516) (xy 46.297188 -293.055279)
			(xy 46.31303 -293.156574) (xy 46.320975 -293.258793) (xy 46.321472 -293.310056) (xy 46.320975 -293.361319)
			(xy 46.31303 -293.463538) (xy 46.297188 -293.564833) (xy 46.273544 -293.664596) (xy 46.24224 -293.762227)
			(xy 46.203464 -293.857138) (xy 46.15745 -293.94876) (xy 46.104475 -294.03654) (xy 46.044856 -294.11995)
			(xy 45.978953 -294.19849) (xy 45.907162 -294.271687) (xy 45.829915 -294.339101) (xy 45.747676 -294.400325)
			(xy 45.66094 -294.454993) (xy 45.570228 -294.502775) (xy 45.476086 -294.543384) (xy 45.379081 -294.576575)
			(xy 45.279795 -294.60215) (xy 45.178826 -294.619953) (xy 45.076781 -294.629879) (xy 44.974274 -294.631867)
			(xy 44.87192 -294.625906) (xy 44.770337 -294.61203) (xy 44.670134 -294.590325) (xy 44.571914 -294.56092)
			(xy 44.476269 -294.523992) (xy 44.383773 -294.479764) (xy 44.294982 -294.4285) (xy 44.210431 -294.370511)
			(xy 44.130628 -294.306143) (xy 44.056052 -294.235785) (xy 43.987154 -294.159859) (xy 43.924346 -294.078823)
			(xy 43.868006 -293.993163) (xy 43.818474 -293.903395) (xy 43.776048 -293.810059) (xy 43.740982 -293.713715)
			(xy 43.713487 -293.614944) (xy 43.693729 -293.514339) (xy 43.681826 -293.412506) (xy 43.677851 -293.310056)
			(xy 0.509016 -293.310056) (xy 0.509016 -295.310052) (xy 41.677855 -295.310052) (xy 41.68183 -295.207602)
			(xy 41.693733 -295.105769) (xy 41.713491 -295.005164) (xy 41.740986 -294.906393) (xy 41.776052 -294.810049)
			(xy 41.818478 -294.716713) (xy 41.86801 -294.626945) (xy 41.92435 -294.541285) (xy 41.987158 -294.460249)
			(xy 42.056056 -294.384323) (xy 42.130632 -294.313965) (xy 42.210435 -294.249597) (xy 42.294986 -294.191608)
			(xy 42.383777 -294.140344) (xy 42.476273 -294.096116) (xy 42.571918 -294.059188) (xy 42.670138 -294.029783)
			(xy 42.770341 -294.008078) (xy 42.871924 -293.994202) (xy 42.974278 -293.988241) (xy 43.076785 -293.990229)
			(xy 43.17883 -294.000155) (xy 43.279799 -294.017958) (xy 43.379085 -294.043533) (xy 43.47609 -294.076724)
			(xy 43.570232 -294.117333) (xy 43.660944 -294.165115) (xy 43.74768 -294.219783) (xy 43.829919 -294.281007)
			(xy 43.907166 -294.348421) (xy 43.978957 -294.421618) (xy 44.04486 -294.500158) (xy 44.104479 -294.583568)
			(xy 44.157454 -294.671348) (xy 44.203468 -294.76297) (xy 44.242244 -294.857881) (xy 44.273548 -294.955512)
			(xy 44.297192 -295.055275) (xy 44.313034 -295.15657) (xy 44.320979 -295.258789) (xy 44.321476 -295.310052)
			(xy 44.320979 -295.361315) (xy 44.313034 -295.463534) (xy 44.297192 -295.564829) (xy 44.273548 -295.664592)
			(xy 44.242244 -295.762223) (xy 44.203468 -295.857134) (xy 44.157454 -295.948756) (xy 44.104479 -296.036536)
			(xy 44.04486 -296.119946) (xy 43.978957 -296.198486) (xy 43.907166 -296.271683) (xy 43.829919 -296.339097)
			(xy 43.74768 -296.400321) (xy 43.660944 -296.454989) (xy 43.570232 -296.502771) (xy 43.47609 -296.54338)
			(xy 43.379085 -296.576571) (xy 43.279799 -296.602146) (xy 43.17883 -296.619949) (xy 43.076785 -296.629875)
			(xy 42.974278 -296.631863) (xy 42.871924 -296.625902) (xy 42.770341 -296.612026) (xy 42.670138 -296.590321)
			(xy 42.571918 -296.560916) (xy 42.476273 -296.523988) (xy 42.383777 -296.47976) (xy 42.294986 -296.428496)
			(xy 42.210435 -296.370507) (xy 42.130632 -296.306139) (xy 42.056056 -296.235781) (xy 41.987158 -296.159855)
			(xy 41.92435 -296.078819) (xy 41.86801 -295.993159) (xy 41.818478 -295.903391) (xy 41.776052 -295.810055)
			(xy 41.740986 -295.713711) (xy 41.713491 -295.61494) (xy 41.693733 -295.514335) (xy 41.68183 -295.412502)
			(xy 41.677855 -295.310052) (xy 0.509016 -295.310052) (xy 0.509016 -297.310048) (xy 7.377949 -297.310048)
			(xy 7.381924 -297.207598) (xy 7.393827 -297.105765) (xy 7.413585 -297.00516) (xy 7.44108 -296.906389)
			(xy 7.476146 -296.810045) (xy 7.518572 -296.716709) (xy 7.568104 -296.626941) (xy 7.624444 -296.541281)
			(xy 7.687252 -296.460245) (xy 7.75615 -296.384319) (xy 7.830726 -296.313961) (xy 7.910529 -296.249593)
			(xy 7.99508 -296.191604) (xy 8.083871 -296.14034) (xy 8.176367 -296.096112) (xy 8.272012 -296.059184)
			(xy 8.370232 -296.029779) (xy 8.470435 -296.008074) (xy 8.572018 -295.994198) (xy 8.674372 -295.988237)
			(xy 8.776879 -295.990225) (xy 8.878924 -296.000151) (xy 8.979893 -296.017954) (xy 9.079179 -296.043529)
			(xy 9.176184 -296.07672) (xy 9.270326 -296.117329) (xy 9.361038 -296.165111) (xy 9.447774 -296.219779)
			(xy 9.530013 -296.281003) (xy 9.60726 -296.348417) (xy 9.679051 -296.421614) (xy 9.744954 -296.500154)
			(xy 9.804573 -296.583564) (xy 9.857548 -296.671344) (xy 9.903562 -296.762966) (xy 9.942338 -296.857877)
			(xy 9.973642 -296.955508) (xy 9.997286 -297.055271) (xy 10.013128 -297.156566) (xy 10.021073 -297.258785)
			(xy 10.02157 -297.310048) (xy 10.021073 -297.361311) (xy 10.013128 -297.46353) (xy 9.997286 -297.564825)
			(xy 9.973642 -297.664588) (xy 9.942338 -297.762219) (xy 9.903562 -297.85713) (xy 9.857548 -297.948752)
			(xy 9.804573 -298.036532) (xy 9.744954 -298.119942) (xy 9.679051 -298.198482) (xy 9.60726 -298.271679)
			(xy 9.530013 -298.339093) (xy 9.447774 -298.400317) (xy 9.361038 -298.454985) (xy 9.270326 -298.502767)
			(xy 9.176184 -298.543376) (xy 9.079179 -298.576567) (xy 8.979893 -298.602142) (xy 8.878924 -298.619945)
			(xy 8.776879 -298.629871) (xy 8.674372 -298.631859) (xy 8.572018 -298.625898) (xy 8.470435 -298.612022)
			(xy 8.370232 -298.590317) (xy 8.272012 -298.560912) (xy 8.176367 -298.523984) (xy 8.083871 -298.479756)
			(xy 7.99508 -298.428492) (xy 7.910529 -298.370503) (xy 7.830726 -298.306135) (xy 7.75615 -298.235777)
			(xy 7.687252 -298.159851) (xy 7.624444 -298.078815) (xy 7.568104 -297.993155) (xy 7.518572 -297.903387)
			(xy 7.476146 -297.810051) (xy 7.44108 -297.713707) (xy 7.413585 -297.614936) (xy 7.393827 -297.514331)
			(xy 7.381924 -297.412498) (xy 7.377949 -297.310048) (xy 0.509016 -297.310048) (xy 0.509016 -299.310044)
			(xy 5.377953 -299.310044) (xy 5.381928 -299.207594) (xy 5.393831 -299.105761) (xy 5.413589 -299.005156)
			(xy 5.441084 -298.906385) (xy 5.47615 -298.810041) (xy 5.518576 -298.716705) (xy 5.568108 -298.626937)
			(xy 5.624448 -298.541277) (xy 5.687256 -298.460241) (xy 5.756154 -298.384315) (xy 5.83073 -298.313957)
			(xy 5.910533 -298.249589) (xy 5.995084 -298.1916) (xy 6.083875 -298.140336) (xy 6.176371 -298.096108)
			(xy 6.272016 -298.05918) (xy 6.370236 -298.029775) (xy 6.470439 -298.00807) (xy 6.572022 -297.994194)
			(xy 6.674376 -297.988233) (xy 6.776883 -297.990221) (xy 6.878928 -298.000147) (xy 6.979897 -298.01795)
			(xy 7.079183 -298.043525) (xy 7.176188 -298.076716) (xy 7.27033 -298.117325) (xy 7.361042 -298.165107)
			(xy 7.447778 -298.219775) (xy 7.530017 -298.280999) (xy 7.607264 -298.348413) (xy 7.679055 -298.42161)
			(xy 7.744958 -298.50015) (xy 7.804577 -298.58356) (xy 7.857552 -298.67134) (xy 7.903566 -298.762962)
			(xy 7.942342 -298.857873) (xy 7.973646 -298.955504) (xy 7.99729 -299.055267) (xy 8.013132 -299.156562)
			(xy 8.021077 -299.258781) (xy 8.021574 -299.310044) (xy 8.021077 -299.361307) (xy 8.013132 -299.463526)
			(xy 7.99729 -299.564821) (xy 7.973646 -299.664584) (xy 7.942342 -299.762215) (xy 7.903566 -299.857126)
			(xy 7.857552 -299.948748) (xy 7.842312 -299.974) (xy 30.352492 -299.974) (xy 30.352931 -299.93248)
			(xy 30.360686 -299.849804) (xy 30.37611 -299.76821) (xy 30.399068 -299.688407) (xy 30.429361 -299.61109)
			(xy 30.466726 -299.536932) (xy 30.510837 -299.466578) (xy 30.561311 -299.400639) (xy 30.617709 -299.33969)
			(xy 30.679539 -299.284259) (xy 30.746265 -299.23483) (xy 30.817306 -299.191833) (xy 30.892043 -299.155641)
			(xy 30.969827 -299.12657) (xy 31.049982 -299.104872) (xy 31.131809 -299.090735) (xy 31.173166 -299.087032)
			(xy 31.177635 -299.086561) (xy 31.18632 -299.084258) (xy 31.190438 -299.08246) (xy 31.225448 -299.066822)
			(xy 31.297618 -299.040905) (xy 31.371752 -299.021302) (xy 31.4473 -299.008159) (xy 31.523699 -299.001573)
			(xy 31.56204 -299.00118) (xy 31.603119 -299.001636) (xy 31.684927 -299.00922) (xy 31.765685 -299.024319)
			(xy 31.844706 -299.046806) (xy 31.921316 -299.076487) (xy 31.99486 -299.11311) (xy 32.064711 -299.156362)
			(xy 32.130274 -299.205875) (xy 32.190989 -299.261225) (xy 32.246338 -299.321941) (xy 32.295849 -299.387505)
			(xy 32.3391 -299.457358) (xy 32.375721 -299.530902) (xy 32.405401 -299.607513) (xy 32.427885 -299.686534)
			(xy 32.442983 -299.767293) (xy 32.450565 -299.849101) (xy 32.45104 -299.89018) (xy 32.450492 -299.931563)
			(xy 32.442783 -300.01397) (xy 32.427448 -300.095304) (xy 32.404621 -300.174861) (xy 32.374498 -300.251951)
			(xy 32.33734 -300.325909) (xy 32.29347 -300.396092) (xy 32.243266 -300.461895) (xy 32.187164 -300.522746)
			(xy 32.12565 -300.57812) (xy 32.059255 -300.627538) (xy 31.988554 -300.67057) (xy 31.91416 -300.706845)
			(xy 31.836717 -300.736049) (xy 31.756894 -300.757929) (xy 31.675384 -300.772295) (xy 31.634176 -300.776132)
			(xy 31.62971 -300.776617) (xy 31.621026 -300.778916) (xy 31.616904 -300.780704) (xy 31.581628 -300.796634)
			(xy 31.508851 -300.823008) (xy 31.43406 -300.842968) (xy 31.35782 -300.856361) (xy 31.280704 -300.863087)
			(xy 31.242 -300.863508) (xy 31.200898 -300.863033) (xy 31.119043 -300.855448) (xy 31.038238 -300.840343)
			(xy 30.959171 -300.817847) (xy 30.882517 -300.788151) (xy 30.80893 -300.751509) (xy 30.739038 -300.708234)
			(xy 30.673437 -300.658694) (xy 30.612687 -300.603313) (xy 30.557306 -300.542563) (xy 30.507766 -300.476962)
			(xy 30.464491 -300.40707) (xy 30.427849 -300.333483) (xy 30.398153 -300.256829) (xy 30.375657 -300.177762)
			(xy 30.360552 -300.096957) (xy 30.352967 -300.015102) (xy 30.352492 -299.974) (xy 7.842312 -299.974)
			(xy 7.804577 -300.036528) (xy 7.744958 -300.119938) (xy 7.679055 -300.198478) (xy 7.607264 -300.271675)
			(xy 7.530017 -300.339089) (xy 7.447778 -300.400313) (xy 7.361042 -300.454981) (xy 7.27033 -300.502763)
			(xy 7.176188 -300.543372) (xy 7.079183 -300.576563) (xy 6.979897 -300.602138) (xy 6.878928 -300.619941)
			(xy 6.776883 -300.629867) (xy 6.674376 -300.631855) (xy 6.572022 -300.625894) (xy 6.470439 -300.612018)
			(xy 6.370236 -300.590313) (xy 6.272016 -300.560908) (xy 6.176371 -300.52398) (xy 6.083875 -300.479752)
			(xy 5.995084 -300.428488) (xy 5.910533 -300.370499) (xy 5.83073 -300.306131) (xy 5.756154 -300.235773)
			(xy 5.687256 -300.159847) (xy 5.624448 -300.078811) (xy 5.568108 -299.993151) (xy 5.518576 -299.903383)
			(xy 5.47615 -299.810047) (xy 5.441084 -299.713703) (xy 5.413589 -299.614932) (xy 5.393831 -299.514327)
			(xy 5.381928 -299.412494) (xy 5.377953 -299.310044) (xy 0.509016 -299.310044) (xy 0.509016 -301.103538)
			(xy 18.063972 -301.103538) (xy 18.064496 -301.06246) (xy 18.072073 -300.980653) (xy 18.087166 -300.899895)
			(xy 18.109646 -300.820874) (xy 18.139321 -300.744264) (xy 18.175939 -300.67072) (xy 18.219186 -300.600867)
			(xy 18.268694 -300.535303) (xy 18.32404 -300.474587) (xy 18.384752 -300.419236) (xy 18.450313 -300.369723)
			(xy 18.520162 -300.326471) (xy 18.593704 -300.289848) (xy 18.670312 -300.260167) (xy 18.749331 -300.237681)
			(xy 18.830088 -300.222582) (xy 18.911894 -300.214999) (xy 18.952972 -300.214538) (xy 18.995213 -300.215016)
			(xy 19.079314 -300.223028) (xy 19.162276 -300.238983) (xy 19.24335 -300.262736) (xy 19.321804 -300.294074)
			(xy 19.396932 -300.332714) (xy 19.468055 -300.378307) (xy 19.534532 -300.430442) (xy 19.595762 -300.488648)
			(xy 19.651195 -300.552401) (xy 19.700329 -300.621125) (xy 19.742722 -300.694201) (xy 19.777991 -300.770969)
			(xy 19.805817 -300.850737) (xy 19.82595 -300.932785) (xy 19.832574 -300.974506) (xy 19.834848 -300.985648)
			(xy 19.847507 -301.004504) (xy 19.856958 -301.010828) (xy 19.892904 -301.032565) (xy 19.960952 -301.081831)
			(xy 20.024051 -301.137293) (xy 20.081641 -301.198458) (xy 20.133207 -301.264779) (xy 20.178291 -301.335666)
			(xy 20.216491 -301.410489) (xy 20.247467 -301.488579) (xy 20.270942 -301.569242) (xy 20.286707 -301.651759)
			(xy 20.294623 -301.735395) (xy 20.295108 -301.7774) (xy 20.294633 -301.818502) (xy 20.287048 -301.900357)
			(xy 20.271943 -301.981162) (xy 20.249447 -302.060229) (xy 20.219751 -302.136883) (xy 20.183109 -302.21047)
			(xy 20.139834 -302.280362) (xy 20.090294 -302.345963) (xy 20.034913 -302.406713) (xy 19.974163 -302.462094)
			(xy 19.908562 -302.511634) (xy 19.83867 -302.554909) (xy 19.765083 -302.591551) (xy 19.688429 -302.621247)
			(xy 19.609362 -302.643743) (xy 19.528557 -302.658848) (xy 19.446702 -302.666433) (xy 19.4056 -302.666908)
			(xy 19.363299 -302.666402) (xy 19.279081 -302.658354) (xy 19.196007 -302.642348) (xy 19.114828 -302.618531)
			(xy 19.036275 -302.587116) (xy 18.961058 -302.548387) (xy 18.889857 -302.502694) (xy 18.823314 -302.45045)
			(xy 18.76203 -302.392126) (xy 18.706558 -302.328249) (xy 18.657399 -302.259396) (xy 18.614996 -302.186187)
			(xy 18.579734 -302.109285) (xy 18.55193 -302.029382) (xy 18.531834 -301.947202) (xy 18.525236 -301.905416)
			(xy 18.522983 -301.89421) (xy 18.51034 -301.875211) (xy 18.500852 -301.86884) (xy 18.465024 -301.847076)
			(xy 18.397167 -301.797846) (xy 18.334248 -301.742445) (xy 18.276825 -301.681364) (xy 18.22541 -301.615147)
			(xy 18.180459 -301.544383) (xy 18.142372 -301.4697) (xy 18.111488 -301.391763) (xy 18.08808 -301.311263)
			(xy 18.072357 -301.228916) (xy 18.064458 -301.145455) (xy 18.063972 -301.103538) (xy 0.509016 -301.103538)
			(xy 0.509016 -305.209956) (xy 42.741353 -305.209956) (xy 42.745331 -305.109963) (xy 42.757241 -305.010603)
			(xy 42.777008 -304.912502) (xy 42.804507 -304.816283) (xy 42.839563 -304.722552) (xy 42.881955 -304.631903)
			(xy 42.931416 -304.544909) (xy 42.987632 -304.462119) (xy 43.050248 -304.384057) (xy 43.118867 -304.311217)
			(xy 43.193058 -304.244059) (xy 43.272349 -304.183007) (xy 43.35624 -304.128449) (xy 43.444201 -304.080728)
			(xy 43.535675 -304.040146) (xy 43.630084 -304.00696) (xy 43.726831 -303.98138) (xy 43.825305 -303.963567)
			(xy 43.924883 -303.953635) (xy 44.024935 -303.951645) (xy 44.124829 -303.957611) (xy 44.223933 -303.971495)
			(xy 44.321621 -303.993208) (xy 44.417275 -304.022614) (xy 44.51029 -304.059527) (xy 44.600078 -304.103713)
			(xy 44.686072 -304.154894) (xy 44.767728 -304.212744) (xy 44.844529 -304.2769) (xy 44.915991 -304.346954)
			(xy 44.981661 -304.422465) (xy 45.041123 -304.502955) (xy 45.094003 -304.587914) (xy 45.139966 -304.676806)
			(xy 45.178721 -304.769069) (xy 45.210023 -304.864119) (xy 45.233675 -304.961356) (xy 45.249526 -305.060165)
			(xy 45.257476 -305.15992) (xy 45.257974 -305.209956) (xy 45.257476 -305.259992) (xy 45.249526 -305.359747)
			(xy 45.233675 -305.458556) (xy 45.210023 -305.555793) (xy 45.178721 -305.650843) (xy 45.139966 -305.743106)
			(xy 45.094003 -305.831998) (xy 45.041123 -305.916957) (xy 44.981661 -305.997447) (xy 44.915991 -306.072958)
			(xy 44.844529 -306.143012) (xy 44.767728 -306.207168) (xy 44.686072 -306.265018) (xy 44.600078 -306.316199)
			(xy 44.51029 -306.360385) (xy 44.417275 -306.397298) (xy 44.321621 -306.426704) (xy 44.223933 -306.448417)
			(xy 44.124829 -306.462301) (xy 44.024935 -306.468267) (xy 43.924883 -306.466277) (xy 43.825305 -306.456345)
			(xy 43.726831 -306.438532) (xy 43.630084 -306.412952) (xy 43.535675 -306.379766) (xy 43.444201 -306.339184)
			(xy 43.35624 -306.291463) (xy 43.272349 -306.236905) (xy 43.193058 -306.175853) (xy 43.118867 -306.108695)
			(xy 43.050248 -306.035855) (xy 42.987632 -305.957793) (xy 42.931416 -305.875003) (xy 42.881955 -305.788009)
			(xy 42.839563 -305.69736) (xy 42.804507 -305.603629) (xy 42.777008 -305.50741) (xy 42.757241 -305.409309)
			(xy 42.745331 -305.309949) (xy 42.741353 -305.209956) (xy 0.509016 -305.209956) (xy 0.509016 -312.436961)
			(xy 41.147742 -312.436961) (xy 41.147742 -312.352239) (xy 41.155795 -312.267902) (xy 41.171829 -312.184712)
			(xy 41.195697 -312.103422) (xy 41.227185 -312.02477) (xy 41.266007 -311.949467) (xy 41.31181 -311.878195)
			(xy 41.364181 -311.811599) (xy 41.422646 -311.750284) (xy 41.486674 -311.694803) (xy 41.555686 -311.64566)
			(xy 41.629056 -311.6033) (xy 41.706121 -311.568105) (xy 41.786183 -311.540396) (xy 41.868516 -311.520422)
			(xy 41.952375 -311.508365) (xy 42.037 -311.504334) (xy 42.121625 -311.508365) (xy 42.205484 -311.520422)
			(xy 42.287817 -311.540396) (xy 42.367879 -311.568105) (xy 42.444944 -311.6033) (xy 42.518314 -311.64566)
			(xy 42.587326 -311.694803) (xy 42.651354 -311.750284) (xy 42.709819 -311.811599) (xy 42.76219 -311.878195)
			(xy 42.807993 -311.949467) (xy 42.846815 -312.02477) (xy 42.878303 -312.103422) (xy 42.902171 -312.184712)
			(xy 42.918205 -312.267902) (xy 42.926258 -312.352239) (xy 42.926762 -312.3946) (xy 42.926258 -312.436961)
			(xy 42.918205 -312.521298) (xy 42.902171 -312.604488) (xy 42.878303 -312.685778) (xy 42.846815 -312.76443)
			(xy 42.807993 -312.839733) (xy 42.76219 -312.911005) (xy 42.709819 -312.977601) (xy 42.651354 -313.038916)
			(xy 42.587326 -313.094397) (xy 42.518314 -313.14354) (xy 42.444944 -313.1859) (xy 42.367879 -313.221095)
			(xy 42.287817 -313.248804) (xy 42.205484 -313.268778) (xy 42.121625 -313.280835) (xy 42.037 -313.284867)
			(xy 41.952375 -313.280835) (xy 41.868516 -313.268778) (xy 41.786183 -313.248804) (xy 41.706121 -313.221095)
			(xy 41.629056 -313.1859) (xy 41.555686 -313.14354) (xy 41.486674 -313.094397) (xy 41.422646 -313.038916)
			(xy 41.364181 -312.977601) (xy 41.31181 -312.911005) (xy 41.266007 -312.839733) (xy 41.227185 -312.76443)
			(xy 41.195697 -312.685778) (xy 41.171829 -312.604488) (xy 41.155795 -312.521298) (xy 41.147742 -312.436961)
			(xy 0.509016 -312.436961) (xy 0.509016 -332.04257) (xy 2.984235 -332.04257) (xy 2.984235 -331.91343)
			(xy 2.992185 -331.784535) (xy 3.008055 -331.656375) (xy 3.031784 -331.529434) (xy 3.063283 -331.404195)
			(xy 3.102432 -331.281132) (xy 3.149083 -331.160713) (xy 3.203058 -331.043394) (xy 3.264153 -330.92962)
			(xy 3.332136 -330.819823) (xy 3.40675 -330.71442) (xy 3.487711 -330.61381) (xy 3.574711 -330.518375)
			(xy 3.667422 -330.428476) (xy 3.765492 -330.344455) (xy 3.868547 -330.266631) (xy 3.976198 -330.195299)
			(xy 4.088037 -330.130729) (xy 4.203638 -330.073167) (xy 4.322563 -330.02283) (xy 4.444362 -329.97991)
			(xy 4.568572 -329.944569) (xy 4.694721 -329.916942) (xy 4.822333 -329.897133) (xy 4.950922 -329.885217)
			(xy 5.08 -329.881241) (xy 5.209078 -329.885217) (xy 5.337667 -329.897133) (xy 5.465279 -329.916942)
			(xy 5.591428 -329.944569) (xy 5.715638 -329.97991) (xy 5.837437 -330.02283) (xy 5.956362 -330.073167)
			(xy 6.071963 -330.130729) (xy 6.183802 -330.195299) (xy 6.291453 -330.266631) (xy 6.394508 -330.344455)
			(xy 6.492578 -330.428476) (xy 6.585289 -330.518375) (xy 6.672289 -330.61381) (xy 6.75325 -330.71442)
			(xy 6.827864 -330.819823) (xy 6.895847 -330.92962) (xy 6.956942 -331.043394) (xy 7.010917 -331.160713)
			(xy 7.057568 -331.281132) (xy 7.096717 -331.404195) (xy 7.128216 -331.529434) (xy 7.151945 -331.656375)
			(xy 7.167815 -331.784535) (xy 7.175765 -331.91343) (xy 7.176262 -331.978) (xy 7.175765 -332.04257)
			(xy 7.167815 -332.171465) (xy 7.151945 -332.299625) (xy 7.128216 -332.426566) (xy 7.096717 -332.551805)
			(xy 7.057568 -332.674868) (xy 7.010917 -332.795287) (xy 6.956942 -332.912606) (xy 6.895847 -333.02638)
			(xy 6.827864 -333.136177) (xy 6.75325 -333.24158) (xy 6.672289 -333.34219) (xy 6.585289 -333.437625)
			(xy 6.492578 -333.527524) (xy 6.394508 -333.611545) (xy 6.291453 -333.689369) (xy 6.183802 -333.760701)
			(xy 6.071963 -333.825271) (xy 5.956362 -333.882833) (xy 5.837437 -333.93317) (xy 5.715638 -333.97609)
			(xy 5.591428 -334.011431) (xy 5.465279 -334.039058) (xy 5.337667 -334.058867) (xy 5.209078 -334.070783)
			(xy 5.08 -334.07476) (xy 4.950922 -334.070783) (xy 4.822333 -334.058867) (xy 4.694721 -334.039058)
			(xy 4.568572 -334.011431) (xy 4.444362 -333.97609) (xy 4.322563 -333.93317) (xy 4.203638 -333.882833)
			(xy 4.088037 -333.825271) (xy 3.976198 -333.760701) (xy 3.868547 -333.689369) (xy 3.765492 -333.611545)
			(xy 3.667422 -333.527524) (xy 3.574711 -333.437625) (xy 3.487711 -333.34219) (xy 3.40675 -333.24158)
			(xy 3.332136 -333.136177) (xy 3.264153 -333.02638) (xy 3.203058 -332.912606) (xy 3.149083 -332.795287)
			(xy 3.102432 -332.674868) (xy 3.063283 -332.551805) (xy 3.031784 -332.426566) (xy 3.008055 -332.299625)
			(xy 2.992185 -332.171465) (xy 2.984235 -332.04257) (xy 0.509016 -332.04257) (xy 0.509016 -333.000096)
			(xy 0.509503 -333.083185) (xy 0.51741 -333.249175) (xy 0.533206 -333.414601) (xy 0.556856 -333.579088)
			(xy 0.588305 -333.742263) (xy 0.627483 -333.903757) (xy 0.674301 -334.063204) (xy 0.728652 -334.220243)
			(xy 0.790415 -334.374517) (xy 0.859448 -334.525678) (xy 0.935595 -334.673383) (xy 1.018684 -334.817298)
			(xy 1.108527 -334.957096) (xy 1.20492 -335.092461) (xy 1.307644 -335.223086) (xy 1.416468 -335.348675)
			(xy 1.531144 -335.468944) (xy 1.651413 -335.58362) (xy 1.777002 -335.692444) (xy 1.907627 -335.795168)
			(xy 2.042992 -335.891561) (xy 2.18279 -335.981404) (xy 2.326705 -336.064493) (xy 2.47441 -336.14064)
			(xy 2.625571 -336.209673) (xy 2.779845 -336.271436) (xy 2.936884 -336.325787) (xy 3.096331 -336.372605)
			(xy 3.257825 -336.411783) (xy 3.421 -336.443232) (xy 3.585487 -336.466882) (xy 3.750913 -336.482678)
			(xy 3.916903 -336.490585) (xy 3.999992 -336.491072)
		)
		(stroke
			(width 0)
			(type solid)
		)
		(fill yes)
		(layer "In1.Cu")
		(net "GND")
	)
	(gr_circle
		(center 1.905 -11.176)
		(end 2.794 -11.176)
		(stroke
			(width 0.2)
			(type default)
		)
		(fill no)
		(layer "In1.Cu")
	)
	(gr_circle
		(center 3.426968 -267.146024)
		(end 4.315968 -267.146024)
		(stroke
			(width 0.2)
			(type default)
		)
		(fill no)
		(layer "In1.Cu")
	)
	(gr_circle
		(center 3.426968 -266.511024)
		(end 4.315968 -266.511024)
		(stroke
			(width 0.2)
			(type default)
		)
		(fill no)
		(layer "In1.Cu")
	)
	(gr_circle
		(center 3.426968 -265.855704)
		(end 4.315968 -265.855704)
		(stroke
			(width 0.2)
			(type default)
		)
		(fill no)
		(layer "In1.Cu")
	)
	(gr_circle
		(center 3.429 -219.075)
		(end 4.318 -219.075)
		(stroke
			(width 0.2)
			(type default)
		)
		(fill no)
		(layer "In1.Cu")
	)
	(gr_circle
		(center 3.705098 -243.513864)
		(end 4.594098 -243.513864)
		(stroke
			(width 0.2)
			(type default)
		)
		(fill no)
		(layer "In1.Cu")
	)
	(gr_circle
		(center 3.705098 -242.878864)
		(end 4.594098 -242.878864)
		(stroke
			(width 0.2)
			(type default)
		)
		(fill no)
		(layer "In1.Cu")
	)
	(gr_circle
		(center 3.705098 -58.913776)
		(end 4.594098 -58.913776)
		(stroke
			(width 0.2)
			(type default)
		)
		(fill no)
		(layer "In1.Cu")
	)
	(gr_circle
		(center 3.705098 -58.278776)
		(end 4.594098 -58.278776)
		(stroke
			(width 0.2)
			(type default)
		)
		(fill no)
		(layer "In1.Cu")
	)
	(gr_circle
		(center 4.340098 -243.513864)
		(end 5.229098 -243.513864)
		(stroke
			(width 0.2)
			(type default)
		)
		(fill no)
		(layer "In1.Cu")
	)
	(gr_circle
		(center 4.340098 -58.913776)
		(end 5.229098 -58.913776)
		(stroke
			(width 0.2)
			(type default)
		)
		(fill no)
		(layer "In1.Cu")
	)
	(gr_circle
		(center 4.350258 -242.878864)
		(end 5.239258 -242.878864)
		(stroke
			(width 0.2)
			(type default)
		)
		(fill no)
		(layer "In1.Cu")
	)
	(gr_circle
		(center 4.350258 -58.278776)
		(end 5.239258 -58.278776)
		(stroke
			(width 0.2)
			(type default)
		)
		(fill no)
		(layer "In1.Cu")
	)
	(gr_circle
		(center 4.445 -91.878912)
		(end 5.334 -91.878912)
		(stroke
			(width 0.2)
			(type default)
		)
		(fill no)
		(layer "In1.Cu")
	)
	(gr_circle
		(center 4.445 -91.116912)
		(end 5.334 -91.116912)
		(stroke
			(width 0.2)
			(type default)
		)
		(fill no)
		(layer "In1.Cu")
	)
	(gr_circle
		(center 4.61899 -264.6426)
		(end 5.50799 -264.6426)
		(stroke
			(width 0.2)
			(type default)
		)
		(fill no)
		(layer "In1.Cu")
	)
	(gr_circle
		(center 4.61899 -263.8806)
		(end 5.50799 -263.8806)
		(stroke
			(width 0.2)
			(type default)
		)
		(fill no)
		(layer "In1.Cu")
	)
	(gr_circle
		(center 4.61899 -80.067912)
		(end 5.50799 -80.067912)
		(stroke
			(width 0.2)
			(type default)
		)
		(fill no)
		(layer "In1.Cu")
	)
	(gr_circle
		(center 4.61899 -79.305912)
		(end 5.50799 -79.305912)
		(stroke
			(width 0.2)
			(type default)
		)
		(fill no)
		(layer "In1.Cu")
	)
	(gr_circle
		(center 4.826 -281.2542)
		(end 5.715 -281.2542)
		(stroke
			(width 0.2)
			(type default)
		)
		(fill no)
		(layer "In1.Cu")
	)
	(gr_circle
		(center 4.826 -280.4922)
		(end 5.715 -280.4922)
		(stroke
			(width 0.2)
			(type default)
		)
		(fill no)
		(layer "In1.Cu")
	)
	(gr_circle
		(center 4.995418 -243.513864)
		(end 5.884418 -243.513864)
		(stroke
			(width 0.2)
			(type default)
		)
		(fill no)
		(layer "In1.Cu")
	)
	(gr_circle
		(center 4.995418 -242.878864)
		(end 5.884418 -242.878864)
		(stroke
			(width 0.2)
			(type default)
		)
		(fill no)
		(layer "In1.Cu")
	)
	(gr_circle
		(center 4.995418 -58.913776)
		(end 5.884418 -58.913776)
		(stroke
			(width 0.2)
			(type default)
		)
		(fill no)
		(layer "In1.Cu")
	)
	(gr_circle
		(center 4.995418 -58.278776)
		(end 5.884418 -58.278776)
		(stroke
			(width 0.2)
			(type default)
		)
		(fill no)
		(layer "In1.Cu")
	)
	(gr_circle
		(center 5.207 -91.878912)
		(end 6.096 -91.878912)
		(stroke
			(width 0.2)
			(type default)
		)
		(fill no)
		(layer "In1.Cu")
	)
	(gr_circle
		(center 5.207 -91.116912)
		(end 6.096 -91.116912)
		(stroke
			(width 0.2)
			(type default)
		)
		(fill no)
		(layer "In1.Cu")
	)
	(gr_circle
		(center 5.38099 -80.067912)
		(end 6.26999 -80.067912)
		(stroke
			(width 0.2)
			(type default)
		)
		(fill no)
		(layer "In1.Cu")
	)
	(gr_circle
		(center 5.38099 -79.305912)
		(end 6.26999 -79.305912)
		(stroke
			(width 0.2)
			(type default)
		)
		(fill no)
		(layer "In1.Cu")
	)
	(gr_circle
		(center 5.43179 -264.6426)
		(end 6.32079 -264.6426)
		(stroke
			(width 0.2)
			(type default)
		)
		(fill no)
		(layer "In1.Cu")
	)
	(gr_circle
		(center 5.43179 -263.8806)
		(end 6.32079 -263.8806)
		(stroke
			(width 0.2)
			(type default)
		)
		(fill no)
		(layer "In1.Cu")
	)
	(gr_circle
		(center 5.588 -281.2542)
		(end 6.477 -281.2542)
		(stroke
			(width 0.2)
			(type default)
		)
		(fill no)
		(layer "In1.Cu")
	)
	(gr_circle
		(center 5.588 -280.4922)
		(end 6.477 -280.4922)
		(stroke
			(width 0.2)
			(type default)
		)
		(fill no)
		(layer "In1.Cu")
	)
	(gr_circle
		(center 5.842 -193.04)
		(end 6.731 -193.04)
		(stroke
			(width 0.2)
			(type default)
		)
		(fill no)
		(layer "In1.Cu")
	)
	(gr_circle
		(center 5.969 -91.878912)
		(end 6.858 -91.878912)
		(stroke
			(width 0.2)
			(type default)
		)
		(fill no)
		(layer "In1.Cu")
	)
	(gr_circle
		(center 5.969 -91.116912)
		(end 6.858 -91.116912)
		(stroke
			(width 0.2)
			(type default)
		)
		(fill no)
		(layer "In1.Cu")
	)
	(gr_circle
		(center 6.14299 -80.067912)
		(end 7.03199 -80.067912)
		(stroke
			(width 0.2)
			(type default)
		)
		(fill no)
		(layer "In1.Cu")
	)
	(gr_circle
		(center 6.14299 -79.305912)
		(end 7.03199 -79.305912)
		(stroke
			(width 0.2)
			(type default)
		)
		(fill no)
		(layer "In1.Cu")
	)
	(gr_circle
		(center 6.26999 -264.6172)
		(end 7.15899 -264.6172)
		(stroke
			(width 0.2)
			(type default)
		)
		(fill no)
		(layer "In1.Cu")
	)
	(gr_circle
		(center 6.26999 -263.8552)
		(end 7.15899 -263.8552)
		(stroke
			(width 0.2)
			(type default)
		)
		(fill no)
		(layer "In1.Cu")
	)
	(gr_circle
		(center 6.35 -281.2542)
		(end 7.239 -281.2542)
		(stroke
			(width 0.2)
			(type default)
		)
		(fill no)
		(layer "In1.Cu")
	)
	(gr_circle
		(center 6.35 -280.4922)
		(end 7.239 -280.4922)
		(stroke
			(width 0.2)
			(type default)
		)
		(fill no)
		(layer "In1.Cu")
	)
	(gr_circle
		(center 6.700012 -299.310044)
		(end 8.020812 -299.310044)
		(stroke
			(width 0.2)
			(type default)
		)
		(fill no)
		(layer "In1.Cu")
	)
	(gr_circle
		(center 6.700012 -207.01)
		(end 8.020812 -207.01)
		(stroke
			(width 0.2)
			(type default)
		)
		(fill no)
		(layer "In1.Cu")
	)
	(gr_circle
		(center 6.700012 -114.709956)
		(end 8.020812 -114.709956)
		(stroke
			(width 0.2)
			(type default)
		)
		(fill no)
		(layer "In1.Cu")
	)
	(gr_circle
		(center 6.700012 -22.409912)
		(end 8.020812 -22.409912)
		(stroke
			(width 0.2)
			(type default)
		)
		(fill no)
		(layer "In1.Cu")
	)
	(gr_circle
		(center 6.731 -91.878912)
		(end 7.62 -91.878912)
		(stroke
			(width 0.2)
			(type default)
		)
		(fill no)
		(layer "In1.Cu")
	)
	(gr_circle
		(center 6.731 -91.116912)
		(end 7.62 -91.116912)
		(stroke
			(width 0.2)
			(type default)
		)
		(fill no)
		(layer "In1.Cu")
	)
	(gr_circle
		(center 6.804914 -244.31371)
		(end 7.693914 -244.31371)
		(stroke
			(width 0.2)
			(type default)
		)
		(fill no)
		(layer "In1.Cu")
	)
	(gr_circle
		(center 6.804914 -243.67871)
		(end 7.693914 -243.67871)
		(stroke
			(width 0.2)
			(type default)
		)
		(fill no)
		(layer "In1.Cu")
	)
	(gr_circle
		(center 6.804914 -59.713622)
		(end 7.693914 -59.713622)
		(stroke
			(width 0.2)
			(type default)
		)
		(fill no)
		(layer "In1.Cu")
	)
	(gr_circle
		(center 6.804914 -59.078622)
		(end 7.693914 -59.078622)
		(stroke
			(width 0.2)
			(type default)
		)
		(fill no)
		(layer "In1.Cu")
	)
	(gr_circle
		(center 6.90499 -80.067912)
		(end 7.79399 -80.067912)
		(stroke
			(width 0.2)
			(type default)
		)
		(fill no)
		(layer "In1.Cu")
	)
	(gr_circle
		(center 6.90499 -79.305912)
		(end 7.79399 -79.305912)
		(stroke
			(width 0.2)
			(type default)
		)
		(fill no)
		(layer "In1.Cu")
	)
	(gr_circle
		(center 7.007098 -238.20501)
		(end 7.896098 -238.20501)
		(stroke
			(width 0.2)
			(type default)
		)
		(fill no)
		(layer "In1.Cu")
	)
	(gr_circle
		(center 7.007098 -237.44301)
		(end 7.896098 -237.44301)
		(stroke
			(width 0.2)
			(type default)
		)
		(fill no)
		(layer "In1.Cu")
	)
	(gr_circle
		(center 7.414514 -53.448712)
		(end 8.303514 -53.448712)
		(stroke
			(width 0.2)
			(type default)
		)
		(fill no)
		(layer "In1.Cu")
	)
	(gr_circle
		(center 7.414514 -52.686712)
		(end 8.303514 -52.686712)
		(stroke
			(width 0.2)
			(type default)
		)
		(fill no)
		(layer "In1.Cu")
	)
	(gr_circle
		(center 7.439914 -244.31371)
		(end 8.328914 -244.31371)
		(stroke
			(width 0.2)
			(type default)
		)
		(fill no)
		(layer "In1.Cu")
	)
	(gr_circle
		(center 7.439914 -59.713622)
		(end 8.328914 -59.713622)
		(stroke
			(width 0.2)
			(type default)
		)
		(fill no)
		(layer "In1.Cu")
	)
	(gr_circle
		(center 7.450074 -243.67871)
		(end 8.339074 -243.67871)
		(stroke
			(width 0.2)
			(type default)
		)
		(fill no)
		(layer "In1.Cu")
	)
	(gr_circle
		(center 7.450074 -59.078622)
		(end 8.339074 -59.078622)
		(stroke
			(width 0.2)
			(type default)
		)
		(fill no)
		(layer "In1.Cu")
	)
	(gr_circle
		(center 8.095234 -244.31371)
		(end 8.984234 -244.31371)
		(stroke
			(width 0.2)
			(type default)
		)
		(fill no)
		(layer "In1.Cu")
	)
	(gr_circle
		(center 8.095234 -243.67871)
		(end 8.984234 -243.67871)
		(stroke
			(width 0.2)
			(type default)
		)
		(fill no)
		(layer "In1.Cu")
	)
	(gr_circle
		(center 8.095234 -59.713622)
		(end 8.984234 -59.713622)
		(stroke
			(width 0.2)
			(type default)
		)
		(fill no)
		(layer "In1.Cu")
	)
	(gr_circle
		(center 8.095234 -59.078622)
		(end 8.984234 -59.078622)
		(stroke
			(width 0.2)
			(type default)
		)
		(fill no)
		(layer "In1.Cu")
	)
	(gr_circle
		(center 8.26135 -230.439214)
		(end 9.15035 -230.439214)
		(stroke
			(width 0.2)
			(type default)
		)
		(fill no)
		(layer "In1.Cu")
	)
	(gr_circle
		(center 8.26135 -229.677214)
		(end 9.15035 -229.677214)
		(stroke
			(width 0.2)
			(type default)
		)
		(fill no)
		(layer "In1.Cu")
	)
	(gr_circle
		(center 8.28675 -235.773214)
		(end 9.17575 -235.773214)
		(stroke
			(width 0.2)
			(type default)
		)
		(fill no)
		(layer "In1.Cu")
	)
	(gr_circle
		(center 8.28675 -235.011214)
		(end 9.17575 -235.011214)
		(stroke
			(width 0.2)
			(type default)
		)
		(fill no)
		(layer "In1.Cu")
	)
	(gr_circle
		(center 8.33755 -233.131614)
		(end 9.22655 -233.131614)
		(stroke
			(width 0.2)
			(type default)
		)
		(fill no)
		(layer "In1.Cu")
	)
	(gr_circle
		(center 8.33755 -232.369614)
		(end 9.22655 -232.369614)
		(stroke
			(width 0.2)
			(type default)
		)
		(fill no)
		(layer "In1.Cu")
	)
	(gr_circle
		(center 8.700008 -297.310048)
		(end 10.020808 -297.310048)
		(stroke
			(width 0.2)
			(type default)
		)
		(fill no)
		(layer "In1.Cu")
	)
	(gr_circle
		(center 8.700008 -205.010004)
		(end 10.020808 -205.010004)
		(stroke
			(width 0.2)
			(type default)
		)
		(fill no)
		(layer "In1.Cu")
	)
	(gr_circle
		(center 8.700008 -112.70996)
		(end 10.020808 -112.70996)
		(stroke
			(width 0.2)
			(type default)
		)
		(fill no)
		(layer "In1.Cu")
	)
	(gr_circle
		(center 8.700008 -20.409916)
		(end 10.020808 -20.409916)
		(stroke
			(width 0.2)
			(type default)
		)
		(fill no)
		(layer "In1.Cu")
	)
	(gr_circle
		(center 8.73252 -46.391322)
		(end 9.62152 -46.391322)
		(stroke
			(width 0.2)
			(type default)
		)
		(fill no)
		(layer "In1.Cu")
	)
	(gr_circle
		(center 8.73252 -45.629322)
		(end 9.62152 -45.629322)
		(stroke
			(width 0.2)
			(type default)
		)
		(fill no)
		(layer "In1.Cu")
	)
	(gr_circle
		(center 8.75792 -51.369722)
		(end 9.64692 -51.369722)
		(stroke
			(width 0.2)
			(type default)
		)
		(fill no)
		(layer "In1.Cu")
	)
	(gr_circle
		(center 8.75792 -50.607722)
		(end 9.64692 -50.607722)
		(stroke
			(width 0.2)
			(type default)
		)
		(fill no)
		(layer "In1.Cu")
	)
	(gr_circle
		(center 8.774176 -48.90516)
		(end 9.663176 -48.90516)
		(stroke
			(width 0.2)
			(type default)
		)
		(fill no)
		(layer "In1.Cu")
	)
	(gr_circle
		(center 8.774176 -48.14316)
		(end 9.663176 -48.14316)
		(stroke
			(width 0.2)
			(type default)
		)
		(fill no)
		(layer "In1.Cu")
	)
	(gr_circle
		(center 9.44499 -80.321912)
		(end 10.33399 -80.321912)
		(stroke
			(width 0.2)
			(type default)
		)
		(fill no)
		(layer "In1.Cu")
	)
	(gr_circle
		(center 9.54659 -264.4902)
		(end 10.43559 -264.4902)
		(stroke
			(width 0.2)
			(type default)
		)
		(fill no)
		(layer "In1.Cu")
	)
	(gr_circle
		(center 9.948418 -243.4336)
		(end 10.837418 -243.4336)
		(stroke
			(width 0.2)
			(type default)
		)
		(fill no)
		(layer "In1.Cu")
	)
	(gr_circle
		(center 9.948418 -58.477912)
		(end 10.837418 -58.477912)
		(stroke
			(width 0.2)
			(type default)
		)
		(fill no)
		(layer "In1.Cu")
	)
	(gr_circle
		(center 10.20699 -80.321912)
		(end 11.09599 -80.321912)
		(stroke
			(width 0.2)
			(type default)
		)
		(fill no)
		(layer "In1.Cu")
	)
	(gr_circle
		(center 10.30859 -264.4902)
		(end 11.19759 -264.4902)
		(stroke
			(width 0.2)
			(type default)
		)
		(fill no)
		(layer "In1.Cu")
	)
	(gr_circle
		(center 10.710418 -243.4336)
		(end 11.599418 -243.4336)
		(stroke
			(width 0.2)
			(type default)
		)
		(fill no)
		(layer "In1.Cu")
	)
	(gr_circle
		(center 10.710418 -58.477912)
		(end 11.599418 -58.477912)
		(stroke
			(width 0.2)
			(type default)
		)
		(fill no)
		(layer "In1.Cu")
	)
	(gr_circle
		(center 11.277346 -38.649656)
		(end 12.166346 -38.649656)
		(stroke
			(width 0.2)
			(type default)
		)
		(fill no)
		(layer "In1.Cu")
	)
	(gr_circle
		(center 11.277346 -38.014656)
		(end 12.166346 -38.014656)
		(stroke
			(width 0.2)
			(type default)
		)
		(fill no)
		(layer "In1.Cu")
	)
	(gr_circle
		(center 11.277346 -37.303456)
		(end 12.166346 -37.303456)
		(stroke
			(width 0.2)
			(type default)
		)
		(fill no)
		(layer "In1.Cu")
	)
	(gr_circle
		(center 11.299698 -44.263056)
		(end 12.188698 -44.263056)
		(stroke
			(width 0.2)
			(type default)
		)
		(fill no)
		(layer "In1.Cu")
	)
	(gr_circle
		(center 11.299698 -43.501056)
		(end 12.188698 -43.501056)
		(stroke
			(width 0.2)
			(type default)
		)
		(fill no)
		(layer "In1.Cu")
	)
	(gr_circle
		(center 12.039346 -38.649656)
		(end 12.928346 -38.649656)
		(stroke
			(width 0.2)
			(type default)
		)
		(fill no)
		(layer "In1.Cu")
	)
	(gr_circle
		(center 12.039346 -38.014656)
		(end 12.928346 -38.014656)
		(stroke
			(width 0.2)
			(type default)
		)
		(fill no)
		(layer "In1.Cu")
	)
	(gr_circle
		(center 12.039346 -37.303456)
		(end 12.928346 -37.303456)
		(stroke
			(width 0.2)
			(type default)
		)
		(fill no)
		(layer "In1.Cu")
	)
	(gr_circle
		(center 12.060174 -79.721202)
		(end 12.949174 -79.721202)
		(stroke
			(width 0.2)
			(type default)
		)
		(fill no)
		(layer "In1.Cu")
	)
	(gr_circle
		(center 12.060174 -79.086202)
		(end 12.949174 -79.086202)
		(stroke
			(width 0.2)
			(type default)
		)
		(fill no)
		(layer "In1.Cu")
	)
	(gr_circle
		(center 12.061698 -44.263056)
		(end 12.950698 -44.263056)
		(stroke
			(width 0.2)
			(type default)
		)
		(fill no)
		(layer "In1.Cu")
	)
	(gr_circle
		(center 12.061698 -43.501056)
		(end 12.950698 -43.501056)
		(stroke
			(width 0.2)
			(type default)
		)
		(fill no)
		(layer "In1.Cu")
	)
	(gr_circle
		(center 12.187174 -264.32129)
		(end 13.076174 -264.32129)
		(stroke
			(width 0.2)
			(type default)
		)
		(fill no)
		(layer "In1.Cu")
	)
	(gr_circle
		(center 12.187174 -263.68629)
		(end 13.076174 -263.68629)
		(stroke
			(width 0.2)
			(type default)
		)
		(fill no)
		(layer "In1.Cu")
	)
	(gr_circle
		(center 12.270232 -224.38741)
		(end 13.159232 -224.38741)
		(stroke
			(width 0.2)
			(type default)
		)
		(fill no)
		(layer "In1.Cu")
	)
	(gr_circle
		(center 12.270232 -223.62541)
		(end 13.159232 -223.62541)
		(stroke
			(width 0.2)
			(type default)
		)
		(fill no)
		(layer "In1.Cu")
	)
	(gr_circle
		(center 12.270232 -222.86341)
		(end 13.159232 -222.86341)
		(stroke
			(width 0.2)
			(type default)
		)
		(fill no)
		(layer "In1.Cu")
	)
	(gr_circle
		(center 12.307824 -58.474356)
		(end 13.196824 -58.474356)
		(stroke
			(width 0.2)
			(type default)
		)
		(fill no)
		(layer "In1.Cu")
	)
	(gr_circle
		(center 12.313158 -59.298078)
		(end 13.202158 -59.298078)
		(stroke
			(width 0.2)
			(type default)
		)
		(fill no)
		(layer "In1.Cu")
	)
	(gr_circle
		(center 12.352274 -246.305578)
		(end 13.241274 -246.305578)
		(stroke
			(width 0.2)
			(type default)
		)
		(fill no)
		(layer "In1.Cu")
	)
	(gr_circle
		(center 12.352274 -245.670578)
		(end 13.241274 -245.670578)
		(stroke
			(width 0.2)
			(type default)
		)
		(fill no)
		(layer "In1.Cu")
	)
	(gr_circle
		(center 12.352274 -245.010178)
		(end 13.241274 -245.010178)
		(stroke
			(width 0.2)
			(type default)
		)
		(fill no)
		(layer "In1.Cu")
	)
	(gr_circle
		(center 12.352274 -244.375178)
		(end 13.241274 -244.375178)
		(stroke
			(width 0.2)
			(type default)
		)
		(fill no)
		(layer "In1.Cu")
	)
	(gr_circle
		(center 12.377674 -247.600978)
		(end 13.266674 -247.600978)
		(stroke
			(width 0.2)
			(type default)
		)
		(fill no)
		(layer "In1.Cu")
	)
	(gr_circle
		(center 12.377674 -246.965978)
		(end 13.266674 -246.965978)
		(stroke
			(width 0.2)
			(type default)
		)
		(fill no)
		(layer "In1.Cu")
	)
	(gr_circle
		(center 12.377674 -243.714778)
		(end 13.266674 -243.714778)
		(stroke
			(width 0.2)
			(type default)
		)
		(fill no)
		(layer "In1.Cu")
	)
	(gr_circle
		(center 12.377674 -243.079778)
		(end 13.266674 -243.079778)
		(stroke
			(width 0.2)
			(type default)
		)
		(fill no)
		(layer "In1.Cu")
	)
	(gr_circle
		(center 12.705334 -79.721202)
		(end 13.594334 -79.721202)
		(stroke
			(width 0.2)
			(type default)
		)
		(fill no)
		(layer "In1.Cu")
	)
	(gr_circle
		(center 12.715494 -79.086202)
		(end 13.604494 -79.086202)
		(stroke
			(width 0.2)
			(type default)
		)
		(fill no)
		(layer "In1.Cu")
	)
	(gr_circle
		(center 12.832334 -264.32129)
		(end 13.721334 -264.32129)
		(stroke
			(width 0.2)
			(type default)
		)
		(fill no)
		(layer "In1.Cu")
	)
	(gr_circle
		(center 12.842494 -263.68629)
		(end 13.731494 -263.68629)
		(stroke
			(width 0.2)
			(type default)
		)
		(fill no)
		(layer "In1.Cu")
	)
	(gr_circle
		(center 12.905232 -224.38741)
		(end 13.794232 -224.38741)
		(stroke
			(width 0.2)
			(type default)
		)
		(fill no)
		(layer "In1.Cu")
	)
	(gr_circle
		(center 12.905232 -223.62541)
		(end 13.794232 -223.62541)
		(stroke
			(width 0.2)
			(type default)
		)
		(fill no)
		(layer "In1.Cu")
	)
	(gr_circle
		(center 12.905232 -222.86341)
		(end 13.794232 -222.86341)
		(stroke
			(width 0.2)
			(type default)
		)
		(fill no)
		(layer "In1.Cu")
	)
	(gr_circle
		(center 12.945618 -62.541912)
		(end 13.834618 -62.541912)
		(stroke
			(width 0.2)
			(type default)
		)
		(fill no)
		(layer "In1.Cu")
	)
	(gr_circle
		(center 13.069824 -58.474356)
		(end 13.958824 -58.474356)
		(stroke
			(width 0.2)
			(type default)
		)
		(fill no)
		(layer "In1.Cu")
	)
	(gr_circle
		(center 13.075158 -59.298078)
		(end 13.964158 -59.298078)
		(stroke
			(width 0.2)
			(type default)
		)
		(fill no)
		(layer "In1.Cu")
	)
	(gr_circle
		(center 13.350494 -79.721202)
		(end 14.239494 -79.721202)
		(stroke
			(width 0.2)
			(type default)
		)
		(fill no)
		(layer "In1.Cu")
	)
	(gr_circle
		(center 13.350494 -79.086202)
		(end 14.239494 -79.086202)
		(stroke
			(width 0.2)
			(type default)
		)
		(fill no)
		(layer "In1.Cu")
	)
	(gr_circle
		(center 13.462 -93.979238)
		(end 14.351 -93.979238)
		(stroke
			(width 0.2)
			(type default)
		)
		(fill no)
		(layer "In1.Cu")
	)
	(gr_circle
		(center 13.462 -93.344238)
		(end 14.351 -93.344238)
		(stroke
			(width 0.2)
			(type default)
		)
		(fill no)
		(layer "In1.Cu")
	)
	(gr_circle
		(center 13.462 -92.709238)
		(end 14.351 -92.709238)
		(stroke
			(width 0.2)
			(type default)
		)
		(fill no)
		(layer "In1.Cu")
	)
	(gr_circle
		(center 13.462 -89.153238)
		(end 14.351 -89.153238)
		(stroke
			(width 0.2)
			(type default)
		)
		(fill no)
		(layer "In1.Cu")
	)
	(gr_circle
		(center 13.462 -88.518238)
		(end 14.351 -88.518238)
		(stroke
			(width 0.2)
			(type default)
		)
		(fill no)
		(layer "In1.Cu")
	)
	(gr_circle
		(center 13.462 -87.883238)
		(end 14.351 -87.883238)
		(stroke
			(width 0.2)
			(type default)
		)
		(fill no)
		(layer "In1.Cu")
	)
	(gr_circle
		(center 13.477494 -264.32129)
		(end 14.366494 -264.32129)
		(stroke
			(width 0.2)
			(type default)
		)
		(fill no)
		(layer "In1.Cu")
	)
	(gr_circle
		(center 13.477494 -263.68629)
		(end 14.366494 -263.68629)
		(stroke
			(width 0.2)
			(type default)
		)
		(fill no)
		(layer "In1.Cu")
	)
	(gr_circle
		(center 13.707618 -62.541912)
		(end 14.596618 -62.541912)
		(stroke
			(width 0.2)
			(type default)
		)
		(fill no)
		(layer "In1.Cu")
	)
	(gr_circle
		(center 13.831824 -58.474356)
		(end 14.720824 -58.474356)
		(stroke
			(width 0.2)
			(type default)
		)
		(fill no)
		(layer "In1.Cu")
	)
	(gr_circle
		(center 13.837158 -59.298078)
		(end 14.726158 -59.298078)
		(stroke
			(width 0.2)
			(type default)
		)
		(fill no)
		(layer "In1.Cu")
	)
	(gr_circle
		(center 14.13129 -277.895304)
		(end 15.02029 -277.895304)
		(stroke
			(width 0.2)
			(type default)
		)
		(fill no)
		(layer "In1.Cu")
	)
	(gr_circle
		(center 14.13129 -277.02891)
		(end 15.02029 -277.02891)
		(stroke
			(width 0.2)
			(type default)
		)
		(fill no)
		(layer "In1.Cu")
	)
	(gr_circle
		(center 14.1478 -274.139406)
		(end 15.0368 -274.139406)
		(stroke
			(width 0.2)
			(type default)
		)
		(fill no)
		(layer "In1.Cu")
	)
	(gr_circle
		(center 14.1478 -273.273012)
		(end 15.0368 -273.273012)
		(stroke
			(width 0.2)
			(type default)
		)
		(fill no)
		(layer "In1.Cu")
	)
	(gr_circle
		(center 14.1478 -86.995)
		(end 15.0368 -86.995)
		(stroke
			(width 0.2)
			(type default)
		)
		(fill no)
		(layer "In1.Cu")
	)
	(gr_circle
		(center 14.148054 -272.25244)
		(end 15.037054 -272.25244)
		(stroke
			(width 0.2)
			(type default)
		)
		(fill no)
		(layer "In1.Cu")
	)
	(gr_circle
		(center 14.148054 -271.386046)
		(end 15.037054 -271.386046)
		(stroke
			(width 0.2)
			(type default)
		)
		(fill no)
		(layer "In1.Cu")
	)
	(gr_circle
		(center 14.469618 -62.541912)
		(end 15.358618 -62.541912)
		(stroke
			(width 0.2)
			(type default)
		)
		(fill no)
		(layer "In1.Cu")
	)
	(gr_circle
		(center 15.15999 -80.521048)
		(end 16.04899 -80.521048)
		(stroke
			(width 0.2)
			(type default)
		)
		(fill no)
		(layer "In1.Cu")
	)
	(gr_circle
		(center 15.15999 -79.886048)
		(end 16.04899 -79.886048)
		(stroke
			(width 0.2)
			(type default)
		)
		(fill no)
		(layer "In1.Cu")
	)
	(gr_circle
		(center 15.24 -202.67295)
		(end 16.129 -202.67295)
		(stroke
			(width 0.2)
			(type default)
		)
		(fill no)
		(layer "In1.Cu")
	)
	(gr_circle
		(center 15.28699 -265.121136)
		(end 16.17599 -265.121136)
		(stroke
			(width 0.2)
			(type default)
		)
		(fill no)
		(layer "In1.Cu")
	)
	(gr_circle
		(center 15.28699 -264.486136)
		(end 16.17599 -264.486136)
		(stroke
			(width 0.2)
			(type default)
		)
		(fill no)
		(layer "In1.Cu")
	)
	(gr_circle
		(center 15.501366 -270.294862)
		(end 16.390366 -270.294862)
		(stroke
			(width 0.2)
			(type default)
		)
		(fill no)
		(layer "In1.Cu")
	)
	(gr_circle
		(center 15.501366 -269.428468)
		(end 16.390366 -269.428468)
		(stroke
			(width 0.2)
			(type default)
		)
		(fill no)
		(layer "In1.Cu")
	)
	(gr_circle
		(center 15.80515 -80.521048)
		(end 16.69415 -80.521048)
		(stroke
			(width 0.2)
			(type default)
		)
		(fill no)
		(layer "In1.Cu")
	)
	(gr_circle
		(center 15.81531 -79.886048)
		(end 16.70431 -79.886048)
		(stroke
			(width 0.2)
			(type default)
		)
		(fill no)
		(layer "In1.Cu")
	)
	(gr_circle
		(center 15.93215 -265.121136)
		(end 16.82115 -265.121136)
		(stroke
			(width 0.2)
			(type default)
		)
		(fill no)
		(layer "In1.Cu")
	)
	(gr_circle
		(center 15.94231 -264.486136)
		(end 16.83131 -264.486136)
		(stroke
			(width 0.2)
			(type default)
		)
		(fill no)
		(layer "In1.Cu")
	)
	(gr_circle
		(center 16.45031 -80.521048)
		(end 17.33931 -80.521048)
		(stroke
			(width 0.2)
			(type default)
		)
		(fill no)
		(layer "In1.Cu")
	)
	(gr_circle
		(center 16.45031 -79.886048)
		(end 17.33931 -79.886048)
		(stroke
			(width 0.2)
			(type default)
		)
		(fill no)
		(layer "In1.Cu")
	)
	(gr_circle
		(center 16.57731 -265.121136)
		(end 17.46631 -265.121136)
		(stroke
			(width 0.2)
			(type default)
		)
		(fill no)
		(layer "In1.Cu")
	)
	(gr_circle
		(center 16.57731 -264.486136)
		(end 17.46631 -264.486136)
		(stroke
			(width 0.2)
			(type default)
		)
		(fill no)
		(layer "In1.Cu")
	)
	(gr_circle
		(center 17.272 -204.369924)
		(end 18.161 -204.369924)
		(stroke
			(width 0.2)
			(type default)
		)
		(fill no)
		(layer "In1.Cu")
	)
	(gr_circle
		(center 17.907 -112.649)
		(end 18.796 -112.649)
		(stroke
			(width 0.2)
			(type default)
		)
		(fill no)
		(layer "In1.Cu")
	)
	(gr_circle
		(center 18.034 -108.458)
		(end 18.923 -108.458)
		(stroke
			(width 0.2)
			(type default)
		)
		(fill no)
		(layer "In1.Cu")
	)
	(gr_circle
		(center 18.1102 -116.84)
		(end 18.9992 -116.84)
		(stroke
			(width 0.2)
			(type default)
		)
		(fill no)
		(layer "In1.Cu")
	)
	(gr_circle
		(center 19.177 -216.535)
		(end 20.066 -216.535)
		(stroke
			(width 0.2)
			(type default)
		)
		(fill no)
		(layer "In1.Cu")
	)
	(gr_circle
		(center 19.304 -33.909)
		(end 20.193 -33.909)
		(stroke
			(width 0.2)
			(type default)
		)
		(fill no)
		(layer "In1.Cu")
	)
	(gr_circle
		(center 19.4056 -301.7774)
		(end 20.2946 -301.7774)
		(stroke
			(width 0.2)
			(type default)
		)
		(fill no)
		(layer "In1.Cu")
	)
	(gr_circle
		(center 19.492722 -29.591)
		(end 20.381722 -29.591)
		(stroke
			(width 0.2)
			(type default)
		)
		(fill no)
		(layer "In1.Cu")
	)
	(gr_circle
		(center 19.558 -209.169)
		(end 20.447 -209.169)
		(stroke
			(width 0.2)
			(type default)
		)
		(fill no)
		(layer "In1.Cu")
	)
	(gr_circle
		(center 19.6596 -196.85)
		(end 20.5486 -196.85)
		(stroke
			(width 0.2)
			(type default)
		)
		(fill no)
		(layer "In1.Cu")
	)
	(gr_circle
		(center 20.193 -288.036)
		(end 21.082 -288.036)
		(stroke
			(width 0.2)
			(type default)
		)
		(fill no)
		(layer "In1.Cu")
	)
	(gr_circle
		(center 20.32 -210.439)
		(end 21.209 -210.439)
		(stroke
			(width 0.2)
			(type default)
		)
		(fill no)
		(layer "In1.Cu")
	)
	(gr_circle
		(center 20.447 -18.796)
		(end 21.336 -18.796)
		(stroke
			(width 0.2)
			(type default)
		)
		(fill no)
		(layer "In1.Cu")
	)
	(gr_circle
		(center 20.828 -105.41)
		(end 21.717 -105.41)
		(stroke
			(width 0.2)
			(type default)
		)
		(fill no)
		(layer "In1.Cu")
	)
	(gr_circle
		(center 20.955 -101.092)
		(end 21.844 -101.092)
		(stroke
			(width 0.2)
			(type default)
		)
		(fill no)
		(layer "In1.Cu")
	)
	(gr_circle
		(center 21.336 -214.6173)
		(end 22.225 -214.6173)
		(stroke
			(width 0.2)
			(type default)
		)
		(fill no)
		(layer "In1.Cu")
	)
	(gr_circle
		(center 26.035 -248.793)
		(end 26.924 -248.793)
		(stroke
			(width 0.2)
			(type default)
		)
		(fill no)
		(layer "In1.Cu")
	)
	(gr_circle
		(center 27.178 -98.933)
		(end 28.067 -98.933)
		(stroke
			(width 0.2)
			(type default)
		)
		(fill no)
		(layer "In1.Cu")
	)
	(gr_circle
		(center 28.326588 -13.2842)
		(end 29.215588 -13.2842)
		(stroke
			(width 0.2)
			(type default)
		)
		(fill no)
		(layer "In1.Cu")
	)
	(gr_circle
		(center 28.326588 -12.6492)
		(end 29.215588 -12.6492)
		(stroke
			(width 0.2)
			(type default)
		)
		(fill no)
		(layer "In1.Cu")
	)
	(gr_circle
		(center 28.326588 -12.0142)
		(end 29.215588 -12.0142)
		(stroke
			(width 0.2)
			(type default)
		)
		(fill no)
		(layer "In1.Cu")
	)
	(gr_circle
		(center 28.326588 -11.3792)
		(end 29.215588 -11.3792)
		(stroke
			(width 0.2)
			(type default)
		)
		(fill no)
		(layer "In1.Cu")
	)
	(gr_circle
		(center 28.326588 -10.7442)
		(end 29.215588 -10.7442)
		(stroke
			(width 0.2)
			(type default)
		)
		(fill no)
		(layer "In1.Cu")
	)
	(gr_circle
		(center 28.326588 -10.1092)
		(end 29.215588 -10.1092)
		(stroke
			(width 0.2)
			(type default)
		)
		(fill no)
		(layer "In1.Cu")
	)
	(gr_circle
		(center 29.088588 -13.2842)
		(end 29.977588 -13.2842)
		(stroke
			(width 0.2)
			(type default)
		)
		(fill no)
		(layer "In1.Cu")
	)
	(gr_circle
		(center 29.088588 -12.6492)
		(end 29.977588 -12.6492)
		(stroke
			(width 0.2)
			(type default)
		)
		(fill no)
		(layer "In1.Cu")
	)
	(gr_circle
		(center 29.088588 -12.0142)
		(end 29.977588 -12.0142)
		(stroke
			(width 0.2)
			(type default)
		)
		(fill no)
		(layer "In1.Cu")
	)
	(gr_circle
		(center 29.088588 -11.3792)
		(end 29.977588 -11.3792)
		(stroke
			(width 0.2)
			(type default)
		)
		(fill no)
		(layer "In1.Cu")
	)
	(gr_circle
		(center 29.088588 -10.7442)
		(end 29.977588 -10.7442)
		(stroke
			(width 0.2)
			(type default)
		)
		(fill no)
		(layer "In1.Cu")
	)
	(gr_circle
		(center 29.088588 -10.1092)
		(end 29.977588 -10.1092)
		(stroke
			(width 0.2)
			(type default)
		)
		(fill no)
		(layer "In1.Cu")
	)
	(gr_circle
		(center 29.845 -101.219)
		(end 30.734 -101.219)
		(stroke
			(width 0.2)
			(type default)
		)
		(fill no)
		(layer "In1.Cu")
	)
	(gr_circle
		(center 30.988 -117.602)
		(end 31.877 -117.602)
		(stroke
			(width 0.2)
			(type default)
		)
		(fill no)
		(layer "In1.Cu")
	)
	(gr_circle
		(center 31.115 -25.908)
		(end 32.004 -25.908)
		(stroke
			(width 0.2)
			(type default)
		)
		(fill no)
		(layer "In1.Cu")
	)
	(gr_circle
		(center 31.242 -299.974)
		(end 32.131 -299.974)
		(stroke
			(width 0.2)
			(type default)
		)
		(fill no)
		(layer "In1.Cu")
	)
	(gr_circle
		(center 31.242 -210.594956)
		(end 32.131 -210.594956)
		(stroke
			(width 0.2)
			(type default)
		)
		(fill no)
		(layer "In1.Cu")
	)
	(gr_circle
		(center 31.369 -288.925)
		(end 32.258 -288.925)
		(stroke
			(width 0.2)
			(type default)
		)
		(fill no)
		(layer "In1.Cu")
	)
	(gr_circle
		(center 31.369 -15.113)
		(end 32.258 -15.113)
		(stroke
			(width 0.2)
			(type default)
		)
		(fill no)
		(layer "In1.Cu")
	)
	(gr_circle
		(center 32.304228 -267.97)
		(end 33.193228 -267.97)
		(stroke
			(width 0.2)
			(type default)
		)
		(fill no)
		(layer "In1.Cu")
	)
	(gr_circle
		(center 32.304228 -264.668)
		(end 33.193228 -264.668)
		(stroke
			(width 0.2)
			(type default)
		)
		(fill no)
		(layer "In1.Cu")
	)
	(gr_circle
		(center 32.304228 -263.906)
		(end 33.193228 -263.906)
		(stroke
			(width 0.2)
			(type default)
		)
		(fill no)
		(layer "In1.Cu")
	)
	(gr_circle
		(center 32.380428 -80.067912)
		(end 33.269428 -80.067912)
		(stroke
			(width 0.2)
			(type default)
		)
		(fill no)
		(layer "In1.Cu")
	)
	(gr_circle
		(center 32.380428 -79.305912)
		(end 33.269428 -79.305912)
		(stroke
			(width 0.2)
			(type default)
		)
		(fill no)
		(layer "In1.Cu")
	)
	(gr_circle
		(center 32.385 -32.893)
		(end 33.274 -32.893)
		(stroke
			(width 0.2)
			(type default)
		)
		(fill no)
		(layer "In1.Cu")
	)
	(gr_circle
		(center 33.117028 -267.97)
		(end 34.006028 -267.97)
		(stroke
			(width 0.2)
			(type default)
		)
		(fill no)
		(layer "In1.Cu")
	)
	(gr_circle
		(center 33.117028 -264.668)
		(end 34.006028 -264.668)
		(stroke
			(width 0.2)
			(type default)
		)
		(fill no)
		(layer "In1.Cu")
	)
	(gr_circle
		(center 33.117028 -263.906)
		(end 34.006028 -263.906)
		(stroke
			(width 0.2)
			(type default)
		)
		(fill no)
		(layer "In1.Cu")
	)
	(gr_circle
		(center 33.142428 -80.067912)
		(end 34.031428 -80.067912)
		(stroke
			(width 0.2)
			(type default)
		)
		(fill no)
		(layer "In1.Cu")
	)
	(gr_circle
		(center 33.142428 -79.305912)
		(end 34.031428 -79.305912)
		(stroke
			(width 0.2)
			(type default)
		)
		(fill no)
		(layer "In1.Cu")
	)
	(gr_circle
		(center 33.655 -25.146)
		(end 34.544 -25.146)
		(stroke
			(width 0.2)
			(type default)
		)
		(fill no)
		(layer "In1.Cu")
	)
	(gr_circle
		(center 33.879028 -267.97)
		(end 34.768028 -267.97)
		(stroke
			(width 0.2)
			(type default)
		)
		(fill no)
		(layer "In1.Cu")
	)
	(gr_circle
		(center 33.879028 -264.668)
		(end 34.768028 -264.668)
		(stroke
			(width 0.2)
			(type default)
		)
		(fill no)
		(layer "In1.Cu")
	)
	(gr_circle
		(center 33.879028 -263.906)
		(end 34.768028 -263.906)
		(stroke
			(width 0.2)
			(type default)
		)
		(fill no)
		(layer "In1.Cu")
	)
	(gr_circle
		(center 33.904428 -80.067912)
		(end 34.793428 -80.067912)
		(stroke
			(width 0.2)
			(type default)
		)
		(fill no)
		(layer "In1.Cu")
	)
	(gr_circle
		(center 33.904428 -79.305912)
		(end 34.793428 -79.305912)
		(stroke
			(width 0.2)
			(type default)
		)
		(fill no)
		(layer "In1.Cu")
	)
	(gr_circle
		(center 34.0106 -197.104)
		(end 34.8996 -197.104)
		(stroke
			(width 0.2)
			(type default)
		)
		(fill no)
		(layer "In1.Cu")
	)
	(gr_circle
		(center 34.4805 -33.7185)
		(end 35.3695 -33.7185)
		(stroke
			(width 0.2)
			(type default)
		)
		(fill no)
		(layer "In1.Cu")
	)
	(gr_circle
		(center 35.102292 -58.913776)
		(end 35.991292 -58.913776)
		(stroke
			(width 0.2)
			(type default)
		)
		(fill no)
		(layer "In1.Cu")
	)
	(gr_circle
		(center 35.112452 -58.278776)
		(end 36.001452 -58.278776)
		(stroke
			(width 0.2)
			(type default)
		)
		(fill no)
		(layer "In1.Cu")
	)
	(gr_circle
		(center 35.122612 -244.31371)
		(end 36.011612 -244.31371)
		(stroke
			(width 0.2)
			(type default)
		)
		(fill no)
		(layer "In1.Cu")
	)
	(gr_circle
		(center 35.122612 -243.67871)
		(end 36.011612 -243.67871)
		(stroke
			(width 0.2)
			(type default)
		)
		(fill no)
		(layer "In1.Cu")
	)
	(gr_circle
		(center 35.757612 -244.31371)
		(end 36.646612 -244.31371)
		(stroke
			(width 0.2)
			(type default)
		)
		(fill no)
		(layer "In1.Cu")
	)
	(gr_circle
		(center 35.757612 -58.913776)
		(end 36.646612 -58.913776)
		(stroke
			(width 0.2)
			(type default)
		)
		(fill no)
		(layer "In1.Cu")
	)
	(gr_circle
		(center 35.767772 -243.67871)
		(end 36.656772 -243.67871)
		(stroke
			(width 0.2)
			(type default)
		)
		(fill no)
		(layer "In1.Cu")
	)
	(gr_circle
		(center 35.767772 -58.278776)
		(end 36.656772 -58.278776)
		(stroke
			(width 0.2)
			(type default)
		)
		(fill no)
		(layer "In1.Cu")
	)
	(gr_circle
		(center 35.959288 -271.8816)
		(end 36.848288 -271.8816)
		(stroke
			(width 0.2)
			(type default)
		)
		(fill no)
		(layer "In1.Cu")
	)
	(gr_circle
		(center 35.959288 -271.2466)
		(end 36.848288 -271.2466)
		(stroke
			(width 0.2)
			(type default)
		)
		(fill no)
		(layer "In1.Cu")
	)
	(gr_circle
		(center 36.340288 -278.765)
		(end 37.229288 -278.765)
		(stroke
			(width 0.2)
			(type default)
		)
		(fill no)
		(layer "In1.Cu")
	)
	(gr_circle
		(center 36.340288 -278.13)
		(end 37.229288 -278.13)
		(stroke
			(width 0.2)
			(type default)
		)
		(fill no)
		(layer "In1.Cu")
	)
	(gr_circle
		(center 36.340288 -277.495)
		(end 37.229288 -277.495)
		(stroke
			(width 0.2)
			(type default)
		)
		(fill no)
		(layer "In1.Cu")
	)
	(gr_circle
		(center 36.340288 -273.812)
		(end 37.229288 -273.812)
		(stroke
			(width 0.2)
			(type default)
		)
		(fill no)
		(layer "In1.Cu")
	)
	(gr_circle
		(center 36.340288 -273.177)
		(end 37.229288 -273.177)
		(stroke
			(width 0.2)
			(type default)
		)
		(fill no)
		(layer "In1.Cu")
	)
	(gr_circle
		(center 36.340288 -272.542)
		(end 37.229288 -272.542)
		(stroke
			(width 0.2)
			(type default)
		)
		(fill no)
		(layer "In1.Cu")
	)
	(gr_circle
		(center 36.412932 -244.31371)
		(end 37.301932 -244.31371)
		(stroke
			(width 0.2)
			(type default)
		)
		(fill no)
		(layer "In1.Cu")
	)
	(gr_circle
		(center 36.412932 -243.67871)
		(end 37.301932 -243.67871)
		(stroke
			(width 0.2)
			(type default)
		)
		(fill no)
		(layer "In1.Cu")
	)
	(gr_circle
		(center 36.412932 -58.913776)
		(end 37.301932 -58.913776)
		(stroke
			(width 0.2)
			(type default)
		)
		(fill no)
		(layer "In1.Cu")
	)
	(gr_circle
		(center 36.412932 -58.278776)
		(end 37.301932 -58.278776)
		(stroke
			(width 0.2)
			(type default)
		)
		(fill no)
		(layer "In1.Cu")
	)
	(gr_circle
		(center 36.7284 -86.316312)
		(end 37.6174 -86.316312)
		(stroke
			(width 0.2)
			(type default)
		)
		(fill no)
		(layer "In1.Cu")
	)
	(gr_circle
		(center 36.7284 -85.6234)
		(end 37.6174 -85.6234)
		(stroke
			(width 0.2)
			(type default)
		)
		(fill no)
		(layer "In1.Cu")
	)
	(gr_circle
		(center 37.206428 -264.922)
		(end 38.095428 -264.922)
		(stroke
			(width 0.2)
			(type default)
		)
		(fill no)
		(layer "In1.Cu")
	)
	(gr_circle
		(center 37.206428 -80.321912)
		(end 38.095428 -80.321912)
		(stroke
			(width 0.2)
			(type default)
		)
		(fill no)
		(layer "In1.Cu")
	)
	(gr_circle
		(center 37.738304 -37.883846)
		(end 38.627304 -37.883846)
		(stroke
			(width 0.2)
			(type default)
		)
		(fill no)
		(layer "In1.Cu")
	)
	(gr_circle
		(center 37.738304 -37.248846)
		(end 38.627304 -37.248846)
		(stroke
			(width 0.2)
			(type default)
		)
		(fill no)
		(layer "In1.Cu")
	)
	(gr_circle
		(center 37.968428 -264.922)
		(end 38.857428 -264.922)
		(stroke
			(width 0.2)
			(type default)
		)
		(fill no)
		(layer "In1.Cu")
	)
	(gr_circle
		(center 37.968428 -80.321912)
		(end 38.857428 -80.321912)
		(stroke
			(width 0.2)
			(type default)
		)
		(fill no)
		(layer "In1.Cu")
	)
	(gr_circle
		(center 38.014656 -44.308522)
		(end 38.903656 -44.308522)
		(stroke
			(width 0.2)
			(type default)
		)
		(fill no)
		(layer "In1.Cu")
	)
	(gr_circle
		(center 38.014656 -43.546522)
		(end 38.903656 -43.546522)
		(stroke
			(width 0.2)
			(type default)
		)
		(fill no)
		(layer "In1.Cu")
	)
	(gr_circle
		(center 38.014656 -42.784522)
		(end 38.903656 -42.784522)
		(stroke
			(width 0.2)
			(type default)
		)
		(fill no)
		(layer "In1.Cu")
	)
	(gr_circle
		(center 38.014656 -42.022522)
		(end 38.903656 -42.022522)
		(stroke
			(width 0.2)
			(type default)
		)
		(fill no)
		(layer "In1.Cu")
	)
	(gr_circle
		(center 38.065456 -227.61321)
		(end 38.954456 -227.61321)
		(stroke
			(width 0.2)
			(type default)
		)
		(fill no)
		(layer "In1.Cu")
	)
	(gr_circle
		(center 38.065456 -226.85121)
		(end 38.954456 -226.85121)
		(stroke
			(width 0.2)
			(type default)
		)
		(fill no)
		(layer "In1.Cu")
	)
	(gr_circle
		(center 38.065456 -226.08921)
		(end 38.954456 -226.08921)
		(stroke
			(width 0.2)
			(type default)
		)
		(fill no)
		(layer "In1.Cu")
	)
	(gr_circle
		(center 38.0746 -94.0562)
		(end 38.9636 -94.0562)
		(stroke
			(width 0.2)
			(type default)
		)
		(fill no)
		(layer "In1.Cu")
	)
	(gr_circle
		(center 38.0746 -93.352112)
		(end 38.9636 -93.352112)
		(stroke
			(width 0.2)
			(type default)
		)
		(fill no)
		(layer "In1.Cu")
	)
	(gr_circle
		(center 38.0746 -92.5322)
		(end 38.9636 -92.5322)
		(stroke
			(width 0.2)
			(type default)
		)
		(fill no)
		(layer "In1.Cu")
	)
	(gr_circle
		(center 38.0746 -89.3572)
		(end 38.9636 -89.3572)
		(stroke
			(width 0.2)
			(type default)
		)
		(fill no)
		(layer "In1.Cu")
	)
	(gr_circle
		(center 38.0746 -88.653112)
		(end 38.9636 -88.653112)
		(stroke
			(width 0.2)
			(type default)
		)
		(fill no)
		(layer "In1.Cu")
	)
	(gr_circle
		(center 38.0746 -87.9602)
		(end 38.9636 -87.9602)
		(stroke
			(width 0.2)
			(type default)
		)
		(fill no)
		(layer "In1.Cu")
	)
	(gr_circle
		(center 38.222428 -59.713622)
		(end 39.111428 -59.713622)
		(stroke
			(width 0.2)
			(type default)
		)
		(fill no)
		(layer "In1.Cu")
	)
	(gr_circle
		(center 38.222428 -59.078622)
		(end 39.111428 -59.078622)
		(stroke
			(width 0.2)
			(type default)
		)
		(fill no)
		(layer "In1.Cu")
	)
	(gr_circle
		(center 38.374828 -245.113556)
		(end 39.263828 -245.113556)
		(stroke
			(width 0.2)
			(type default)
		)
		(fill no)
		(layer "In1.Cu")
	)
	(gr_circle
		(center 38.374828 -244.478556)
		(end 39.263828 -244.478556)
		(stroke
			(width 0.2)
			(type default)
		)
		(fill no)
		(layer "In1.Cu")
	)
	(gr_circle
		(center 38.500304 -37.883846)
		(end 39.389304 -37.883846)
		(stroke
			(width 0.2)
			(type default)
		)
		(fill no)
		(layer "In1.Cu")
	)
	(gr_circle
		(center 38.500304 -37.248846)
		(end 39.389304 -37.248846)
		(stroke
			(width 0.2)
			(type default)
		)
		(fill no)
		(layer "In1.Cu")
	)
	(gr_circle
		(center 38.700456 -227.61321)
		(end 39.589456 -227.61321)
		(stroke
			(width 0.2)
			(type default)
		)
		(fill no)
		(layer "In1.Cu")
	)
	(gr_circle
		(center 38.700456 -226.85121)
		(end 39.589456 -226.85121)
		(stroke
			(width 0.2)
			(type default)
		)
		(fill no)
		(layer "In1.Cu")
	)
	(gr_circle
		(center 38.700456 -226.08921)
		(end 39.589456 -226.08921)
		(stroke
			(width 0.2)
			(type default)
		)
		(fill no)
		(layer "In1.Cu")
	)
	(gr_circle
		(center 38.857428 -59.713622)
		(end 39.746428 -59.713622)
		(stroke
			(width 0.2)
			(type default)
		)
		(fill no)
		(layer "In1.Cu")
	)
	(gr_circle
		(center 38.867588 -59.078622)
		(end 39.756588 -59.078622)
		(stroke
			(width 0.2)
			(type default)
		)
		(fill no)
		(layer "In1.Cu")
	)
	(gr_circle
		(center 39.009828 -245.113556)
		(end 39.898828 -245.113556)
		(stroke
			(width 0.2)
			(type default)
		)
		(fill no)
		(layer "In1.Cu")
	)
	(gr_circle
		(center 39.019988 -244.478556)
		(end 39.908988 -244.478556)
		(stroke
			(width 0.2)
			(type default)
		)
		(fill no)
		(layer "In1.Cu")
	)
	(gr_circle
		(center 39.262304 -37.883846)
		(end 40.151304 -37.883846)
		(stroke
			(width 0.2)
			(type default)
		)
		(fill no)
		(layer "In1.Cu")
	)
	(gr_circle
		(center 39.262304 -37.248846)
		(end 40.151304 -37.248846)
		(stroke
			(width 0.2)
			(type default)
		)
		(fill no)
		(layer "In1.Cu")
	)
	(gr_circle
		(center 39.512748 -59.713622)
		(end 40.401748 -59.713622)
		(stroke
			(width 0.2)
			(type default)
		)
		(fill no)
		(layer "In1.Cu")
	)
	(gr_circle
		(center 39.512748 -59.078622)
		(end 40.401748 -59.078622)
		(stroke
			(width 0.2)
			(type default)
		)
		(fill no)
		(layer "In1.Cu")
	)
	(gr_circle
		(center 39.665148 -245.113556)
		(end 40.554148 -245.113556)
		(stroke
			(width 0.2)
			(type default)
		)
		(fill no)
		(layer "In1.Cu")
	)
	(gr_circle
		(center 39.665148 -244.478556)
		(end 40.554148 -244.478556)
		(stroke
			(width 0.2)
			(type default)
		)
		(fill no)
		(layer "In1.Cu")
	)
	(gr_circle
		(center 39.821612 -264.32129)
		(end 40.710612 -264.32129)
		(stroke
			(width 0.2)
			(type default)
		)
		(fill no)
		(layer "In1.Cu")
	)
	(gr_circle
		(center 39.821612 -263.68629)
		(end 40.710612 -263.68629)
		(stroke
			(width 0.2)
			(type default)
		)
		(fill no)
		(layer "In1.Cu")
	)
	(gr_circle
		(center 39.821612 -79.721202)
		(end 40.710612 -79.721202)
		(stroke
			(width 0.2)
			(type default)
		)
		(fill no)
		(layer "In1.Cu")
	)
	(gr_circle
		(center 39.821612 -79.086202)
		(end 40.710612 -79.086202)
		(stroke
			(width 0.2)
			(type default)
		)
		(fill no)
		(layer "In1.Cu")
	)
	(gr_circle
		(center 40.349932 -84.385912)
		(end 41.238932 -84.385912)
		(stroke
			(width 0.2)
			(type default)
		)
		(fill no)
		(layer "In1.Cu")
	)
	(gr_circle
		(center 40.349932 -83.623912)
		(end 41.238932 -83.623912)
		(stroke
			(width 0.2)
			(type default)
		)
		(fill no)
		(layer "In1.Cu")
	)
	(gr_circle
		(center 40.466772 -264.32129)
		(end 41.355772 -264.32129)
		(stroke
			(width 0.2)
			(type default)
		)
		(fill no)
		(layer "In1.Cu")
	)
	(gr_circle
		(center 40.466772 -79.721202)
		(end 41.355772 -79.721202)
		(stroke
			(width 0.2)
			(type default)
		)
		(fill no)
		(layer "In1.Cu")
	)
	(gr_circle
		(center 40.476932 -263.68629)
		(end 41.365932 -263.68629)
		(stroke
			(width 0.2)
			(type default)
		)
		(fill no)
		(layer "In1.Cu")
	)
	(gr_circle
		(center 40.476932 -79.086202)
		(end 41.365932 -79.086202)
		(stroke
			(width 0.2)
			(type default)
		)
		(fill no)
		(layer "In1.Cu")
	)
	(gr_circle
		(center 41.111932 -264.32129)
		(end 42.000932 -264.32129)
		(stroke
			(width 0.2)
			(type default)
		)
		(fill no)
		(layer "In1.Cu")
	)
	(gr_circle
		(center 41.111932 -263.68629)
		(end 42.000932 -263.68629)
		(stroke
			(width 0.2)
			(type default)
		)
		(fill no)
		(layer "In1.Cu")
	)
	(gr_circle
		(center 41.111932 -79.721202)
		(end 42.000932 -79.721202)
		(stroke
			(width 0.2)
			(type default)
		)
		(fill no)
		(layer "In1.Cu")
	)
	(gr_circle
		(center 41.111932 -79.086202)
		(end 42.000932 -79.086202)
		(stroke
			(width 0.2)
			(type default)
		)
		(fill no)
		(layer "In1.Cu")
	)
	(gr_circle
		(center 41.370758 -237.363)
		(end 42.259758 -237.363)
		(stroke
			(width 0.2)
			(type default)
		)
		(fill no)
		(layer "In1.Cu")
	)
	(gr_circle
		(center 41.370758 -236.601)
		(end 42.259758 -236.601)
		(stroke
			(width 0.2)
			(type default)
		)
		(fill no)
		(layer "In1.Cu")
	)
	(gr_circle
		(center 41.370758 -234.823)
		(end 42.259758 -234.823)
		(stroke
			(width 0.2)
			(type default)
		)
		(fill no)
		(layer "In1.Cu")
	)
	(gr_circle
		(center 41.370758 -234.061)
		(end 42.259758 -234.061)
		(stroke
			(width 0.2)
			(type default)
		)
		(fill no)
		(layer "In1.Cu")
	)
	(gr_circle
		(center 41.370758 -232.029)
		(end 42.259758 -232.029)
		(stroke
			(width 0.2)
			(type default)
		)
		(fill no)
		(layer "In1.Cu")
	)
	(gr_circle
		(center 41.370758 -231.267)
		(end 42.259758 -231.267)
		(stroke
			(width 0.2)
			(type default)
		)
		(fill no)
		(layer "In1.Cu")
	)
	(gr_circle
		(center 41.407588 -58.570622)
		(end 42.296588 -58.570622)
		(stroke
			(width 0.2)
			(type default)
		)
		(fill no)
		(layer "In1.Cu")
	)
	(gr_circle
		(center 41.873932 -244.2972)
		(end 42.762932 -244.2972)
		(stroke
			(width 0.2)
			(type default)
		)
		(fill no)
		(layer "In1.Cu")
	)
	(gr_circle
		(center 41.875456 -52.944522)
		(end 42.764456 -52.944522)
		(stroke
			(width 0.2)
			(type default)
		)
		(fill no)
		(layer "In1.Cu")
	)
	(gr_circle
		(center 41.875456 -52.182522)
		(end 42.764456 -52.182522)
		(stroke
			(width 0.2)
			(type default)
		)
		(fill no)
		(layer "In1.Cu")
	)
	(gr_circle
		(center 41.900856 -50.683922)
		(end 42.789856 -50.683922)
		(stroke
			(width 0.2)
			(type default)
		)
		(fill no)
		(layer "In1.Cu")
	)
	(gr_circle
		(center 41.900856 -49.921922)
		(end 42.789856 -49.921922)
		(stroke
			(width 0.2)
			(type default)
		)
		(fill no)
		(layer "In1.Cu")
	)
	(gr_circle
		(center 41.951656 -48.042322)
		(end 42.840656 -48.042322)
		(stroke
			(width 0.2)
			(type default)
		)
		(fill no)
		(layer "In1.Cu")
	)
	(gr_circle
		(center 41.951656 -47.280322)
		(end 42.840656 -47.280322)
		(stroke
			(width 0.2)
			(type default)
		)
		(fill no)
		(layer "In1.Cu")
	)
	(gr_circle
		(center 42.037 -312.3946)
		(end 42.926 -312.3946)
		(stroke
			(width 0.2)
			(type default)
		)
		(fill no)
		(layer "In1.Cu")
	)
	(gr_circle
		(center 42.052748 -58.570622)
		(end 42.941748 -58.570622)
		(stroke
			(width 0.2)
			(type default)
		)
		(fill no)
		(layer "In1.Cu")
	)
	(gr_circle
		(center 42.635932 -244.2972)
		(end 43.524932 -244.2972)
		(stroke
			(width 0.2)
			(type default)
		)
		(fill no)
		(layer "In1.Cu")
	)
	(gr_circle
		(center 42.716958 -239.5474)
		(end 43.605958 -239.5474)
		(stroke
			(width 0.2)
			(type default)
		)
		(fill no)
		(layer "In1.Cu")
	)
	(gr_circle
		(center 42.716958 -238.7854)
		(end 43.605958 -238.7854)
		(stroke
			(width 0.2)
			(type default)
		)
		(fill no)
		(layer "In1.Cu")
	)
	(gr_circle
		(center 42.815256 -55.255922)
		(end 43.704256 -55.255922)
		(stroke
			(width 0.2)
			(type default)
		)
		(fill no)
		(layer "In1.Cu")
	)
	(gr_circle
		(center 42.815256 -54.493922)
		(end 43.704256 -54.493922)
		(stroke
			(width 0.2)
			(type default)
		)
		(fill no)
		(layer "In1.Cu")
	)
	(gr_circle
		(center 42.921428 -265.121136)
		(end 43.810428 -265.121136)
		(stroke
			(width 0.2)
			(type default)
		)
		(fill no)
		(layer "In1.Cu")
	)
	(gr_circle
		(center 42.921428 -264.486136)
		(end 43.810428 -264.486136)
		(stroke
			(width 0.2)
			(type default)
		)
		(fill no)
		(layer "In1.Cu")
	)
	(gr_circle
		(center 42.921428 -80.521048)
		(end 43.810428 -80.521048)
		(stroke
			(width 0.2)
			(type default)
		)
		(fill no)
		(layer "In1.Cu")
	)
	(gr_circle
		(center 42.921428 -79.886048)
		(end 43.810428 -79.886048)
		(stroke
			(width 0.2)
			(type default)
		)
		(fill no)
		(layer "In1.Cu")
	)
	(gr_circle
		(center 42.999914 -295.310052)
		(end 44.320714 -295.310052)
		(stroke
			(width 0.2)
			(type default)
		)
		(fill no)
		(layer "In1.Cu")
	)
	(gr_circle
		(center 42.999914 -203.010008)
		(end 44.320714 -203.010008)
		(stroke
			(width 0.2)
			(type default)
		)
		(fill no)
		(layer "In1.Cu")
	)
	(gr_circle
		(center 42.999914 -110.709964)
		(end 44.320714 -110.709964)
		(stroke
			(width 0.2)
			(type default)
		)
		(fill no)
		(layer "In1.Cu")
	)
	(gr_circle
		(center 42.999914 -18.40992)
		(end 44.320714 -18.40992)
		(stroke
			(width 0.2)
			(type default)
		)
		(fill no)
		(layer "In1.Cu")
	)
	(gr_circle
		(center 43.566588 -265.121136)
		(end 44.455588 -265.121136)
		(stroke
			(width 0.2)
			(type default)
		)
		(fill no)
		(layer "In1.Cu")
	)
	(gr_circle
		(center 43.566588 -80.521048)
		(end 44.455588 -80.521048)
		(stroke
			(width 0.2)
			(type default)
		)
		(fill no)
		(layer "In1.Cu")
	)
	(gr_circle
		(center 43.576748 -264.486136)
		(end 44.465748 -264.486136)
		(stroke
			(width 0.2)
			(type default)
		)
		(fill no)
		(layer "In1.Cu")
	)
	(gr_circle
		(center 43.576748 -79.886048)
		(end 44.465748 -79.886048)
		(stroke
			(width 0.2)
			(type default)
		)
		(fill no)
		(layer "In1.Cu")
	)
	(gr_circle
		(center 44.211748 -265.121136)
		(end 45.100748 -265.121136)
		(stroke
			(width 0.2)
			(type default)
		)
		(fill no)
		(layer "In1.Cu")
	)
	(gr_circle
		(center 44.211748 -264.486136)
		(end 45.100748 -264.486136)
		(stroke
			(width 0.2)
			(type default)
		)
		(fill no)
		(layer "In1.Cu")
	)
	(gr_circle
		(center 44.211748 -80.521048)
		(end 45.100748 -80.521048)
		(stroke
			(width 0.2)
			(type default)
		)
		(fill no)
		(layer "In1.Cu")
	)
	(gr_circle
		(center 44.211748 -79.886048)
		(end 45.100748 -79.886048)
		(stroke
			(width 0.2)
			(type default)
		)
		(fill no)
		(layer "In1.Cu")
	)
	(gr_circle
		(center 44.921932 -92.02166)
		(end 45.810932 -92.02166)
		(stroke
			(width 0.2)
			(type default)
		)
		(fill no)
		(layer "In1.Cu")
	)
	(gr_circle
		(center 44.921932 -91.38666)
		(end 45.810932 -91.38666)
		(stroke
			(width 0.2)
			(type default)
		)
		(fill no)
		(layer "In1.Cu")
	)
	(gr_circle
		(center 44.99991 -293.310056)
		(end 46.32071 -293.310056)
		(stroke
			(width 0.2)
			(type default)
		)
		(fill no)
		(layer "In1.Cu")
	)
	(gr_circle
		(center 44.99991 -201.010012)
		(end 46.32071 -201.010012)
		(stroke
			(width 0.2)
			(type default)
		)
		(fill no)
		(layer "In1.Cu")
	)
	(gr_circle
		(center 44.99991 -108.709968)
		(end 46.32071 -108.709968)
		(stroke
			(width 0.2)
			(type default)
		)
		(fill no)
		(layer "In1.Cu")
	)
	(gr_circle
		(center 44.99991 -16.409924)
		(end 46.32071 -16.409924)
		(stroke
			(width 0.2)
			(type default)
		)
		(fill no)
		(layer "In1.Cu")
	)
	(gr_circle
		(center 45.556932 -58.503312)
		(end 46.445932 -58.503312)
		(stroke
			(width 0.2)
			(type default)
		)
		(fill no)
		(layer "In1.Cu")
	)
	(gr_circle
		(center 45.556932 -57.741312)
		(end 46.445932 -57.741312)
		(stroke
			(width 0.2)
			(type default)
		)
		(fill no)
		(layer "In1.Cu")
	)
	(gr_circle
		(center 45.633132 -61.856112)
		(end 46.522132 -61.856112)
		(stroke
			(width 0.2)
			(type default)
		)
		(fill no)
		(layer "In1.Cu")
	)
	(gr_circle
		(center 45.683932 -92.02166)
		(end 46.572932 -92.02166)
		(stroke
			(width 0.2)
			(type default)
		)
		(fill no)
		(layer "In1.Cu")
	)
	(gr_circle
		(center 45.683932 -91.38666)
		(end 46.572932 -91.38666)
		(stroke
			(width 0.2)
			(type default)
		)
		(fill no)
		(layer "In1.Cu")
	)
	(gr_circle
		(center 45.836332 -281.092148)
		(end 46.725332 -281.092148)
		(stroke
			(width 0.2)
			(type default)
		)
		(fill no)
		(layer "In1.Cu")
	)
	(gr_circle
		(center 45.836332 -280.330148)
		(end 46.725332 -280.330148)
		(stroke
			(width 0.2)
			(type default)
		)
		(fill no)
		(layer "In1.Cu")
	)
	(gr_circle
		(center 45.887132 -246.126)
		(end 46.776132 -246.126)
		(stroke
			(width 0.2)
			(type default)
		)
		(fill no)
		(layer "In1.Cu")
	)
	(gr_circle
		(center 45.887132 -242.8494)
		(end 46.776132 -242.8494)
		(stroke
			(width 0.2)
			(type default)
		)
		(fill no)
		(layer "In1.Cu")
	)
	(gr_circle
		(center 45.887132 -242.0366)
		(end 46.776132 -242.0366)
		(stroke
			(width 0.2)
			(type default)
		)
		(fill no)
		(layer "In1.Cu")
	)
	(gr_circle
		(center 46.318932 -58.503312)
		(end 47.207932 -58.503312)
		(stroke
			(width 0.2)
			(type default)
		)
		(fill no)
		(layer "In1.Cu")
	)
	(gr_circle
		(center 46.318932 -57.741312)
		(end 47.207932 -57.741312)
		(stroke
			(width 0.2)
			(type default)
		)
		(fill no)
		(layer "In1.Cu")
	)
	(gr_circle
		(center 46.395132 -61.856112)
		(end 47.284132 -61.856112)
		(stroke
			(width 0.2)
			(type default)
		)
		(fill no)
		(layer "In1.Cu")
	)
	(gr_circle
		(center 46.445932 -92.02166)
		(end 47.334932 -92.02166)
		(stroke
			(width 0.2)
			(type default)
		)
		(fill no)
		(layer "In1.Cu")
	)
	(gr_circle
		(center 46.445932 -91.38666)
		(end 47.334932 -91.38666)
		(stroke
			(width 0.2)
			(type default)
		)
		(fill no)
		(layer "In1.Cu")
	)
	(gr_circle
		(center 46.598332 -281.092148)
		(end 47.487332 -281.092148)
		(stroke
			(width 0.2)
			(type default)
		)
		(fill no)
		(layer "In1.Cu")
	)
	(gr_circle
		(center 46.598332 -280.330148)
		(end 47.487332 -280.330148)
		(stroke
			(width 0.2)
			(type default)
		)
		(fill no)
		(layer "In1.Cu")
	)
	(gr_circle
		(center 46.674532 -246.1514)
		(end 47.563532 -246.1514)
		(stroke
			(width 0.2)
			(type default)
		)
		(fill no)
		(layer "In1.Cu")
	)
	(gr_circle
		(center 46.674532 -242.8748)
		(end 47.563532 -242.8748)
		(stroke
			(width 0.2)
			(type default)
		)
		(fill no)
		(layer "In1.Cu")
	)
	(gr_circle
		(center 46.674532 -242.062)
		(end 47.563532 -242.062)
		(stroke
			(width 0.2)
			(type default)
		)
		(fill no)
		(layer "In1.Cu")
	)
	(gr_circle
		(center 47.080932 -58.503312)
		(end 47.969932 -58.503312)
		(stroke
			(width 0.2)
			(type default)
		)
		(fill no)
		(layer "In1.Cu")
	)
	(gr_circle
		(center 47.080932 -57.741312)
		(end 47.969932 -57.741312)
		(stroke
			(width 0.2)
			(type default)
		)
		(fill no)
		(layer "In1.Cu")
	)
	(gr_circle
		(center 47.157132 -61.856112)
		(end 48.046132 -61.856112)
		(stroke
			(width 0.2)
			(type default)
		)
		(fill no)
		(layer "In1.Cu")
	)
	(gr_circle
		(center 47.207932 -92.02166)
		(end 48.096932 -92.02166)
		(stroke
			(width 0.2)
			(type default)
		)
		(fill no)
		(layer "In1.Cu")
	)
	(gr_circle
		(center 47.207932 -91.38666)
		(end 48.096932 -91.38666)
		(stroke
			(width 0.2)
			(type default)
		)
		(fill no)
		(layer "In1.Cu")
	)
	(gr_circle
		(center 47.360332 -281.092148)
		(end 48.249332 -281.092148)
		(stroke
			(width 0.2)
			(type default)
		)
		(fill no)
		(layer "In1.Cu")
	)
	(gr_circle
		(center 47.360332 -280.330148)
		(end 48.249332 -280.330148)
		(stroke
			(width 0.2)
			(type default)
		)
		(fill no)
		(layer "In1.Cu")
	)
	(gr_circle
		(center 47.411132 -246.126)
		(end 48.300132 -246.126)
		(stroke
			(width 0.2)
			(type default)
		)
		(fill no)
		(layer "In1.Cu")
	)
	(gr_circle
		(center 47.411132 -242.8494)
		(end 48.300132 -242.8494)
		(stroke
			(width 0.2)
			(type default)
		)
		(fill no)
		(layer "In1.Cu")
	)
	(gr_circle
		(center 47.411132 -242.0366)
		(end 48.300132 -242.0366)
		(stroke
			(width 0.2)
			(type default)
		)
		(fill no)
		(layer "In1.Cu")
	)
	(gr_poly
		(pts
			(arc
				(start 15.026386 -166.803324)
				(mid 15.052415 -166.817134)
				(end 15.081758 -166.814246)
			)
			(xy 15.095982 -166.808404) (xy 15.113 -166.783004) (xy 15.113 -166.22649)
			(arc
				(start 15.112492 -166.222934)
				(mid 15.109482 -166.196211)
				(end 15.108428 -166.16934)
			)
			(arc
				(start 15.108428 -165.559232)
				(mid 15.104595 -165.539875)
				(end 15.093696 -165.523418)
			)
			(arc
				(start 14.750034 -165.179502)
				(mid 14.670142 -165.059936)
				(end 14.642084 -164.918898)
			)
			(xy 14.642084 -161.382456) (xy 14.63421 -161.363914) (xy 14.629384 -161.359088)
			(arc
				(start 14.367256 -161.359088)
				(mid 14.347899 -161.362921)
				(end 14.331442 -161.37382)
			)
			(arc
				(start 13.567156 -162.138106)
				(mid 13.553346 -162.164135)
				(end 13.556234 -162.193478)
			)
			(xy 13.562076 -162.207702) (xy 13.587476 -162.22472)
			(arc
				(start 13.66266 -162.22472)
				(mid 13.698581 -162.239599)
				(end 13.71346 -162.27552)
			)
			(arc
				(start 13.71346 -163.79444)
				(mid 13.698581 -163.830361)
				(end 13.66266 -163.84524)
			)
			(arc
				(start 13.62837 -163.84524)
				(mid 13.603474 -163.851759)
				(end 13.584936 -163.869624)
			)
			(xy 13.53312 -163.955222) (xy 13.532104 -163.981638)
			(arc
				(start 13.5382 -163.993576)
				(mid 13.568922 -164.075818)
				(end 13.579348 -164.162994)
			)
			(arc
				(start 13.579348 -165.88867)
				(mid 13.583298 -165.908057)
				(end 13.594334 -165.924484)
			)
			(arc
				(start 14.286738 -166.616888)
				(mid 14.303184 -166.627814)
				(end 14.322552 -166.63162)
			)
			(arc
				(start 14.702028 -166.63162)
				(mid 14.843097 -166.659792)
				(end 14.962632 -166.739824)
			)
		)
		(stroke
			(width 0)
			(type solid)
		)
		(fill yes)
		(layer "In2.Cu")
		(net "P3V3_AUX")
	)
	(gr_poly
		(pts
			(arc
				(start 8.952992 -173.99)
				(mid 8.988913 -173.975121)
				(end 9.003792 -173.9392)
			)
			(arc
				(start 9.003792 -167.34536)
				(mid 8.999959 -167.326003)
				(end 8.98906 -167.309546)
			)
			(arc
				(start 6.678422 -164.998908)
				(mid 6.652431 -164.984902)
				(end 6.62305 -164.987732)
			)
			(xy 6.608572 -164.993828) (xy 6.591808 -165.018974)
			(arc
				(start 6.591808 -165.180264)
				(mid 6.595641 -165.199621)
				(end 6.60654 -165.216078)
			)
			(arc
				(start 7.91591 -166.525702)
				(mid 7.995802 -166.645268)
				(end 8.02386 -166.786306)
			)
			(arc
				(start 8.02386 -167.193722)
				(mid 8.029888 -167.217723)
				(end 8.046466 -167.23614)
			)
			(xy 8.127746 -167.290242) (xy 8.152638 -167.292528)
			(arc
				(start 8.164576 -167.287702)
				(mid 8.236288 -167.265895)
				(end 8.31088 -167.258492)
			)
			(arc
				(start 8.31088 -167.258492)
				(mid 8.692388 -167.64)
				(end 8.31088 -168.021508)
			)
			(arc
				(start 8.31088 -168.021508)
				(mid 8.23628 -168.014143)
				(end 8.164576 -167.992298)
			)
			(xy 8.152638 -167.987472) (xy 8.127746 -167.989758)
			(arc
				(start 8.046466 -168.04386)
				(mid 8.02977 -168.062214)
				(end 8.02386 -168.086278)
			)
			(arc
				(start 8.02386 -172.020738)
				(mid 8.029997 -172.044691)
				(end 8.04672 -172.062902)
			)
			(xy 8.127746 -172.117004) (xy 8.153146 -172.11929)
			(arc
				(start 8.165084 -172.114464)
				(mid 8.2375 -172.092079)
				(end 8.312912 -172.084492)
			)
			(arc
				(start 8.312912 -172.084492)
				(mid 8.69442 -172.466)
				(end 8.312912 -172.847508)
			)
			(arc
				(start 8.312912 -172.847508)
				(mid 8.237508 -172.83988)
				(end 8.165084 -172.817536)
			)
			(xy 8.153146 -172.81271) (xy 8.127746 -172.814996)
			(arc
				(start 8.04672 -172.869098)
				(mid 8.030004 -172.887313)
				(end 8.02386 -172.911262)
			)
			(arc
				(start 8.02386 -173.59757)
				(mid 8.02781 -173.616957)
				(end 8.038846 -173.633384)
			)
			(arc
				(start 8.380476 -173.975014)
				(mid 8.39701 -173.986125)
				(end 8.416544 -173.99)
			)
		)
		(stroke
			(width 0)
			(type solid)
		)
		(fill yes)
		(layer "In2.Cu")
		(net "P3V3_AUX")
	)
	(gr_poly
		(pts
			(xy 16.151352 -169.453052) (xy 16.162166 -169.452615) (xy 16.181906 -169.443793) (xy 16.189452 -169.436034)
			(xy 16.24711 -169.370502) (xy 16.25346 -169.349674) (xy 16.25219 -169.338752) (xy 16.25078 -169.326864)
			(xy 16.249256 -169.302971) (xy 16.249142 -169.291) (xy 16.2496 -169.264444) (xy 16.256967 -169.211844)
			(xy 16.271557 -169.160774) (xy 16.281908 -169.136314) (xy 16.286226 -169.126408) (xy 16.28648 -169.106088)
			(xy 16.250158 -169.018458) (xy 16.235426 -169.00398) (xy 16.22552 -169.00017) (xy 16.201639 -168.99053)
			(xy 16.156609 -168.965538) (xy 16.115496 -168.934521) (xy 16.096996 -168.916604) (xy 14.564106 -167.383968)
			(xy 14.556695 -167.377286) (xy 14.538259 -167.369707) (xy 14.528292 -167.369236) (xy 14.148816 -167.369236)
			(xy 14.119843 -167.368674) (xy 14.062619 -167.359562) (xy 14.007525 -167.341607) (xy 13.955919 -167.315251)
			(xy 13.909075 -167.281144) (xy 13.888212 -167.261032) (xy 12.95019 -166.32301) (xy 12.930113 -166.30213)
			(xy 12.896067 -166.25527) (xy 12.869771 -166.203662) (xy 12.851872 -166.148575) (xy 12.84281 -166.091367)
			(xy 12.84224 -166.062406) (xy 12.84224 -164.33673) (xy 12.841706 -164.326741) (xy 12.833994 -164.308307)
			(xy 12.827254 -164.300916) (xy 12.468606 -163.942268) (xy 12.461195 -163.935586) (xy 12.442759 -163.928007)
			(xy 12.432792 -163.927536) (xy 12.03706 -163.927536) (xy 12.026266 -163.927904) (xy 12.006512 -163.936581)
			(xy 11.99896 -163.9443) (xy 11.941302 -164.009324) (xy 11.934698 -164.029644) (xy 11.935968 -164.040566)
			(xy 11.937143 -164.051386) (xy 11.938412 -164.073116) (xy 11.938508 -164.084) (xy 11.938022 -164.111251)
			(xy 11.930266 -164.165199) (xy 11.914911 -164.217494) (xy 11.892269 -164.267071) (xy 11.862803 -164.312921)
			(xy 11.827112 -164.354112) (xy 11.785921 -164.389803) (xy 11.740071 -164.419269) (xy 11.690494 -164.441911)
			(xy 11.638199 -164.457266) (xy 11.584251 -164.465022) (xy 11.529749 -164.465022) (xy 11.475801 -164.457266)
			(xy 11.423506 -164.441911) (xy 11.373929 -164.419269) (xy 11.328079 -164.389803) (xy 11.286888 -164.354112)
			(xy 11.251197 -164.312921) (xy 11.221731 -164.267071) (xy 11.199089 -164.217494) (xy 11.183734 -164.165199)
			(xy 11.175978 -164.111251) (xy 11.175492 -164.084) (xy 11.175584 -164.073116) (xy 11.176854 -164.051386)
			(xy 11.178032 -164.040566) (xy 11.179302 -164.029644) (xy 11.172698 -164.009324) (xy 11.11504 -163.9443)
			(xy 11.107391 -163.936714) (xy 11.0877 -163.928041) (xy 11.07694 -163.927536) (xy 9.468104 -163.927536)
			(xy 9.458072 -163.92789) (xy 9.439508 -163.935487) (xy 9.425317 -163.949662) (xy 9.421114 -163.958778)
			(xy 9.415272 -163.973256) (xy 9.421114 -164.002974) (xy 9.629902 -164.211762) (xy 9.637246 -164.218576)
			(xy 9.655708 -164.226314) (xy 9.665716 -164.226748) (xy 10.541 -164.226748) (xy 10.569963 -164.227286)
			(xy 10.627177 -164.236348) (xy 10.682269 -164.254249) (xy 10.733882 -164.280547) (xy 10.780746 -164.314596)
			(xy 10.801604 -164.334698) (xy 11.312931 -164.846) (xy 11.682728 -164.846) (xy 11.686799 -164.790378)
			(xy 11.698925 -164.735941) (xy 11.718848 -164.68385) (xy 11.746144 -164.635215) (xy 11.78023 -164.591072)
			(xy 11.820379 -164.552363) (xy 11.865737 -164.519912) (xy 11.915337 -164.494411) (xy 11.968121 -164.476404)
			(xy 12.022964 -164.466274) (xy 12.078698 -164.464237) (xy 12.134135 -164.470337) (xy 12.188092 -164.484443)
			(xy 12.239421 -164.506255) (xy 12.287027 -164.535309) (xy 12.329895 -164.570984) (xy 12.367112 -164.612521)
			(xy 12.397885 -164.659034) (xy 12.421557 -164.709531) (xy 12.437625 -164.762938) (xy 12.445745 -164.818114)
			(xy 12.446254 -164.846) (xy 12.445745 -164.873886) (xy 12.437625 -164.929062) (xy 12.421557 -164.982469)
			(xy 12.397885 -165.032966) (xy 12.367112 -165.079479) (xy 12.329895 -165.121016) (xy 12.287027 -165.156691)
			(xy 12.239421 -165.185745) (xy 12.188092 -165.207557) (xy 12.134135 -165.221663) (xy 12.078698 -165.227763)
			(xy 12.022964 -165.225726) (xy 11.968121 -165.215596) (xy 11.915337 -165.197589) (xy 11.865737 -165.172088)
			(xy 11.820379 -165.139637) (xy 11.78023 -165.100928) (xy 11.746144 -165.056785) (xy 11.718848 -165.00815)
			(xy 11.698925 -164.956059) (xy 11.686799 -164.901622) (xy 11.682728 -164.846) (xy 11.312931 -164.846)
			(xy 15.90548 -169.43832) (xy 15.91289 -169.445005) (xy 15.931325 -169.452591) (xy 15.941294 -169.453052)
		)
		(stroke
			(width 0)
			(type solid)
		)
		(fill yes)
		(layer "In2.Cu")
		(net "P3V3_AUX")
	)
	(gr_poly
		(pts
			(xy 5.628386 -171.98467) (xy 5.635829 -171.991366) (xy 5.654328 -171.998969) (xy 5.674329 -171.998957)
			(xy 5.683758 -171.995592) (xy 5.697982 -171.98975) (xy 5.715 -171.96435) (xy 5.715 -171.6278) (xy 5.715488 -171.617792)
			(xy 5.723148 -171.599301) (xy 5.737301 -171.585148) (xy 5.755792 -171.577488) (xy 5.7658 -171.577)
			(xy 7.235952 -171.577) (xy 7.24598 -171.576589) (xy 7.264513 -171.568927) (xy 7.2787 -171.554753)
			(xy 7.286379 -171.536227) (xy 7.286752 -171.5262) (xy 7.286752 -166.960042) (xy 7.286221 -166.950052)
			(xy 7.278513 -166.931614) (xy 7.271766 -166.924228) (xy 5.962396 -165.614604) (xy 5.942269 -165.593754)
			(xy 5.908165 -165.546905) (xy 5.881811 -165.495297) (xy 5.863856 -165.440201) (xy 5.854742 -165.382974)
			(xy 5.854192 -165.354) (xy 5.854192 -163.86683) (xy 5.853705 -163.856868) (xy 5.846115 -163.838446)
			(xy 5.83946 -163.831016) (xy 5.293614 -163.28517) (xy 5.286172 -163.27847) (xy 5.267673 -163.270861)
			(xy 5.247669 -163.270873) (xy 5.238242 -163.274248) (xy 5.224018 -163.28009) (xy 5.207 -163.30549)
			(xy 5.207 -163.9062) (xy 5.206512 -163.916208) (xy 5.198852 -163.934699) (xy 5.184699 -163.948852)
			(xy 5.166208 -163.956512) (xy 5.1562 -163.957) (xy 5.0038 -163.957) (xy 4.993792 -163.956512) (xy 4.975301 -163.948852)
			(xy 4.961148 -163.934699) (xy 4.953488 -163.916208) (xy 4.953 -163.9062) (xy 4.953 -163.597082) (xy 4.952573 -163.587013)
			(xy 4.944854 -163.568414) (xy 4.938014 -163.561014) (xy 4.821682 -163.444682) (xy 4.814317 -163.437864)
			(xy 4.79581 -163.43014) (xy 4.775755 -163.430107) (xy 4.76631 -163.433506) (xy 4.751832 -163.439602)
			(xy 4.735068 -163.465002) (xy 4.735068 -168.416986) (xy 4.735557 -168.426947) (xy 4.743146 -168.44537)
			(xy 4.7498 -168.4528) (xy 4.811014 -168.514014) (xy 4.817868 -168.521409) (xy 4.82561 -168.540008)
			(xy 4.826 -168.550082) (xy 4.826 -168.6179) (xy 5.973824 -168.6179) (xy 5.977895 -168.562278) (xy 5.990021 -168.507841)
			(xy 6.009944 -168.45575) (xy 6.03724 -168.407115) (xy 6.071326 -168.362972) (xy 6.111475 -168.324263)
			(xy 6.156833 -168.291812) (xy 6.206433 -168.266311) (xy 6.259217 -168.248304) (xy 6.31406 -168.238174)
			(xy 6.369794 -168.236137) (xy 6.425231 -168.242237) (xy 6.479188 -168.256343) (xy 6.530517 -168.278155)
			(xy 6.578123 -168.307209) (xy 6.620991 -168.342884) (xy 6.658208 -168.384421) (xy 6.688981 -168.430934)
			(xy 6.712653 -168.481431) (xy 6.728721 -168.534838) (xy 6.736841 -168.590014) (xy 6.73735 -168.6179)
			(xy 6.736841 -168.645786) (xy 6.728721 -168.700962) (xy 6.712653 -168.754369) (xy 6.688981 -168.804866)
			(xy 6.658208 -168.851379) (xy 6.620991 -168.892916) (xy 6.578123 -168.928591) (xy 6.530517 -168.957645)
			(xy 6.479188 -168.979457) (xy 6.425231 -168.993563) (xy 6.369794 -168.999663) (xy 6.31406 -168.997626)
			(xy 6.259217 -168.987496) (xy 6.206433 -168.969489) (xy 6.156833 -168.943988) (xy 6.111475 -168.911537)
			(xy 6.071326 -168.872828) (xy 6.03724 -168.828685) (xy 6.009944 -168.78005) (xy 5.990021 -168.727959)
			(xy 5.977895 -168.673522) (xy 5.973824 -168.6179) (xy 4.826 -168.6179) (xy 4.826 -169.650918) (xy 4.825573 -169.660987)
			(xy 4.817854 -169.679586) (xy 4.811014 -169.686986) (xy 4.3561 -170.1419) (xy 5.973824 -170.1419)
			(xy 5.977895 -170.086278) (xy 5.990021 -170.031841) (xy 6.009944 -169.97975) (xy 6.03724 -169.931115)
			(xy 6.071326 -169.886972) (xy 6.111475 -169.848263) (xy 6.156833 -169.815812) (xy 6.206433 -169.790311)
			(xy 6.259217 -169.772304) (xy 6.31406 -169.762174) (xy 6.369794 -169.760137) (xy 6.425231 -169.766237)
			(xy 6.479188 -169.780343) (xy 6.530517 -169.802155) (xy 6.578123 -169.831209) (xy 6.620991 -169.866884)
			(xy 6.658208 -169.908421) (xy 6.688981 -169.954934) (xy 6.712653 -170.005431) (xy 6.728721 -170.058838)
			(xy 6.736841 -170.114014) (xy 6.73735 -170.1419) (xy 6.736841 -170.169786) (xy 6.728721 -170.224962)
			(xy 6.712653 -170.278369) (xy 6.688981 -170.328866) (xy 6.658208 -170.375379) (xy 6.620991 -170.416916)
			(xy 6.578123 -170.452591) (xy 6.530517 -170.481645) (xy 6.479188 -170.503457) (xy 6.425231 -170.517563)
			(xy 6.369794 -170.523663) (xy 6.31406 -170.521626) (xy 6.259217 -170.511496) (xy 6.206433 -170.493489)
			(xy 6.156833 -170.467988) (xy 6.111475 -170.435537) (xy 6.071326 -170.396828) (xy 6.03724 -170.352685)
			(xy 6.009944 -170.30405) (xy 5.990021 -170.251959) (xy 5.977895 -170.197522) (xy 5.973824 -170.1419)
			(xy 4.3561 -170.1419) (xy 4.106672 -170.391328) (xy 4.09985 -170.398705) (xy 4.09213 -170.417239)
			(xy 4.092122 -170.437317) (xy 4.099825 -170.455859) (xy 4.106672 -170.46321)
		)
		(stroke
			(width 0)
			(type solid)
		)
		(fill yes)
		(layer "In2.Cu")
		(net "P3V3_AUX")
	)
	(gr_poly
		(pts
			(xy 13.550646 -180.440076) (xy 16.86306 -177.127662) (xy 16.869801 -177.120291) (xy 16.877385 -177.101829)
			(xy 16.877792 -177.091848) (xy 16.877792 -174.450502) (xy 16.877142 -174.438569) (xy 16.866409 -174.417248)
			(xy 16.857218 -174.409608) (xy 16.781018 -174.353982) (xy 16.757396 -174.349918) (xy 16.745712 -174.353728)
			(xy 16.717678 -174.362048) (xy 16.659888 -174.370983) (xy 16.63065 -174.371508) (xy 16.603399 -174.371022)
			(xy 16.549451 -174.363266) (xy 16.497156 -174.347911) (xy 16.447579 -174.325269) (xy 16.401729 -174.295803)
			(xy 16.360538 -174.260112) (xy 16.324847 -174.218921) (xy 16.295381 -174.173071) (xy 16.272739 -174.123494)
			(xy 16.257384 -174.071199) (xy 16.249628 -174.017251) (xy 16.249628 -173.962749) (xy 16.257384 -173.908801)
			(xy 16.272739 -173.856506) (xy 16.295381 -173.806929) (xy 16.324847 -173.761079) (xy 16.360538 -173.719888)
			(xy 16.401729 -173.684197) (xy 16.447579 -173.654731) (xy 16.497156 -173.632089) (xy 16.549451 -173.616734)
			(xy 16.603399 -173.608978) (xy 16.63065 -173.608492) (xy 16.659888 -173.60902) (xy 16.71768 -173.617942)
			(xy 16.745712 -173.626272) (xy 16.757396 -173.630082) (xy 16.781018 -173.626018) (xy 16.857218 -173.570392)
			(xy 16.86644 -173.562779) (xy 16.877161 -173.541441) (xy 16.877792 -173.529498) (xy 16.877792 -172.8724)
			(xy 16.8783 -172.85335) (xy 16.828262 -172.820838) (xy 16.817363 -172.814548) (xy 16.792319 -172.812425)
			(xy 16.78051 -172.816774) (xy 16.756736 -172.826495) (xy 16.707229 -172.840178) (xy 16.656332 -172.847079)
			(xy 16.63065 -172.847508) (xy 16.603395 -172.847048) (xy 16.549438 -172.839297) (xy 16.497135 -172.823945)
			(xy 16.447548 -172.801306) (xy 16.401689 -172.771839) (xy 16.36049 -172.736145) (xy 16.324791 -172.694951)
			(xy 16.295318 -172.649096) (xy 16.272672 -172.599512) (xy 16.257314 -172.54721) (xy 16.249555 -172.493255)
			(xy 16.249142 -172.466) (xy 16.249858 -172.432801) (xy 16.26135 -172.367404) (xy 16.272002 -172.335952)
			(xy 16.27632 -172.324268) (xy 16.273018 -172.29963) (xy 16.218154 -172.221398) (xy 16.210538 -172.211755)
			(xy 16.188767 -172.200449) (xy 16.176498 -172.199808) (xy 15.921736 -172.199808) (xy 15.911774 -172.200294)
			(xy 15.89335 -172.207882) (xy 15.885922 -172.21454) (xy 12.95654 -175.143922) (xy 12.949797 -175.151292)
			(xy 12.942206 -175.169754) (xy 12.941808 -175.179736) (xy 12.941808 -176.520602) (xy 12.942163 -176.530635)
			(xy 12.949758 -176.5492) (xy 12.963931 -176.563396) (xy 12.97305 -176.567592) (xy 12.987528 -176.573434)
			(xy 13.017246 -176.567592) (xy 14.77645 -174.808388) (xy 14.779752 -174.803054) (xy 14.794643 -174.779264)
			(xy 14.830305 -174.735928) (xy 14.871929 -174.698281) (xy 14.918618 -174.667136) (xy 14.969364 -174.643164)
			(xy 15.023073 -174.626882) (xy 15.078589 -174.618641) (xy 15.10665 -174.618142) (xy 15.133904 -174.618602)
			(xy 15.187858 -174.626353) (xy 15.240159 -174.641706) (xy 15.289742 -174.664346) (xy 15.335598 -174.693813)
			(xy 15.376792 -174.729508) (xy 15.412487 -174.770702) (xy 15.441954 -174.816558) (xy 15.464594 -174.866141)
			(xy 15.479947 -174.918442) (xy 15.487698 -174.972396) (xy 15.488158 -174.99965) (xy 15.487664 -175.027714)
			(xy 15.479444 -175.083238) (xy 15.463174 -175.136956) (xy 15.439206 -175.18771) (xy 15.408058 -175.234403)
			(xy 15.370402 -175.276025) (xy 15.327052 -175.311679) (xy 15.303246 -175.326548) (xy 15.297912 -175.32985)
			(xy 13.593826 -177.033936) (xy 14.857982 -177.033936) (xy 14.862053 -176.978314) (xy 14.874179 -176.923877)
			(xy 14.894102 -176.871786) (xy 14.921398 -176.823151) (xy 14.955484 -176.779008) (xy 14.995633 -176.740299)
			(xy 15.040991 -176.707848) (xy 15.090591 -176.682347) (xy 15.143375 -176.66434) (xy 15.198218 -176.65421)
			(xy 15.253952 -176.652173) (xy 15.309389 -176.658273) (xy 15.363346 -176.672379) (xy 15.414675 -176.694191)
			(xy 15.462281 -176.723245) (xy 15.505149 -176.75892) (xy 15.542366 -176.800457) (xy 15.573139 -176.84697)
			(xy 15.596811 -176.897467) (xy 15.612879 -176.950874) (xy 15.620999 -177.00605) (xy 15.621508 -177.033936)
			(xy 15.620999 -177.061822) (xy 15.612879 -177.116998) (xy 15.596811 -177.170405) (xy 15.573139 -177.220902)
			(xy 15.542366 -177.267415) (xy 15.505149 -177.308952) (xy 15.462281 -177.344627) (xy 15.414675 -177.373681)
			(xy 15.363346 -177.395493) (xy 15.309389 -177.409599) (xy 15.253952 -177.415699) (xy 15.198218 -177.413662)
			(xy 15.143375 -177.403532) (xy 15.090591 -177.385525) (xy 15.040991 -177.360024) (xy 14.995633 -177.327573)
			(xy 14.955484 -177.288864) (xy 14.921398 -177.244721) (xy 14.894102 -177.196086) (xy 14.874179 -177.143995)
			(xy 14.862053 -177.089558) (xy 14.857982 -177.033936) (xy 13.593826 -177.033936) (xy 13.48994 -177.137822)
			(xy 13.483197 -177.145192) (xy 13.475606 -177.163654) (xy 13.475208 -177.173636) (xy 13.475208 -180.393086)
			(xy 13.47556 -180.403121) (xy 13.483152 -180.421691) (xy 13.497324 -180.435892) (xy 13.50645 -180.440076)
			(xy 13.520928 -180.445918)
		)
		(stroke
			(width 0)
			(type solid)
		)
		(fill yes)
		(layer "In2.Cu")
		(net "P3V3_AUX")
	)
	(gr_poly
		(pts
			(xy 4.433824 -190.373) (xy 4.443892 -190.372572) (xy 4.46249 -190.364852) (xy 4.469892 -190.358014)
			(xy 4.712716 -190.11519) (xy 4.719397 -190.107779) (xy 4.726973 -190.089343) (xy 4.727448 -190.079376)
			(xy 4.727448 -187.68822) (xy 4.726776 -187.675576) (xy 4.71478 -187.653315) (xy 4.704588 -187.645802)
			(xy 4.623054 -187.591954) (xy 4.597654 -187.589922) (xy 4.585716 -187.595002) (xy 4.561714 -187.604879)
			(xy 4.51171 -187.618791) (xy 4.460284 -187.625807) (xy 4.434332 -187.626244) (xy 4.407079 -187.625781)
			(xy 4.353129 -187.618024) (xy 4.300831 -187.602668) (xy 4.251251 -187.580026) (xy 4.205398 -187.550559)
			(xy 4.164206 -187.514865) (xy 4.128513 -187.473673) (xy 4.099045 -187.42782) (xy 4.076402 -187.378241)
			(xy 4.061046 -187.325943) (xy 4.053289 -187.271993) (xy 4.053289 -187.217487) (xy 4.061046 -187.163537)
			(xy 4.076402 -187.111239) (xy 4.099045 -187.06166) (xy 4.128513 -187.015807) (xy 4.164206 -186.974615)
			(xy 4.205398 -186.938921) (xy 4.251251 -186.909454) (xy 4.300831 -186.886812) (xy 4.353129 -186.871456)
			(xy 4.407079 -186.863699) (xy 4.434332 -186.863228) (xy 4.460286 -186.863642) (xy 4.511719 -186.870642)
			(xy 4.561725 -186.884562) (xy 4.585716 -186.89447) (xy 4.597654 -186.89955) (xy 4.623054 -186.897518)
			(xy 4.704588 -186.84367) (xy 4.714776 -186.836152) (xy 4.726779 -186.813895) (xy 4.727448 -186.801252)
			(xy 4.727448 -181.621176) (xy 4.726968 -181.611212) (xy 4.719385 -181.592781) (xy 4.712716 -181.585362)
			(xy 3.79984 -180.672486) (xy 3.794506 -180.669184) (xy 3.766312 -180.650642) (xy 3.757431 -180.644888)
			(xy 3.73676 -180.640471) (xy 3.716062 -180.644759) (xy 3.698847 -180.657024) (xy 3.688034 -180.675186)
			(xy 3.685457 -180.696166) (xy 3.691553 -180.716405) (xy 3.697986 -180.72481) (xy 3.715536 -180.745725)
			(xy 3.745098 -180.791628) (xy 3.767812 -180.841277) (xy 3.783212 -180.893659) (xy 3.790984 -180.947701)
			(xy 3.791458 -180.975) (xy 3.790972 -181.002251) (xy 3.783216 -181.056199) (xy 3.767861 -181.108494)
			(xy 3.745219 -181.158071) (xy 3.715753 -181.203921) (xy 3.680062 -181.245112) (xy 3.638871 -181.280803)
			(xy 3.593021 -181.310269) (xy 3.543444 -181.332911) (xy 3.491149 -181.348266) (xy 3.437201 -181.356022)
			(xy 3.382699 -181.356022) (xy 3.328751 -181.348266) (xy 3.276456 -181.332911) (xy 3.226879 -181.310269)
			(xy 3.181029 -181.280803) (xy 3.139838 -181.245112) (xy 3.104147 -181.203921) (xy 3.074681 -181.158071)
			(xy 3.052039 -181.108494) (xy 3.036684 -181.056199) (xy 3.028928 -181.002251) (xy 3.028928 -180.947749)
			(xy 3.036684 -180.893801) (xy 3.052039 -180.841506) (xy 3.074681 -180.791929) (xy 3.104147 -180.746079)
			(xy 3.139838 -180.704888) (xy 3.181029 -180.669197) (xy 3.226879 -180.639731) (xy 3.276456 -180.617089)
			(xy 3.328751 -180.601734) (xy 3.382699 -180.593978) (xy 3.40995 -180.593492) (xy 3.435468 -180.593902)
			(xy 3.486057 -180.600651) (xy 3.510788 -180.606954) (xy 3.524758 -180.611018) (xy 3.551936 -180.603144)
			(xy 3.632708 -180.51526) (xy 3.638042 -180.487574) (xy 3.632962 -180.474112) (xy 3.622016 -180.442262)
			(xy 3.610256 -180.375957) (xy 3.609594 -180.342286) (xy 3.61004 -180.315906) (xy 3.617307 -180.263648)
			(xy 3.624072 -180.238146) (xy 3.626104 -180.231542) (xy 3.626104 -178.6128) (xy 3.625616 -178.602792)
			(xy 3.617956 -178.5843) (xy 3.603804 -178.570146) (xy 3.585312 -178.562485) (xy 3.575304 -178.562)
			(xy 2.561082 -178.562) (xy 2.551013 -178.562427) (xy 2.532414 -178.570146) (xy 2.525014 -178.576986)
			(xy 2.427986 -178.674014) (xy 2.421132 -178.681409) (xy 2.41339 -178.700008) (xy 2.413 -178.710082)
			(xy 2.413 -181.088792) (xy 2.40919 -181.09438) (xy 2.405293 -181.100766) (xy 2.401022 -181.115097)
			(xy 2.400808 -181.122574) (xy 2.400808 -183.349138) (xy 2.401289 -183.359102) (xy 2.408871 -183.377533)
			(xy 2.41554 -183.384952) (xy 2.98323 -183.952896) (xy 3.003306 -183.973777) (xy 3.037349 -184.020637)
			(xy 3.063643 -184.072245) (xy 3.08154 -184.127332) (xy 3.0906 -184.18454) (xy 3.09118 -184.2135)
			(xy 3.09118 -185.051954) (xy 3.091542 -185.060457) (xy 3.097193 -185.0765) (xy 3.107787 -185.089808)
			(xy 3.114802 -185.094626) (xy 3.198114 -185.147712) (xy 3.224022 -185.14949) (xy 3.23596 -185.143902)
			(xy 3.261337 -185.132619) (xy 3.314537 -185.116683) (xy 3.369483 -185.108612) (xy 3.39725 -185.108088)
			(xy 3.424502 -185.108574) (xy 3.47845 -185.11633) (xy 3.530745 -185.131686) (xy 3.580323 -185.154327)
			(xy 3.626174 -185.183794) (xy 3.667364 -185.219486) (xy 3.703056 -185.260676) (xy 3.732523 -185.306527)
			(xy 3.755164 -185.356105) (xy 3.77052 -185.4084) (xy 3.778276 -185.462348) (xy 3.778276 -185.516852)
			(xy 3.77052 -185.5708) (xy 3.755164 -185.623095) (xy 3.732523 -185.672673) (xy 3.703056 -185.718524)
			(xy 3.667364 -185.759714) (xy 3.626174 -185.795406) (xy 3.580323 -185.824873) (xy 3.530745 -185.847514)
			(xy 3.47845 -185.86287) (xy 3.424502 -185.870626) (xy 3.39725 -185.871104) (xy 3.369481 -185.870604)
			(xy 3.314531 -185.862541) (xy 3.261336 -185.84658) (xy 3.23596 -185.83529) (xy 3.224022 -185.829702)
			(xy 3.198114 -185.83148) (xy 3.114802 -185.884566) (xy 3.107788 -185.889387) (xy 3.097193 -185.902693)
			(xy 3.09154 -185.918735) (xy 3.09118 -185.927238) (xy 3.09118 -189.373002) (xy 3.43103 -189.373002)
			(xy 3.435101 -189.31738) (xy 3.447227 -189.262943) (xy 3.46715 -189.210852) (xy 3.494446 -189.162217)
			(xy 3.528532 -189.118074) (xy 3.568681 -189.079365) (xy 3.614039 -189.046914) (xy 3.663639 -189.021413)
			(xy 3.716423 -189.003406) (xy 3.771266 -188.993276) (xy 3.827 -188.991239) (xy 3.882437 -188.997339)
			(xy 3.936394 -189.011445) (xy 3.987723 -189.033257) (xy 4.035329 -189.062311) (xy 4.078197 -189.097986)
			(xy 4.115414 -189.139523) (xy 4.146187 -189.186036) (xy 4.169859 -189.236533) (xy 4.185927 -189.28994)
			(xy 4.194047 -189.345116) (xy 4.194556 -189.373002) (xy 4.194047 -189.400888) (xy 4.185927 -189.456064)
			(xy 4.169859 -189.509471) (xy 4.146187 -189.559968) (xy 4.115414 -189.606481) (xy 4.078197 -189.648018)
			(xy 4.035329 -189.683693) (xy 3.987723 -189.712747) (xy 3.936394 -189.734559) (xy 3.882437 -189.748665)
			(xy 3.827 -189.754765) (xy 3.771266 -189.752728) (xy 3.716423 -189.742598) (xy 3.663639 -189.724591)
			(xy 3.614039 -189.69909) (xy 3.568681 -189.666639) (xy 3.528532 -189.62793) (xy 3.494446 -189.583787)
			(xy 3.46715 -189.535152) (xy 3.447227 -189.483061) (xy 3.435101 -189.428624) (xy 3.43103 -189.373002)
			(xy 3.09118 -189.373002) (xy 3.09118 -190.141352) (xy 3.091708 -190.151344) (xy 3.099407 -190.16979)
			(xy 3.106166 -190.177166) (xy 3.287014 -190.358014) (xy 3.294409 -190.364868) (xy 3.313008 -190.37261)
			(xy 3.323082 -190.373)
		)
		(stroke
			(width 0)
			(type solid)
		)
		(fill yes)
		(layer "In2.Cu")
		(net "P3V3_AUX")
	)
	(gr_poly
		(pts
			(xy 29.493718 -191.2112) (xy 29.503787 -191.210773) (xy 29.522386 -191.203054) (xy 29.529786 -191.196214)
			(xy 30.492446 -190.233554) (xy 30.498796 -190.222124) (xy 30.500574 -190.215266) (xy 30.508532 -190.18666)
			(xy 30.532078 -190.132154) (xy 30.563777 -190.081949) (xy 30.602866 -190.037257) (xy 30.648402 -189.999154)
			(xy 30.673548 -189.983364) (xy 30.678882 -189.980062) (xy 31.49346 -189.165484) (xy 31.500204 -189.158114)
			(xy 31.507797 -189.139652) (xy 31.508192 -189.12967) (xy 31.508192 -184.945274) (xy 31.508749 -184.9163)
			(xy 31.517854 -184.859071) (xy 31.535804 -184.803972) (xy 31.562156 -184.752362) (xy 31.596261 -184.705512)
			(xy 31.616396 -184.68467) (xy 32.19831 -184.102502) (xy 32.201612 -184.097168) (xy 32.216504 -184.07338)
			(xy 32.252167 -184.030048) (xy 32.293792 -183.992407) (xy 32.340481 -183.961267) (xy 32.391227 -183.937302)
			(xy 32.444936 -183.921028) (xy 32.50045 -183.912795) (xy 32.52851 -183.912256) (xy 32.551802 -183.912634)
			(xy 32.598034 -183.918362) (xy 32.620712 -183.923686) (xy 32.626808 -183.924956) (xy 32.769302 -183.924956)
			(xy 32.779268 -183.92448) (xy 32.797705 -183.916904) (xy 32.805116 -183.910224) (xy 35.65906 -181.05628)
			(xy 35.665803 -181.04891) (xy 35.673395 -181.030448) (xy 35.673792 -181.020466) (xy 35.673792 -177.045874)
			(xy 35.673313 -177.035909) (xy 35.665735 -177.017475) (xy 35.65906 -177.01006) (xy 35.447986 -176.798986)
			(xy 35.440591 -176.792132) (xy 35.421992 -176.78439) (xy 35.411918 -176.784) (xy 32.530542 -176.784)
			(xy 32.512 -176.784508) (xy 32.493458 -176.784) (xy 31.669482 -176.784) (xy 31.659413 -176.784427)
			(xy 31.640814 -176.792146) (xy 31.633414 -176.798986) (xy 31.34614 -177.08626) (xy 31.339445 -177.093666)
			(xy 31.331842 -177.112102) (xy 31.331408 -177.122074) (xy 31.331408 -179.451) (xy 31.748982 -179.451)
			(xy 31.753053 -179.395378) (xy 31.765179 -179.340941) (xy 31.785102 -179.28885) (xy 31.812398 -179.240215)
			(xy 31.846484 -179.196072) (xy 31.886633 -179.157363) (xy 31.931991 -179.124912) (xy 31.981591 -179.099411)
			(xy 32.034375 -179.081404) (xy 32.089218 -179.071274) (xy 32.144952 -179.069237) (xy 32.200389 -179.075337)
			(xy 32.254346 -179.089443) (xy 32.305675 -179.111255) (xy 32.353281 -179.140309) (xy 32.396149 -179.175984)
			(xy 32.433366 -179.217521) (xy 32.464139 -179.264034) (xy 32.487811 -179.314531) (xy 32.503879 -179.367938)
			(xy 32.511999 -179.423114) (xy 32.512508 -179.451) (xy 32.511999 -179.478886) (xy 32.503879 -179.534062)
			(xy 32.487811 -179.587469) (xy 32.464139 -179.637966) (xy 32.433366 -179.684479) (xy 32.396149 -179.726016)
			(xy 32.353281 -179.761691) (xy 32.305675 -179.790745) (xy 32.254346 -179.812557) (xy 32.200389 -179.826663)
			(xy 32.144952 -179.832763) (xy 32.089218 -179.830726) (xy 32.034375 -179.820596) (xy 31.981591 -179.802589)
			(xy 31.931991 -179.777088) (xy 31.886633 -179.744637) (xy 31.846484 -179.705928) (xy 31.812398 -179.661785)
			(xy 31.785102 -179.61315) (xy 31.765179 -179.561059) (xy 31.753053 -179.506622) (xy 31.748982 -179.451)
			(xy 31.331408 -179.451) (xy 31.331408 -181.263036) (xy 31.331873 -181.272977) (xy 31.339424 -181.291367)
			(xy 31.353412 -181.305494) (xy 31.362396 -181.309772) (xy 31.462472 -181.35219) (xy 31.492444 -181.346602)
			(xy 31.50362 -181.335934) (xy 31.525093 -181.315887) (xy 31.573053 -181.281969) (xy 31.625647 -181.255804)
			(xy 31.68163 -181.238012) (xy 31.739679 -181.229014) (xy 31.76905 -181.228492) (xy 31.796305 -181.228952)
			(xy 31.850262 -181.236703) (xy 31.902565 -181.252055) (xy 31.952152 -181.274694) (xy 31.998011 -181.304161)
			(xy 32.03921 -181.339855) (xy 32.074909 -181.381049) (xy 32.104382 -181.426904) (xy 32.127028 -181.476488)
			(xy 32.142386 -181.52879) (xy 32.150145 -181.582745) (xy 32.150145 -181.637255) (xy 32.142386 -181.69121)
			(xy 32.127028 -181.743512) (xy 32.104382 -181.793096) (xy 32.074909 -181.838951) (xy 32.03921 -181.880145)
			(xy 31.998011 -181.915839) (xy 31.952152 -181.945306) (xy 31.902565 -181.967945) (xy 31.850262 -181.983297)
			(xy 31.796305 -181.991048) (xy 31.76905 -181.991508) (xy 31.739681 -181.990964) (xy 31.681639 -181.981956)
			(xy 31.625662 -181.964161) (xy 31.573073 -181.937999) (xy 31.525114 -181.904087) (xy 31.50362 -181.884066)
			(xy 31.492444 -181.873398) (xy 31.462472 -181.86781) (xy 31.362396 -181.910228) (xy 31.353435 -181.914544)
			(xy 31.339456 -181.928664) (xy 31.331874 -181.94703) (xy 31.331408 -181.956964) (xy 31.331408 -182.08752)
			(xy 31.330851 -182.116494) (xy 31.321747 -182.173724) (xy 31.303798 -182.228823) (xy 31.277447 -182.280434)
			(xy 31.243342 -182.327285) (xy 31.223204 -182.348124) (xy 31.002986 -182.568596) (xy 30.99613 -182.57599)
			(xy 30.98838 -182.594589) (xy 30.988 -182.604664) (xy 30.988 -182.604918) (xy 30.987573 -182.614987)
			(xy 30.979854 -182.633586) (xy 30.973014 -182.640986) (xy 28.332684 -185.281316) (xy 28.326004 -185.288727)
			(xy 28.31843 -185.307163) (xy 28.317952 -185.31713) (xy 28.317952 -186.436) (xy 29.843982 -186.436)
			(xy 29.848053 -186.380378) (xy 29.860179 -186.325941) (xy 29.880102 -186.27385) (xy 29.907398 -186.225215)
			(xy 29.941484 -186.181072) (xy 29.981633 -186.142363) (xy 30.026991 -186.109912) (xy 30.076591 -186.084411)
			(xy 30.129375 -186.066404) (xy 30.184218 -186.056274) (xy 30.239952 -186.054237) (xy 30.295389 -186.060337)
			(xy 30.349346 -186.074443) (xy 30.400675 -186.096255) (xy 30.448281 -186.125309) (xy 30.491149 -186.160984)
			(xy 30.528366 -186.202521) (xy 30.559139 -186.249034) (xy 30.582811 -186.299531) (xy 30.598879 -186.352938)
			(xy 30.606999 -186.408114) (xy 30.607508 -186.436) (xy 30.606999 -186.463886) (xy 30.598879 -186.519062)
			(xy 30.582811 -186.572469) (xy 30.559139 -186.622966) (xy 30.528366 -186.669479) (xy 30.491149 -186.711016)
			(xy 30.448281 -186.746691) (xy 30.400675 -186.775745) (xy 30.349346 -186.797557) (xy 30.295389 -186.811663)
			(xy 30.239952 -186.817763) (xy 30.184218 -186.815726) (xy 30.129375 -186.805596) (xy 30.076591 -186.787589)
			(xy 30.026991 -186.762088) (xy 29.981633 -186.729637) (xy 29.941484 -186.690928) (xy 29.907398 -186.646785)
			(xy 29.880102 -186.59815) (xy 29.860179 -186.546059) (xy 29.848053 -186.491622) (xy 29.843982 -186.436)
			(xy 28.317952 -186.436) (xy 28.317952 -188.341) (xy 28.79166 -188.341) (xy 28.795731 -188.285378)
			(xy 28.807857 -188.230941) (xy 28.82778 -188.17885) (xy 28.855076 -188.130215) (xy 28.889162 -188.086072)
			(xy 28.929311 -188.047363) (xy 28.974669 -188.014912) (xy 29.024269 -187.989411) (xy 29.077053 -187.971404)
			(xy 29.131896 -187.961274) (xy 29.18763 -187.959237) (xy 29.243067 -187.965337) (xy 29.297024 -187.979443)
			(xy 29.348353 -188.001255) (xy 29.395959 -188.030309) (xy 29.438827 -188.065984) (xy 29.476044 -188.107521)
			(xy 29.506817 -188.154034) (xy 29.530489 -188.204531) (xy 29.546557 -188.257938) (xy 29.554677 -188.313114)
			(xy 29.555186 -188.341) (xy 29.554677 -188.368886) (xy 29.546557 -188.424062) (xy 29.530489 -188.477469)
			(xy 29.506817 -188.527966) (xy 29.476044 -188.574479) (xy 29.438827 -188.616016) (xy 29.395959 -188.651691)
			(xy 29.348353 -188.680745) (xy 29.297024 -188.702557) (xy 29.243067 -188.716663) (xy 29.18763 -188.722763)
			(xy 29.131896 -188.720726) (xy 29.077053 -188.710596) (xy 29.024269 -188.692589) (xy 28.974669 -188.667088)
			(xy 28.929311 -188.634637) (xy 28.889162 -188.595928) (xy 28.855076 -188.551785) (xy 28.82778 -188.50315)
			(xy 28.807857 -188.451059) (xy 28.795731 -188.396622) (xy 28.79166 -188.341) (xy 28.317952 -188.341)
			(xy 28.317952 -190.76162) (xy 28.318453 -190.771611) (xy 28.326097 -190.790076) (xy 28.34019 -190.804245)
			(xy 28.349194 -190.80861) (xy 28.363672 -190.814452) (xy 28.39339 -190.80861) (xy 28.448 -190.831216)
			(xy 28.448 -191.008) (xy 28.448488 -191.018008) (xy 28.456148 -191.036499) (xy 28.470301 -191.050652)
			(xy 28.488792 -191.058312) (xy 28.4988 -191.0588) (xy 28.782518 -191.0588) (xy 28.792587 -191.059227)
			(xy 28.811186 -191.066946) (xy 28.818586 -191.073786) (xy 28.941014 -191.196214) (xy 28.948409 -191.203068)
			(xy 28.967008 -191.21081) (xy 28.977082 -191.2112)
		)
		(stroke
			(width 0)
			(type solid)
		)
		(fill yes)
		(layer "In2.Cu")
		(net "P3V3_AUX")
	)
	(gr_poly
		(pts
			(arc
				(start 47.69993 -336.492088)
				(mid 50.169141 -335.469307)
				(end 51.191922 -333.000096)
			)
			(arc
				(start 51.191922 -3.999992)
				(mid 50.169141 -1.530781)
				(end 47.69993 -0.508)
			)
			(xy 36.950396 -0.508) (xy 35.74796 -1.710436)
			(arc
				(start 35.74796 -10.999978)
				(mid 35.246291 -12.209079)
				(end 34.036 -12.707874)
			)
			(arc
				(start 34.036 -13.215874)
				(mid 35.60534 -12.568202)
				(end 36.255706 -10.999978)
			)
			(xy 36.255706 -1.920748) (xy 37.160708 -1.015746)
			(arc
				(start 47.69993 -1.015746)
				(mid 49.810111 -1.889811)
				(end 50.684176 -3.999992)
			)
			(arc
				(start 50.684176 -333.000096)
				(mid 49.810111 -335.110277)
				(end 47.69993 -335.984342)
			)
			(arc
				(start 3.999992 -335.984342)
				(mid 1.889811 -335.110277)
				(end 1.015746 -333.000096)
			)
			(arc
				(start 1.015746 -3.999992)
				(mid 1.889811 -1.889811)
				(end 3.999992 -1.015746)
			)
			(xy 14.539214 -1.015746) (xy 15.444216 -1.920748)
			(arc
				(start 15.444216 -10.999978)
				(mid 16.09074 -12.564247)
				(end 17.653 -13.21562)
			)
			(arc
				(start 17.653 -12.707874)
				(mid 16.449761 -12.205225)
				(end 15.951962 -10.999978)
			)
			(xy 15.951962 -1.710436) (xy 14.749526 -0.508)
			(arc
				(start 3.999992 -0.508)
				(mid 1.530781 -1.530781)
				(end 0.508 -3.999992)
			)
			(arc
				(start 0.508 -333.000096)
				(mid 1.530781 -335.469307)
				(end 3.999992 -336.492088)
			)
		)
		(stroke
			(width 0)
			(type solid)
		)
		(fill yes)
		(layer "In2.Cu")
		(net "GND")
	)
	(gr_poly
		(pts
			(xy 12.117578 -175.566578) (xy 12.124945 -175.573396) (xy 12.143454 -175.581125) (xy 12.163511 -175.581172)
			(xy 12.17295 -175.577754) (xy 12.187428 -175.571658) (xy 12.204192 -175.546258) (xy 12.204192 -175.006)
			(xy 12.204747 -174.977025) (xy 12.213849 -174.919794) (xy 12.231795 -174.864693) (xy 12.258145 -174.813079)
			(xy 12.292249 -174.766226) (xy 12.312396 -174.745396) (xy 13.385038 -173.6725) (xy 13.391003 -173.666075)
			(xy 13.398537 -173.650261) (xy 13.400265 -173.632828) (xy 13.3985 -173.62424) (xy 13.37437 -173.526704)
			(xy 13.356082 -173.507654) (xy 13.343382 -173.50359) (xy 13.317777 -173.495183) (xy 13.269046 -173.472168)
			(xy 13.224039 -173.442523) (xy 13.183654 -173.406839) (xy 13.148694 -173.365824) (xy 13.119855 -173.320298)
			(xy 13.097711 -173.271165) (xy 13.082704 -173.219404) (xy 13.075132 -173.166046) (xy 13.07465 -173.1391)
			(xy 13.075136 -173.111848) (xy 13.082892 -173.057898) (xy 13.098247 -173.005601) (xy 13.120887 -172.956021)
			(xy 13.150353 -172.910167) (xy 13.186044 -172.868974) (xy 13.227234 -172.833278) (xy 13.273084 -172.803807)
			(xy 13.322661 -172.781161) (xy 13.374957 -172.765801) (xy 13.428906 -172.758039) (xy 13.456158 -172.757592)
			(xy 13.483102 -172.75806) (xy 13.536454 -172.765649) (xy 13.588208 -172.780669) (xy 13.637334 -172.80282)
			(xy 13.682855 -172.831663) (xy 13.723865 -172.866622) (xy 13.75955 -172.907003) (xy 13.789198 -172.952003)
			(xy 13.812221 -173.000727) (xy 13.820648 -173.026324) (xy 13.824712 -173.039024) (xy 13.843762 -173.057312)
			(xy 13.941298 -173.081442) (xy 13.949884 -173.083189) (xy 13.967304 -173.081428) (xy 13.983123 -173.073925)
			(xy 13.989558 -173.06798) (xy 15.487396 -171.570396) (xy 15.508246 -171.550269) (xy 15.555095 -171.516165)
			(xy 15.606703 -171.489811) (xy 15.661799 -171.471856) (xy 15.719026 -171.462742) (xy 15.748 -171.462192)
			(xy 17.173702 -171.462192) (xy 17.179798 -171.460922) (xy 17.202477 -171.455602) (xy 17.248708 -171.449875)
			(xy 17.272 -171.449492) (xy 17.302087 -171.450059) (xy 17.361515 -171.45951) (xy 17.418721 -171.478179)
			(xy 17.472285 -171.5056) (xy 17.520877 -171.541095) (xy 17.54251 -171.562014) (xy 17.553432 -171.572936)
			(xy 17.583658 -171.579032) (xy 17.68475 -171.537376) (xy 17.693851 -171.53315) (xy 17.708013 -171.518957)
			(xy 17.715636 -171.500413) (xy 17.715992 -171.490386) (xy 17.715992 -170.59021) (xy 17.715404 -170.579015)
			(xy 17.705908 -170.558736) (xy 17.697704 -170.551094) (xy 17.62887 -170.493944) (xy 17.607026 -170.488102)
			(xy 17.59585 -170.490388) (xy 17.578544 -170.493383) (xy 17.543563 -170.496561) (xy 17.526 -170.496738)
			(xy 17.498464 -170.496255) (xy 17.443964 -170.488339) (xy 17.391168 -170.472672) (xy 17.341172 -170.449579)
			(xy 17.295015 -170.419539) (xy 17.253654 -170.383177) (xy 17.21795 -170.341247) (xy 17.202912 -170.318176)
			(xy 17.199864 -170.31335) (xy 17.091914 -170.2054) (xy 17.084505 -170.198714) (xy 17.066069 -170.191126)
			(xy 17.0561 -170.190668) (xy 17.03832 -170.190668) (xy 17.029178 -170.191045) (xy 17.012055 -170.197453)
			(xy 16.99827 -170.209462) (xy 16.993616 -170.217338) (xy 16.944594 -170.309032) (xy 16.946118 -170.336972)
			(xy 16.953992 -170.348656) (xy 16.969233 -170.37234) (xy 16.993335 -170.423242) (xy 17.009699 -170.477132)
			(xy 17.017971 -170.53284) (xy 17.018508 -170.561) (xy 17.018022 -170.588251) (xy 17.010266 -170.642199)
			(xy 16.994911 -170.694494) (xy 16.972269 -170.744071) (xy 16.942803 -170.789921) (xy 16.907112 -170.831112)
			(xy 16.865921 -170.866803) (xy 16.820071 -170.896269) (xy 16.770494 -170.918911) (xy 16.718199 -170.934266)
			(xy 16.664251 -170.942022) (xy 16.609749 -170.942022) (xy 16.555801 -170.934266) (xy 16.503506 -170.918911)
			(xy 16.453929 -170.896269) (xy 16.408079 -170.866803) (xy 16.366888 -170.831112) (xy 16.331197 -170.789921)
			(xy 16.301731 -170.744071) (xy 16.279089 -170.694494) (xy 16.263734 -170.642199) (xy 16.255978 -170.588251)
			(xy 16.255492 -170.561) (xy 16.255996 -170.532839) (xy 16.264274 -170.477129) (xy 16.280651 -170.423241)
			(xy 16.304771 -170.372345) (xy 16.320008 -170.348656) (xy 16.327882 -170.336972) (xy 16.329406 -170.309032)
			(xy 16.280384 -170.217338) (xy 16.275704 -170.209483) (xy 16.261927 -170.197483) (xy 16.244815 -170.191079)
			(xy 16.23568 -170.190668) (xy 15.767558 -170.190668) (xy 15.738584 -170.19011) (xy 15.681355 -170.181004)
			(xy 15.626256 -170.163055) (xy 15.574645 -170.136704) (xy 15.527793 -170.102602) (xy 15.506954 -170.082464)
			(xy 13.931392 -168.507156) (xy 13.922965 -168.499528) (xy 13.901596 -168.491869) (xy 13.890244 -168.492424)
			(xy 13.800328 -168.501568) (xy 13.781024 -168.513252) (xy 13.774674 -168.522904) (xy 13.759478 -168.545157)
			(xy 13.72382 -168.585556) (xy 13.682827 -168.620531) (xy 13.637318 -168.649384) (xy 13.588199 -168.671542)
			(xy 13.53645 -168.686561) (xy 13.483101 -168.694143) (xy 13.456158 -168.694608) (xy 13.428909 -168.694119)
			(xy 13.374966 -168.686358) (xy 13.322676 -168.670999) (xy 13.273104 -168.648356) (xy 13.227259 -168.618888)
			(xy 13.186074 -168.583197) (xy 13.150387 -168.542008) (xy 13.120924 -168.496159) (xy 13.098286 -168.446585)
			(xy 13.082933 -168.394293) (xy 13.075178 -168.340349) (xy 13.07465 -168.3131) (xy 13.075115 -168.286157)
			(xy 13.0827 -168.232808) (xy 13.09772 -168.181058) (xy 13.119876 -168.131937) (xy 13.148725 -168.086424)
			(xy 13.183695 -168.045426) (xy 13.224087 -168.009759) (xy 13.246354 -167.994584) (xy 13.256006 -167.988234)
			(xy 13.26769 -167.96893) (xy 13.276834 -167.879014) (xy 13.277347 -167.867669) (xy 13.26969 -167.846318)
			(xy 13.262102 -167.837866) (xy 10.403078 -164.978842) (xy 10.395734 -164.97203) (xy 10.377271 -164.964299)
			(xy 10.367264 -164.963856) (xy 9.49198 -164.963856) (xy 9.463019 -164.963287) (xy 9.405812 -164.954223)
			(xy 9.350726 -164.936322) (xy 9.299119 -164.910024) (xy 9.252262 -164.875977) (xy 9.231376 -164.855906)
			(xy 4.260596 -159.885126) (xy 4.240474 -159.864275) (xy 4.206379 -159.817423) (xy 4.180036 -159.765814)
			(xy 4.162093 -159.710718) (xy 4.152991 -159.653494) (xy 4.152392 -159.624522) (xy 4.152392 -144.000474)
			(xy 4.151913 -143.990509) (xy 4.144335 -143.972075) (xy 4.13766 -143.96466) (xy 3.757422 -143.584422)
			(xy 3.750055 -143.577604) (xy 3.731546 -143.569875) (xy 3.711489 -143.569828) (xy 3.70205 -143.573246)
			(xy 3.687572 -143.579342) (xy 3.670808 -143.604742) (xy 3.670808 -159.83331) (xy 3.671284 -159.843277)
			(xy 3.678858 -159.861715) (xy 3.68554 -159.869124) (xy 7.085838 -163.269676) (xy 7.105914 -163.290556)
			(xy 7.139959 -163.337416) (xy 7.166255 -163.389025) (xy 7.184155 -163.444111) (xy 7.193219 -163.501319)
			(xy 7.193788 -163.53028) (xy 7.193788 -164.450522) (xy 7.194329 -164.460508) (xy 7.202047 -164.478935)
			(xy 7.208774 -164.486336) (xy 7.226046 -164.503862) (xy 7.234765 -164.511743) (xy 7.257001 -164.519271)
			(xy 7.268718 -164.51834) (xy 7.360412 -164.506148) (xy 7.380224 -164.49294) (xy 7.386066 -164.48278)
			(xy 7.400759 -164.458273) (xy 7.436335 -164.413559) (xy 7.478187 -164.374657) (xy 7.525378 -164.342439)
			(xy 7.576849 -164.317626) (xy 7.631448 -164.300775) (xy 7.68795 -164.292263) (xy 7.71652 -164.291772)
			(xy 7.743771 -164.292259) (xy 7.797717 -164.300018) (xy 7.850011 -164.315374) (xy 7.899587 -164.338017)
			(xy 7.945436 -164.367483) (xy 7.986626 -164.403174) (xy 8.022317 -164.444364) (xy 8.051783 -164.490213)
			(xy 8.074426 -164.539789) (xy 8.089782 -164.592083) (xy 8.097541 -164.646029) (xy 8.098028 -164.67328)
			(xy 8.097513 -164.701846) (xy 8.088981 -164.758337) (xy 8.072118 -164.812924) (xy 8.047302 -164.864385)
			(xy 8.015089 -164.911569) (xy 7.976199 -164.953421) (xy 7.931502 -164.989005) (xy 7.90702 -165.003734)
			(xy 7.89686 -165.009576) (xy 7.883652 -165.029388) (xy 7.87146 -165.121082) (xy 7.870516 -165.1328)
			(xy 7.878046 -165.155043) (xy 7.885938 -165.163754) (xy 9.600184 -166.878) (xy 11.108942 -166.878)
			(xy 11.113013 -166.822378) (xy 11.125139 -166.767941) (xy 11.145062 -166.71585) (xy 11.172358 -166.667215)
			(xy 11.206444 -166.623072) (xy 11.246593 -166.584363) (xy 11.291951 -166.551912) (xy 11.341551 -166.526411)
			(xy 11.394335 -166.508404) (xy 11.449178 -166.498274) (xy 11.504912 -166.496237) (xy 11.560349 -166.502337)
			(xy 11.614306 -166.516443) (xy 11.665635 -166.538255) (xy 11.713241 -166.567309) (xy 11.756109 -166.602984)
			(xy 11.793326 -166.644521) (xy 11.824099 -166.691034) (xy 11.847771 -166.741531) (xy 11.863839 -166.794938)
			(xy 11.871959 -166.850114) (xy 11.872468 -166.878) (xy 11.871959 -166.905886) (xy 11.863839 -166.961062)
			(xy 11.847771 -167.014469) (xy 11.824099 -167.064966) (xy 11.793326 -167.111479) (xy 11.756109 -167.153016)
			(xy 11.713241 -167.188691) (xy 11.665635 -167.217745) (xy 11.614306 -167.239557) (xy 11.560349 -167.253663)
			(xy 11.504912 -167.259763) (xy 11.449178 -167.257726) (xy 11.394335 -167.247596) (xy 11.341551 -167.229589)
			(xy 11.291951 -167.204088) (xy 11.246593 -167.171637) (xy 11.206444 -167.132928) (xy 11.172358 -167.088785)
			(xy 11.145062 -167.04015) (xy 11.125139 -166.988059) (xy 11.113013 -166.933622) (xy 11.108942 -166.878)
			(xy 9.600184 -166.878) (xy 9.633204 -166.91102) (xy 9.653329 -166.93187) (xy 9.687431 -166.97872)
			(xy 9.713782 -167.030329) (xy 9.731733 -167.085425) (xy 9.740843 -167.142651) (xy 9.741408 -167.171624)
			(xy 9.741408 -169.291) (xy 11.543282 -169.291) (xy 11.547353 -169.235378) (xy 11.559479 -169.180941)
			(xy 11.579402 -169.12885) (xy 11.606698 -169.080215) (xy 11.640784 -169.036072) (xy 11.680933 -168.997363)
			(xy 11.726291 -168.964912) (xy 11.775891 -168.939411) (xy 11.828675 -168.921404) (xy 11.883518 -168.911274)
			(xy 11.939252 -168.909237) (xy 11.994689 -168.915337) (xy 12.048646 -168.929443) (xy 12.099975 -168.951255)
			(xy 12.147581 -168.980309) (xy 12.190449 -169.015984) (xy 12.227666 -169.057521) (xy 12.258439 -169.104034)
			(xy 12.282111 -169.154531) (xy 12.298179 -169.207938) (xy 12.306299 -169.263114) (xy 12.306808 -169.291)
			(xy 12.306299 -169.318886) (xy 12.298179 -169.374062) (xy 12.282111 -169.427469) (xy 12.258439 -169.477966)
			(xy 12.227666 -169.524479) (xy 12.190449 -169.566016) (xy 12.147581 -169.601691) (xy 12.099975 -169.630745)
			(xy 12.048646 -169.652557) (xy 11.994689 -169.666663) (xy 11.939252 -169.672763) (xy 11.883518 -169.670726)
			(xy 11.828675 -169.660596) (xy 11.775891 -169.642589) (xy 11.726291 -169.617088) (xy 11.680933 -169.584637)
			(xy 11.640784 -169.545928) (xy 11.606698 -169.501785) (xy 11.579402 -169.45315) (xy 11.559479 -169.401059)
			(xy 11.547353 -169.346622) (xy 11.543282 -169.291) (xy 9.741408 -169.291) (xy 9.741408 -170.053)
			(xy 11.108942 -170.053) (xy 11.113013 -169.997378) (xy 11.125139 -169.942941) (xy 11.145062 -169.89085)
			(xy 11.172358 -169.842215) (xy 11.206444 -169.798072) (xy 11.246593 -169.759363) (xy 11.291951 -169.726912)
			(xy 11.341551 -169.701411) (xy 11.394335 -169.683404) (xy 11.449178 -169.673274) (xy 11.504912 -169.671237)
			(xy 11.560349 -169.677337) (xy 11.614306 -169.691443) (xy 11.665635 -169.713255) (xy 11.713241 -169.742309)
			(xy 11.756109 -169.777984) (xy 11.793326 -169.819521) (xy 11.824099 -169.866034) (xy 11.847771 -169.916531)
			(xy 11.863839 -169.969938) (xy 11.871959 -170.025114) (xy 11.872468 -170.053) (xy 11.871959 -170.080886)
			(xy 11.863839 -170.136062) (xy 11.847771 -170.189469) (xy 11.824099 -170.239966) (xy 11.793326 -170.286479)
			(xy 11.756109 -170.328016) (xy 11.713241 -170.363691) (xy 11.665635 -170.392745) (xy 11.614306 -170.414557)
			(xy 11.560349 -170.428663) (xy 11.504912 -170.434763) (xy 11.449178 -170.432726) (xy 11.394335 -170.422596)
			(xy 11.341551 -170.404589) (xy 11.291951 -170.379088) (xy 11.246593 -170.346637) (xy 11.206444 -170.307928)
			(xy 11.172358 -170.263785) (xy 11.145062 -170.21515) (xy 11.125139 -170.163059) (xy 11.113013 -170.108622)
			(xy 11.108942 -170.053) (xy 9.741408 -170.053) (xy 9.741408 -170.815) (xy 11.543282 -170.815) (xy 11.547353 -170.759378)
			(xy 11.559479 -170.704941) (xy 11.579402 -170.65285) (xy 11.606698 -170.604215) (xy 11.640784 -170.560072)
			(xy 11.680933 -170.521363) (xy 11.726291 -170.488912) (xy 11.775891 -170.463411) (xy 11.828675 -170.445404)
			(xy 11.883518 -170.435274) (xy 11.939252 -170.433237) (xy 11.994689 -170.439337) (xy 12.048646 -170.453443)
			(xy 12.099975 -170.475255) (xy 12.147581 -170.504309) (xy 12.190449 -170.539984) (xy 12.227666 -170.581521)
			(xy 12.258439 -170.628034) (xy 12.282111 -170.678531) (xy 12.298179 -170.731938) (xy 12.306299 -170.787114)
			(xy 12.306808 -170.815) (xy 12.306299 -170.842886) (xy 12.298179 -170.898062) (xy 12.282111 -170.951469)
			(xy 12.258439 -171.001966) (xy 12.227666 -171.048479) (xy 12.190449 -171.090016) (xy 12.147581 -171.125691)
			(xy 12.099975 -171.154745) (xy 12.048646 -171.176557) (xy 11.994689 -171.190663) (xy 11.939252 -171.196763)
			(xy 11.883518 -171.194726) (xy 11.828675 -171.184596) (xy 11.775891 -171.166589) (xy 11.726291 -171.141088)
			(xy 11.680933 -171.108637) (xy 11.640784 -171.069928) (xy 11.606698 -171.025785) (xy 11.579402 -170.97715)
			(xy 11.559479 -170.925059) (xy 11.547353 -170.870622) (xy 11.543282 -170.815) (xy 9.741408 -170.815)
			(xy 9.741408 -173.228) (xy 11.108942 -173.228) (xy 11.113013 -173.172378) (xy 11.125139 -173.117941)
			(xy 11.145062 -173.06585) (xy 11.172358 -173.017215) (xy 11.206444 -172.973072) (xy 11.246593 -172.934363)
			(xy 11.291951 -172.901912) (xy 11.341551 -172.876411) (xy 11.394335 -172.858404) (xy 11.449178 -172.848274)
			(xy 11.504912 -172.846237) (xy 11.560349 -172.852337) (xy 11.614306 -172.866443) (xy 11.665635 -172.888255)
			(xy 11.713241 -172.917309) (xy 11.756109 -172.952984) (xy 11.793326 -172.994521) (xy 11.824099 -173.041034)
			(xy 11.847771 -173.091531) (xy 11.863839 -173.144938) (xy 11.871959 -173.200114) (xy 11.872468 -173.228)
			(xy 11.871959 -173.255886) (xy 11.863839 -173.311062) (xy 11.847771 -173.364469) (xy 11.824099 -173.414966)
			(xy 11.793326 -173.461479) (xy 11.756109 -173.503016) (xy 11.713241 -173.538691) (xy 11.665635 -173.567745)
			(xy 11.614306 -173.589557) (xy 11.560349 -173.603663) (xy 11.504912 -173.609763) (xy 11.449178 -173.607726)
			(xy 11.394335 -173.597596) (xy 11.341551 -173.579589) (xy 11.291951 -173.554088) (xy 11.246593 -173.521637)
			(xy 11.206444 -173.482928) (xy 11.172358 -173.438785) (xy 11.145062 -173.39015) (xy 11.125139 -173.338059)
			(xy 11.113013 -173.283622) (xy 11.108942 -173.228) (xy 9.741408 -173.228) (xy 9.741408 -174.032164)
			(xy 9.741898 -174.042163) (xy 9.749527 -174.060651) (xy 9.763614 -174.074848) (xy 9.77265 -174.079154)
			(xy 9.787128 -174.084996) (xy 9.816846 -174.079154) (xy 10.018014 -173.877986) (xy 10.025409 -173.871132)
			(xy 10.044008 -173.86339) (xy 10.054082 -173.863) (xy 10.392918 -173.863) (xy 10.402987 -173.863427)
			(xy 10.421586 -173.871146) (xy 10.428986 -173.877986)
		)
		(stroke
			(width 0)
			(type solid)
		)
		(fill yes)
		(layer "In2.Cu")
		(net "P3V3_AUX")
	)
	(gr_poly
		(pts
			(xy 33.740344 -217.273378) (xy 36.942014 -214.071708) (xy 36.948871 -214.064314) (xy 36.956622 -214.045715)
			(xy 36.957 -214.03564) (xy 36.957 -213.284308) (xy 36.933378 -213.256114) (xy 36.91509 -213.252812)
			(xy 36.888992 -213.247689) (xy 36.838441 -213.231163) (xy 36.790678 -213.20777) (xy 36.746632 -213.177963)
			(xy 36.707157 -213.142322) (xy 36.673022 -213.101538) (xy 36.644888 -213.056405) (xy 36.623302 -213.007799)
			(xy 36.608684 -212.956663) (xy 36.601317 -212.903992) (xy 36.600892 -212.8774) (xy 36.601377 -212.849516)
			(xy 36.609497 -212.794344) (xy 36.625566 -212.740942) (xy 36.649239 -212.690449) (xy 36.680013 -212.643942)
			(xy 36.717231 -212.602411) (xy 36.760101 -212.566743) (xy 36.807707 -212.537698) (xy 36.859035 -212.515895)
			(xy 36.88588 -212.508338) (xy 36.892484 -212.50656) (xy 36.903914 -212.499956) (xy 39.018464 -210.385406)
			(xy 39.025153 -210.377998) (xy 39.032743 -210.359562) (xy 39.033196 -210.349592) (xy 39.033196 -195.928996)
			(xy 39.033752 -195.900021) (xy 39.042853 -195.84279) (xy 39.060801 -195.78769) (xy 39.087151 -195.736077)
			(xy 39.121255 -195.689225) (xy 39.1414 -195.668392) (xy 42.20845 -192.601088) (xy 42.215611 -192.593065)
			(xy 42.223219 -192.57298) (xy 42.223182 -192.562226) (xy 42.218356 -192.475612) (xy 42.20845 -192.456562)
			(xy 42.199814 -192.449704) (xy 42.177711 -192.431521) (xy 42.138688 -192.389654) (xy 42.106364 -192.342422)
			(xy 42.081468 -192.290887) (xy 42.064557 -192.236209) (xy 42.056013 -192.179617) (xy 42.055542 -192.151)
			(xy 42.056005 -192.123748) (xy 42.063763 -192.0698) (xy 42.079119 -192.017505) (xy 42.101762 -191.967928)
			(xy 42.131231 -191.922079) (xy 42.166926 -191.88089) (xy 42.208119 -191.845201) (xy 42.253972 -191.815738)
			(xy 42.303552 -191.793102) (xy 42.355849 -191.777752) (xy 42.409798 -191.770002) (xy 42.43705 -191.769492)
			(xy 42.465663 -191.770008) (xy 42.522245 -191.778565) (xy 42.576914 -191.795479) (xy 42.628442 -191.82037)
			(xy 42.675674 -191.85268) (xy 42.717548 -191.891684) (xy 42.735754 -191.913764) (xy 42.742612 -191.9224)
			(xy 42.761662 -191.932306) (xy 42.848276 -191.937132) (xy 42.859052 -191.937303) (xy 42.879189 -191.929677)
			(xy 42.887138 -191.9224) (xy 43.470068 -191.33947) (xy 43.477446 -191.33135) (xy 43.4851 -191.310812)
			(xy 43.4848 -191.299846) (xy 43.478704 -191.212216) (xy 43.46829 -191.193166) (xy 43.459146 -191.186308)
			(xy 43.435864 -191.16817) (xy 43.394656 -191.125924) (xy 43.360449 -191.077834) (xy 43.334061 -191.025046)
			(xy 43.316121 -190.968824) (xy 43.307058 -190.910508) (xy 43.306492 -190.881) (xy 43.306978 -190.853749)
			(xy 43.314734 -190.799801) (xy 43.330089 -190.747506) (xy 43.352731 -190.697929) (xy 43.382197 -190.652079)
			(xy 43.417888 -190.610888) (xy 43.459079 -190.575197) (xy 43.504929 -190.545731) (xy 43.554506 -190.523089)
			(xy 43.606801 -190.507734) (xy 43.660749 -190.499978) (xy 43.688 -190.499492) (xy 43.717509 -190.500035)
			(xy 43.775825 -190.509109) (xy 43.832048 -190.527054) (xy 43.884838 -190.553444) (xy 43.932933 -190.587648)
			(xy 43.975188 -190.62885) (xy 43.993308 -190.652146) (xy 44.000166 -190.66129) (xy 44.019216 -190.671704)
			(xy 44.106846 -190.6778) (xy 44.117815 -190.678098) (xy 44.138361 -190.670461) (xy 44.14647 -190.663068)
			(xy 44.19346 -190.616078) (xy 44.200203 -190.608708) (xy 44.207794 -190.590246) (xy 44.208192 -190.580264)
			(xy 44.208192 -179.370736) (xy 44.207706 -179.360774) (xy 44.200118 -179.34235) (xy 44.19346 -179.334922)
			(xy 43.147996 -178.289204) (xy 43.127869 -178.268354) (xy 43.093765 -178.221505) (xy 43.067411 -178.169897)
			(xy 43.049456 -178.114801) (xy 43.040342 -178.057574) (xy 43.039792 -178.0286) (xy 43.039792 -173.608238)
			(xy 43.039345 -173.598061) (xy 43.031438 -173.579305) (xy 43.016854 -173.565106) (xy 43.007534 -173.560994)
			(xy 42.90441 -173.521116) (xy 42.87393 -173.528228) (xy 42.863262 -173.539912) (xy 42.845107 -173.559193)
			(xy 42.804389 -173.593059) (xy 42.759378 -173.620964) (xy 42.710937 -173.642371) (xy 42.660001 -173.65687)
			(xy 42.607548 -173.66418) (xy 42.581068 -173.664626) (xy 42.553817 -173.664138) (xy 42.49987 -173.656377)
			(xy 42.447577 -173.641019) (xy 42.398001 -173.618375) (xy 42.352153 -173.588906) (xy 42.310964 -173.553213)
			(xy 42.275275 -173.512022) (xy 42.24581 -173.466171) (xy 42.22317 -173.416593) (xy 42.207816 -173.364299)
			(xy 42.20006 -173.310351) (xy 42.20006 -173.255849) (xy 42.207816 -173.201901) (xy 42.22317 -173.149607)
			(xy 42.24581 -173.100029) (xy 42.275275 -173.054178) (xy 42.310964 -173.012987) (xy 42.352153 -172.977294)
			(xy 42.398001 -172.947825) (xy 42.447577 -172.925181) (xy 42.49987 -172.909823) (xy 42.553817 -172.902062)
			(xy 42.581068 -172.90161) (xy 42.607545 -172.902067) (xy 42.65999 -172.909397) (xy 42.710919 -172.923906)
			(xy 42.759353 -172.945315) (xy 42.804362 -172.973215) (xy 42.845082 -173.007068) (xy 42.863262 -173.026324)
			(xy 42.87393 -173.038008) (xy 42.90441 -173.04512) (xy 43.007534 -173.005242) (xy 43.016833 -173.001102)
			(xy 43.031393 -172.9869) (xy 43.039311 -172.968166) (xy 43.039792 -172.957998) (xy 43.039792 -171.595796)
			(xy 43.039403 -171.585677) (xy 43.031652 -171.566986) (xy 43.01725 -171.552773) (xy 43.008042 -171.548552)
			(xy 42.906188 -171.507404) (xy 42.876216 -171.514008) (xy 42.865294 -171.525184) (xy 42.847246 -171.543316)
			(xy 42.807141 -171.57508) (xy 42.763155 -171.601206) (xy 42.716076 -171.621227) (xy 42.666745 -171.634785)
			(xy 42.616046 -171.641636) (xy 42.590466 -171.642024) (xy 42.563215 -171.641536) (xy 42.509269 -171.633775)
			(xy 42.456976 -171.618416) (xy 42.407401 -171.595772) (xy 42.361553 -171.566304) (xy 42.320365 -171.530611)
			(xy 42.284676 -171.48942) (xy 42.255211 -171.443569) (xy 42.232572 -171.393992) (xy 42.217218 -171.341698)
			(xy 42.209462 -171.287751) (xy 42.209462 -171.233249) (xy 42.217218 -171.179302) (xy 42.232572 -171.127008)
			(xy 42.255211 -171.077431) (xy 42.284676 -171.03158) (xy 42.320365 -170.990389) (xy 42.361553 -170.954696)
			(xy 42.407401 -170.925228) (xy 42.456976 -170.902584) (xy 42.509269 -170.887225) (xy 42.563215 -170.879464)
			(xy 42.590466 -170.879008) (xy 42.618465 -170.879498) (xy 42.673861 -170.887679) (xy 42.727467 -170.90387)
			(xy 42.77813 -170.927724) (xy 42.824761 -170.958728) (xy 42.866359 -170.996215) (xy 42.90203 -171.039381)
			(xy 42.931008 -171.087298) (xy 42.942256 -171.112942) (xy 42.948352 -171.127166) (xy 42.973752 -171.144184)
			(xy 42.988992 -171.144184) (xy 42.999013 -171.143766) (xy 43.01753 -171.136097) (xy 43.031701 -171.121923)
			(xy 43.039367 -171.103405) (xy 43.039792 -171.093384) (xy 43.039792 -170.96105) (xy 43.040351 -170.932077)
			(xy 43.049459 -170.874849) (xy 43.067412 -170.819753) (xy 43.093766 -170.768145) (xy 43.127872 -170.721298)
			(xy 43.147996 -170.700446) (xy 44.24045 -169.607738) (xy 44.243752 -169.602404) (xy 44.258641 -169.578611)
			(xy 44.2943 -169.53527) (xy 44.335923 -169.497618) (xy 44.382612 -169.466469) (xy 44.433359 -169.442493)
			(xy 44.48707 -169.426209) (xy 44.542587 -169.417967) (xy 44.57065 -169.417492) (xy 44.597905 -169.417952)
			(xy 44.651862 -169.425703) (xy 44.704165 -169.441055) (xy 44.753752 -169.463694) (xy 44.799611 -169.493161)
			(xy 44.84081 -169.528855) (xy 44.876509 -169.570049) (xy 44.905982 -169.615904) (xy 44.928628 -169.665488)
			(xy 44.943986 -169.71779) (xy 44.951745 -169.771745) (xy 44.952158 -169.799) (xy 44.95166 -169.827062)
			(xy 44.943434 -169.882581) (xy 44.927159 -169.936295) (xy 44.903188 -169.987043) (xy 44.872037 -170.03373)
			(xy 44.83438 -170.075347) (xy 44.79103 -170.110995) (xy 44.767246 -170.125898) (xy 44.761912 -170.1292)
			(xy 44.544234 -170.346878) (xy 44.537548 -170.35429) (xy 44.529948 -170.372724) (xy 44.529946 -170.392664)
			(xy 44.537542 -170.411101) (xy 44.544234 -170.418506) (xy 44.551346 -170.425872) (xy 44.569634 -170.433492)
			(xy 44.579794 -170.433492) (xy 44.595542 -170.434) (xy 45.304202 -170.434) (xy 45.314272 -170.433576)
			(xy 45.332876 -170.425861) (xy 45.34027 -170.419014) (xy 45.46346 -170.295824) (xy 45.470152 -170.288418)
			(xy 45.477749 -170.269981) (xy 45.478192 -170.26001) (xy 45.478192 -165.908736) (xy 45.477706 -165.898774)
			(xy 45.470118 -165.88035) (xy 45.46346 -165.872922) (xy 44.820078 -165.22954) (xy 44.812708 -165.222797)
			(xy 44.794246 -165.215206) (xy 44.784264 -165.214808) (xy 44.115736 -165.214808) (xy 44.105774 -165.215294)
			(xy 44.08735 -165.222882) (xy 44.079922 -165.22954) (xy 42.469562 -166.8399) (xy 43.30014 -166.8399)
			(xy 43.304211 -166.784278) (xy 43.316337 -166.729841) (xy 43.33626 -166.67775) (xy 43.363556 -166.629115)
			(xy 43.397642 -166.584972) (xy 43.437791 -166.546263) (xy 43.483149 -166.513812) (xy 43.532749 -166.488311)
			(xy 43.585533 -166.470304) (xy 43.640376 -166.460174) (xy 43.69611 -166.458137) (xy 43.751547 -166.464237)
			(xy 43.805504 -166.478343) (xy 43.856833 -166.500155) (xy 43.904439 -166.529209) (xy 43.947307 -166.564884)
			(xy 43.984524 -166.606421) (xy 44.015297 -166.652934) (xy 44.038969 -166.703431) (xy 44.055037 -166.756838)
			(xy 44.063157 -166.812014) (xy 44.063666 -166.8399) (xy 44.063157 -166.867786) (xy 44.055037 -166.922962)
			(xy 44.038969 -166.976369) (xy 44.015297 -167.026866) (xy 43.984524 -167.073379) (xy 43.947307 -167.114916)
			(xy 43.904439 -167.150591) (xy 43.856833 -167.179645) (xy 43.805504 -167.201457) (xy 43.751547 -167.215563)
			(xy 43.69611 -167.221663) (xy 43.640376 -167.219626) (xy 43.585533 -167.209496) (xy 43.532749 -167.191489)
			(xy 43.483149 -167.165988) (xy 43.437791 -167.133537) (xy 43.397642 -167.094828) (xy 43.363556 -167.050685)
			(xy 43.33626 -167.00205) (xy 43.316337 -166.949959) (xy 43.304211 -166.895522) (xy 43.30014 -166.8399)
			(xy 42.469562 -166.8399) (xy 42.046652 -167.26281) (xy 42.039975 -167.270222) (xy 42.032404 -167.288658)
			(xy 42.03192 -167.298624) (xy 42.03192 -168.076626) (xy 42.032512 -168.088952) (xy 42.043964 -168.110782)
			(xy 42.053764 -168.118282) (xy 42.132758 -168.173146) (xy 42.157142 -168.176194) (xy 42.16908 -168.171876)
			(xy 42.201385 -168.16056) (xy 42.268718 -168.148288) (xy 42.302938 -168.147492) (xy 42.330187 -168.14798)
			(xy 42.384131 -168.155741) (xy 42.436421 -168.1711) (xy 42.485994 -168.193743) (xy 42.531839 -168.22321)
			(xy 42.573025 -168.258902) (xy 42.608712 -168.300091) (xy 42.638175 -168.34594) (xy 42.660814 -168.395514)
			(xy 42.676167 -168.447806) (xy 42.683922 -168.50175) (xy 42.683922 -168.55625) (xy 42.676167 -168.610194)
			(xy 42.660814 -168.662486) (xy 42.638175 -168.71206) (xy 42.608712 -168.757909) (xy 42.573025 -168.799098)
			(xy 42.531839 -168.83479) (xy 42.485994 -168.864257) (xy 42.436421 -168.8869) (xy 42.384131 -168.902259)
			(xy 42.330187 -168.91002) (xy 42.302938 -168.910508) (xy 42.268712 -168.909769) (xy 42.201368 -168.897502)
			(xy 42.16908 -168.886124) (xy 42.157142 -168.881806) (xy 42.132758 -168.884854) (xy 42.053764 -168.939718)
			(xy 42.044099 -168.947333) (xy 42.03269 -168.969093) (xy 42.03192 -168.981374) (xy 42.03192 -174.585122)
			(xy 42.032381 -174.594998) (xy 42.039828 -174.613294) (xy 42.046398 -174.620682) (xy 42.066039 -174.641482)
			(xy 42.099301 -174.688024) (xy 42.124971 -174.739147) (xy 42.142432 -174.793623) (xy 42.151265 -174.850143)
			(xy 42.151808 -174.878746) (xy 42.151808 -175.44669) (xy 42.152389 -175.459168) (xy 42.163986 -175.48126)
			(xy 42.173906 -175.488854) (xy 42.254424 -175.542956) (xy 42.279316 -175.54575) (xy 42.291 -175.540924)
			(xy 42.313696 -175.532235) (xy 42.360734 -175.520019) (xy 42.408941 -175.513863) (xy 42.43324 -175.513492)
			(xy 42.460489 -175.513981) (xy 42.514433 -175.521742) (xy 42.566723 -175.5371) (xy 42.616295 -175.559744)
			(xy 42.66214 -175.589211) (xy 42.703326 -175.624903) (xy 42.739013 -175.666092) (xy 42.768476 -175.71194)
			(xy 42.791114 -175.761515) (xy 42.806467 -175.813806) (xy 42.814222 -175.867751) (xy 42.814222 -175.922249)
			(xy 42.806467 -175.976194) (xy 42.791114 -176.028485) (xy 42.768476 -176.07806) (xy 42.739013 -176.123908)
			(xy 42.703326 -176.165097) (xy 42.66214 -176.200789) (xy 42.616295 -176.230256) (xy 42.566723 -176.2529)
			(xy 42.514433 -176.268258) (xy 42.460489 -176.276019) (xy 42.43324 -176.276508) (xy 42.408939 -176.276146)
			(xy 42.360728 -176.270006) (xy 42.313691 -176.257781) (xy 42.291 -176.249076) (xy 42.279316 -176.24425)
			(xy 42.254424 -176.247044) (xy 42.173906 -176.301146) (xy 42.163959 -176.308716) (xy 42.152354 -176.330823)
			(xy 42.151808 -176.34331) (xy 42.151808 -180.026818) (xy 43.163742 -180.026818) (xy 43.167813 -179.971196)
			(xy 43.179939 -179.916759) (xy 43.199862 -179.864668) (xy 43.227158 -179.816033) (xy 43.261244 -179.77189)
			(xy 43.301393 -179.733181) (xy 43.346751 -179.70073) (xy 43.396351 -179.675229) (xy 43.449135 -179.657222)
			(xy 43.503978 -179.647092) (xy 43.559712 -179.645055) (xy 43.615149 -179.651155) (xy 43.669106 -179.665261)
			(xy 43.720435 -179.687073) (xy 43.768041 -179.716127) (xy 43.810909 -179.751802) (xy 43.848126 -179.793339)
			(xy 43.878899 -179.839852) (xy 43.902571 -179.890349) (xy 43.918639 -179.943756) (xy 43.926759 -179.998932)
			(xy 43.927268 -180.026818) (xy 43.926759 -180.054704) (xy 43.918639 -180.10988) (xy 43.902571 -180.163287)
			(xy 43.878899 -180.213784) (xy 43.848126 -180.260297) (xy 43.810909 -180.301834) (xy 43.768041 -180.337509)
			(xy 43.720435 -180.366563) (xy 43.669106 -180.388375) (xy 43.615149 -180.402481) (xy 43.559712 -180.408581)
			(xy 43.503978 -180.406544) (xy 43.449135 -180.396414) (xy 43.396351 -180.378407) (xy 43.346751 -180.352906)
			(xy 43.301393 -180.320455) (xy 43.261244 -180.281746) (xy 43.227158 -180.237603) (xy 43.199862 -180.188968)
			(xy 43.179939 -180.136877) (xy 43.167813 -180.08244) (xy 43.163742 -180.026818) (xy 42.151808 -180.026818)
			(xy 42.151808 -181.991) (xy 43.199302 -181.991) (xy 43.203373 -181.935378) (xy 43.215499 -181.880941)
			(xy 43.235422 -181.82885) (xy 43.262718 -181.780215) (xy 43.296804 -181.736072) (xy 43.336953 -181.697363)
			(xy 43.382311 -181.664912) (xy 43.431911 -181.639411) (xy 43.484695 -181.621404) (xy 43.539538 -181.611274)
			(xy 43.595272 -181.609237) (xy 43.650709 -181.615337) (xy 43.704666 -181.629443) (xy 43.755995 -181.651255)
			(xy 43.803601 -181.680309) (xy 43.846469 -181.715984) (xy 43.883686 -181.757521) (xy 43.914459 -181.804034)
			(xy 43.938131 -181.854531) (xy 43.954199 -181.907938) (xy 43.962319 -181.963114) (xy 43.962828 -181.991)
			(xy 43.962319 -182.018886) (xy 43.954199 -182.074062) (xy 43.938131 -182.127469) (xy 43.914459 -182.177966)
			(xy 43.883686 -182.224479) (xy 43.846469 -182.266016) (xy 43.803601 -182.301691) (xy 43.755995 -182.330745)
			(xy 43.704666 -182.352557) (xy 43.650709 -182.366663) (xy 43.595272 -182.372763) (xy 43.539538 -182.370726)
			(xy 43.484695 -182.360596) (xy 43.431911 -182.342589) (xy 43.382311 -182.317088) (xy 43.336953 -182.284637)
			(xy 43.296804 -182.245928) (xy 43.262718 -182.201785) (xy 43.235422 -182.15315) (xy 43.215499 -182.101059)
			(xy 43.203373 -182.046622) (xy 43.199302 -181.991) (xy 42.151808 -181.991) (xy 42.151808 -186.863482)
			(xy 43.200826 -186.863482) (xy 43.204897 -186.80786) (xy 43.217023 -186.753423) (xy 43.236946 -186.701332)
			(xy 43.264242 -186.652697) (xy 43.298328 -186.608554) (xy 43.338477 -186.569845) (xy 43.383835 -186.537394)
			(xy 43.433435 -186.511893) (xy 43.486219 -186.493886) (xy 43.541062 -186.483756) (xy 43.596796 -186.481719)
			(xy 43.652233 -186.487819) (xy 43.70619 -186.501925) (xy 43.757519 -186.523737) (xy 43.805125 -186.552791)
			(xy 43.847993 -186.588466) (xy 43.88521 -186.630003) (xy 43.915983 -186.676516) (xy 43.939655 -186.727013)
			(xy 43.955723 -186.78042) (xy 43.963843 -186.835596) (xy 43.964352 -186.863482) (xy 43.963843 -186.891368)
			(xy 43.955723 -186.946544) (xy 43.939655 -186.999951) (xy 43.915983 -187.050448) (xy 43.88521 -187.096961)
			(xy 43.847993 -187.138498) (xy 43.805125 -187.174173) (xy 43.757519 -187.203227) (xy 43.70619 -187.225039)
			(xy 43.652233 -187.239145) (xy 43.596796 -187.245245) (xy 43.541062 -187.243208) (xy 43.486219 -187.233078)
			(xy 43.433435 -187.215071) (xy 43.383835 -187.18957) (xy 43.338477 -187.157119) (xy 43.298328 -187.11841)
			(xy 43.264242 -187.074267) (xy 43.236946 -187.025632) (xy 43.217023 -186.973541) (xy 43.204897 -186.919104)
			(xy 43.200826 -186.863482) (xy 42.151808 -186.863482) (xy 42.151808 -187.91174) (xy 42.15125 -187.940714)
			(xy 42.142143 -187.997942) (xy 42.124192 -188.053039) (xy 42.097838 -188.104648) (xy 42.063732 -188.151496)
			(xy 42.043604 -188.172344) (xy 41.366998 -188.849) (xy 43.178982 -188.849) (xy 43.183053 -188.793378)
			(xy 43.195179 -188.738941) (xy 43.215102 -188.68685) (xy 43.242398 -188.638215) (xy 43.276484 -188.594072)
			(xy 43.316633 -188.555363) (xy 43.361991 -188.522912) (xy 43.411591 -188.497411) (xy 43.464375 -188.479404)
			(xy 43.519218 -188.469274) (xy 43.574952 -188.467237) (xy 43.630389 -188.473337) (xy 43.684346 -188.487443)
			(xy 43.735675 -188.509255) (xy 43.783281 -188.538309) (xy 43.826149 -188.573984) (xy 43.863366 -188.615521)
			(xy 43.894139 -188.662034) (xy 43.917811 -188.712531) (xy 43.933879 -188.765938) (xy 43.941999 -188.821114)
			(xy 43.942508 -188.849) (xy 43.941999 -188.876886) (xy 43.933879 -188.932062) (xy 43.917811 -188.985469)
			(xy 43.894139 -189.035966) (xy 43.863366 -189.082479) (xy 43.826149 -189.124016) (xy 43.783281 -189.159691)
			(xy 43.735675 -189.188745) (xy 43.684346 -189.210557) (xy 43.630389 -189.224663) (xy 43.574952 -189.230763)
			(xy 43.519218 -189.228726) (xy 43.464375 -189.218596) (xy 43.411591 -189.200589) (xy 43.361991 -189.175088)
			(xy 43.316633 -189.142637) (xy 43.276484 -189.103928) (xy 43.242398 -189.059785) (xy 43.215102 -189.01115)
			(xy 43.195179 -188.959059) (xy 43.183053 -188.904622) (xy 43.178982 -188.849) (xy 41.366998 -188.849)
			(xy 38.58768 -191.628522) (xy 38.579684 -191.637331) (xy 38.572125 -191.659855) (xy 38.573202 -191.671702)
			(xy 38.586918 -191.764412) (xy 38.600634 -191.78397) (xy 38.611302 -191.789812) (xy 38.636873 -191.804215)
			(xy 38.683651 -191.839654) (xy 38.724449 -191.881839) (xy 38.758307 -191.929774) (xy 38.784425 -191.982328)
			(xy 38.802187 -192.038262) (xy 38.811174 -192.096257) (xy 38.811708 -192.1256) (xy 38.811222 -192.152851)
			(xy 38.803466 -192.206799) (xy 38.788111 -192.259094) (xy 38.765469 -192.308671) (xy 38.736003 -192.354521)
			(xy 38.700312 -192.395712) (xy 38.659121 -192.431403) (xy 38.613271 -192.460869) (xy 38.563694 -192.483511)
			(xy 38.511399 -192.498866) (xy 38.457451 -192.506622) (xy 38.4302 -192.507108) (xy 38.400857 -192.50657)
			(xy 38.342863 -192.497583) (xy 38.28693 -192.479821) (xy 38.234376 -192.453704) (xy 38.186442 -192.419846)
			(xy 38.144258 -192.379048) (xy 38.108818 -192.332271) (xy 38.094412 -192.306702) (xy 38.08857 -192.296034)
			(xy 38.069012 -192.282318) (xy 37.976302 -192.268602) (xy 37.964457 -192.26756) (xy 37.941939 -192.275103)
			(xy 37.933122 -192.28308) (xy 36.826444 -193.389758) (xy 36.820331 -193.396396) (xy 36.8128 -193.412783)
			(xy 36.811399 -193.430763) (xy 36.81349 -193.439542) (xy 36.84143 -193.538348) (xy 36.860988 -193.557144)
			(xy 36.874704 -193.560446) (xy 36.902148 -193.567531) (xy 36.954722 -193.588707) (xy 37.003584 -193.617428)
			(xy 37.047658 -193.653063) (xy 37.085976 -193.694826) (xy 37.117693 -193.741799) (xy 37.14211 -193.792947)
			(xy 37.158692 -193.847146) (xy 37.167072 -193.903201) (xy 37.167566 -193.93154) (xy 37.1671 -193.95879)
			(xy 37.159338 -194.012734) (xy 37.143978 -194.065025) (xy 37.121333 -194.114597) (xy 37.091863 -194.160442)
			(xy 37.056169 -194.201627) (xy 37.014977 -194.237312) (xy 36.969125 -194.266772) (xy 36.919548 -194.289407)
			(xy 36.867254 -194.304756) (xy 36.813308 -194.312506) (xy 36.786058 -194.313048) (xy 36.757722 -194.312528)
			(xy 36.701675 -194.304139) (xy 36.647485 -194.287553) (xy 36.596345 -194.263133) (xy 36.549379 -194.231418)
			(xy 36.507621 -194.193105) (xy 36.471989 -194.149036) (xy 36.443268 -194.100182) (xy 36.422089 -194.047617)
			(xy 36.414964 -194.020186) (xy 36.411662 -194.00647) (xy 36.392866 -193.986912) (xy 36.29406 -193.958972)
			(xy 36.285284 -193.956829) (xy 36.267285 -193.958205) (xy 36.250902 -193.965785) (xy 36.244276 -193.971926)
			(xy 34.151824 -196.064124) (xy 34.145679 -196.070846) (xy 34.138172 -196.087425) (xy 34.136914 -196.105581)
			(xy 34.139124 -196.114416) (xy 34.16808 -196.213476) (xy 34.188146 -196.232272) (xy 34.201862 -196.23532)
			(xy 34.243772 -196.245064) (xy 34.325629 -196.271595) (xy 34.404541 -196.305908) (xy 34.479771 -196.34768)
			(xy 34.550615 -196.396523) (xy 34.616412 -196.451978) (xy 34.676546 -196.513528) (xy 34.730455 -196.580598)
			(xy 34.777635 -196.65256) (xy 34.817645 -196.728742) (xy 34.850112 -196.808431) (xy 34.874731 -196.890884)
			(xy 34.891273 -196.975328) (xy 34.899582 -197.060975) (xy 34.900108 -197.104) (xy 34.899633 -197.145102)
			(xy 34.892048 -197.226957) (xy 34.876943 -197.307762) (xy 34.854447 -197.386829) (xy 34.824751 -197.463483)
			(xy 34.788109 -197.53707) (xy 34.744834 -197.606962) (xy 34.695294 -197.672563) (xy 34.639913 -197.733313)
			(xy 34.579163 -197.788694) (xy 34.513562 -197.838234) (xy 34.44367 -197.881509) (xy 34.370083 -197.918151)
			(xy 34.293429 -197.947847) (xy 34.214362 -197.970343) (xy 34.133557 -197.985448) (xy 34.051702 -197.993033)
			(xy 34.0106 -197.993508) (xy 33.96942 -197.993045) (xy 33.887412 -197.985434) (xy 33.806458 -197.970277)
			(xy 33.727252 -197.947704) (xy 33.65047 -197.917909) (xy 33.57677 -197.881145) (xy 33.506783 -197.837729)
			(xy 33.441107 -197.78803) (xy 33.410398 -197.76059) (xy 33.40227 -197.75297) (xy 33.381696 -197.746366)
			(xy 33.283398 -197.757288) (xy 33.264856 -197.768464) (xy 33.258506 -197.777608) (xy 33.243159 -197.798955)
			(xy 33.207542 -197.837628) (xy 33.166954 -197.871046) (xy 33.122165 -197.898578) (xy 33.07402 -197.919703)
			(xy 33.023432 -197.93402) (xy 32.971357 -197.941258) (xy 32.94507 -197.941692) (xy 32.917809 -197.941211)
			(xy 32.863842 -197.933463) (xy 32.811526 -197.918114) (xy 32.761926 -197.895477) (xy 32.716052 -197.866013)
			(xy 32.674838 -197.830321) (xy 32.639121 -197.789128) (xy 32.624014 -197.766432) (xy 32.617664 -197.756526)
			(xy 32.59836 -197.744588) (xy 32.50819 -197.734936) (xy 32.496801 -197.734302) (xy 32.475299 -197.74182)
			(xy 32.466788 -197.749414) (xy 32.170116 -198.046086) (xy 32.163428 -198.053494) (xy 32.155838 -198.07193)
			(xy 32.155384 -198.0819) (xy 32.155384 -198.783702) (xy 32.163004 -198.802244) (xy 32.16783 -198.807324)
			(xy 33.130998 -198.807324) (xy 33.159959 -198.807892) (xy 33.217169 -198.816952) (xy 33.272257 -198.83485)
			(xy 33.323868 -198.861145) (xy 33.370729 -198.895189) (xy 33.391602 -198.915274) (xy 33.882584 -199.406256)
			(xy 33.902708 -199.427106) (xy 33.936807 -199.473957) (xy 33.963154 -199.525566) (xy 33.981101 -199.580662)
			(xy 33.987339 -199.61987) (xy 35.089082 -199.61987) (xy 35.093153 -199.564248) (xy 35.105279 -199.509811)
			(xy 35.125202 -199.45772) (xy 35.152498 -199.409085) (xy 35.186584 -199.364942) (xy 35.226733 -199.326233)
			(xy 35.272091 -199.293782) (xy 35.321691 -199.268281) (xy 35.374475 -199.250274) (xy 35.429318 -199.240144)
			(xy 35.485052 -199.238107) (xy 35.540489 -199.244207) (xy 35.594446 -199.258313) (xy 35.645775 -199.280125)
			(xy 35.693381 -199.309179) (xy 35.736249 -199.344854) (xy 35.773466 -199.386391) (xy 35.804239 -199.432904)
			(xy 35.827911 -199.483401) (xy 35.843979 -199.536808) (xy 35.852099 -199.591984) (xy 35.852608 -199.61987)
			(xy 35.852099 -199.647756) (xy 35.843979 -199.702932) (xy 35.827911 -199.756339) (xy 35.804239 -199.806836)
			(xy 35.773466 -199.853349) (xy 35.736249 -199.894886) (xy 35.693381 -199.930561) (xy 35.645775 -199.959615)
			(xy 35.594446 -199.981427) (xy 35.540489 -199.995533) (xy 35.485052 -200.001633) (xy 35.429318 -199.999596)
			(xy 35.374475 -199.989466) (xy 35.321691 -199.971459) (xy 35.272091 -199.945958) (xy 35.226733 -199.913507)
			(xy 35.186584 -199.874798) (xy 35.152498 -199.830655) (xy 35.125202 -199.78202) (xy 35.105279 -199.729929)
			(xy 35.093153 -199.675492) (xy 35.089082 -199.61987) (xy 33.987339 -199.61987) (xy 33.990206 -199.637888)
			(xy 33.990788 -199.66686) (xy 33.990788 -200.27519) (xy 33.992058 -200.281286) (xy 33.997378 -200.303965)
			(xy 34.003105 -200.350196) (xy 34.003488 -200.373488) (xy 34.003002 -200.400739) (xy 33.995246 -200.454687)
			(xy 33.979891 -200.506982) (xy 33.957249 -200.556559) (xy 33.927783 -200.602409) (xy 33.892092 -200.6436)
			(xy 33.850901 -200.679291) (xy 33.805051 -200.708757) (xy 33.755474 -200.731399) (xy 33.703179 -200.746754)
			(xy 33.649231 -200.75451) (xy 33.594729 -200.75451) (xy 33.540781 -200.746754) (xy 33.488486 -200.731399)
			(xy 33.438909 -200.708757) (xy 33.393059 -200.679291) (xy 33.351868 -200.6436) (xy 33.316177 -200.602409)
			(xy 33.286711 -200.556559) (xy 33.264069 -200.506982) (xy 33.248714 -200.454687) (xy 33.240958 -200.400739)
			(xy 33.240472 -200.373488) (xy 33.24085 -200.350196) (xy 33.246579 -200.303965) (xy 33.251902 -200.281286)
			(xy 33.253172 -200.27519) (xy 33.253172 -199.840596) (xy 33.252697 -199.830629) (xy 33.245122 -199.812191)
			(xy 33.23844 -199.804782) (xy 33.190434 -199.756776) (xy 33.183447 -199.750295) (xy 33.166018 -199.74262)
			(xy 33.14699 -199.74186) (xy 33.137856 -199.744584) (xy 33.03778 -199.779382) (xy 33.019492 -199.801734)
			(xy 33.017714 -199.816466) (xy 33.013916 -199.843899) (xy 32.999423 -199.89735) (xy 32.977354 -199.948144)
			(xy 32.948173 -199.995213) (xy 32.912494 -200.037569) (xy 32.871066 -200.074322) (xy 32.82476 -200.1047)
			(xy 32.774549 -200.128063) (xy 32.721487 -200.143922) (xy 32.66669 -200.151943) (xy 32.639 -200.152508)
			(xy 32.615708 -200.15213) (xy 32.569476 -200.146403) (xy 32.546798 -200.141078) (xy 32.540702 -200.139808)
			(xy 31.643066 -200.139808) (xy 31.619993 -200.139402) (xy 31.574217 -200.133557) (xy 31.529523 -200.122061)
			(xy 31.507938 -200.1139) (xy 31.496 -200.109328) (xy 31.471108 -200.112122) (xy 31.391098 -200.166478)
			(xy 31.3812 -200.174003) (xy 31.369614 -200.19597) (xy 31.369 -200.208388) (xy 31.369 -200.383394)
			(xy 31.369422 -200.393465) (xy 31.377135 -200.412071) (xy 31.383986 -200.419462) (xy 32.005524 -201.041)
			(xy 35.87064 -201.041) (xy 35.874711 -200.985378) (xy 35.886837 -200.930941) (xy 35.90676 -200.87885)
			(xy 35.934056 -200.830215) (xy 35.968142 -200.786072) (xy 36.008291 -200.747363) (xy 36.053649 -200.714912)
			(xy 36.103249 -200.689411) (xy 36.156033 -200.671404) (xy 36.210876 -200.661274) (xy 36.26661 -200.659237)
			(xy 36.322047 -200.665337) (xy 36.376004 -200.679443) (xy 36.427333 -200.701255) (xy 36.474939 -200.730309)
			(xy 36.517807 -200.765984) (xy 36.555024 -200.807521) (xy 36.585797 -200.854034) (xy 36.609469 -200.904531)
			(xy 36.625537 -200.957938) (xy 36.633657 -201.013114) (xy 36.634166 -201.041) (xy 36.633657 -201.068886)
			(xy 36.625537 -201.124062) (xy 36.609469 -201.177469) (xy 36.585797 -201.227966) (xy 36.555024 -201.274479)
			(xy 36.517807 -201.316016) (xy 36.474939 -201.351691) (xy 36.427333 -201.380745) (xy 36.376004 -201.402557)
			(xy 36.322047 -201.416663) (xy 36.26661 -201.422763) (xy 36.210876 -201.420726) (xy 36.156033 -201.410596)
			(xy 36.103249 -201.392589) (xy 36.053649 -201.367088) (xy 36.008291 -201.334637) (xy 35.968142 -201.295928)
			(xy 35.934056 -201.251785) (xy 35.90676 -201.20315) (xy 35.886837 -201.151059) (xy 35.874711 -201.096622)
			(xy 35.87064 -201.041) (xy 32.005524 -201.041) (xy 32.764984 -201.80046) (xy 32.772391 -201.807151)
			(xy 32.790827 -201.814745) (xy 32.800798 -201.815192) (xy 33.192466 -201.815192) (xy 33.201199 -201.814847)
			(xy 33.217646 -201.808974) (xy 33.23113 -201.797877) (xy 33.2359 -201.790554) (xy 33.287716 -201.703686)
			(xy 33.288224 -201.67727) (xy 33.28162 -201.665332) (xy 33.267065 -201.637208) (xy 33.246459 -201.577332)
			(xy 33.23602 -201.514875) (xy 33.235392 -201.483214) (xy 33.235878 -201.455963) (xy 33.243634 -201.402015)
			(xy 33.258989 -201.34972) (xy 33.281631 -201.300143) (xy 33.311097 -201.254293) (xy 33.346788 -201.213102)
			(xy 33.387979 -201.177411) (xy 33.433829 -201.147945) (xy 33.483406 -201.125303) (xy 33.535701 -201.109948)
			(xy 33.589649 -201.102192) (xy 33.644151 -201.102192) (xy 33.698099 -201.109948) (xy 33.750394 -201.125303)
			(xy 33.799971 -201.147945) (xy 33.845821 -201.177411) (xy 33.887012 -201.213102) (xy 33.922703 -201.254293)
			(xy 33.952169 -201.300143) (xy 33.974811 -201.34972) (xy 33.990166 -201.402015) (xy 33.997922 -201.455963)
			(xy 33.998408 -201.483214) (xy 33.997785 -201.514875) (xy 33.987338 -201.57733) (xy 33.966733 -201.637207)
			(xy 33.95218 -201.665332) (xy 33.945576 -201.67727) (xy 33.946084 -201.703686) (xy 33.9979 -201.790554)
			(xy 34.002715 -201.797832) (xy 34.016209 -201.808879) (xy 34.032616 -201.814787) (xy 34.041334 -201.815192)
			(xy 36.516564 -201.815192) (xy 36.545537 -201.815752) (xy 36.602763 -201.824862) (xy 36.657858 -201.842816)
			(xy 36.709464 -201.869172) (xy 36.75631 -201.903279) (xy 36.777168 -201.923396) (xy 37.72281 -202.869038)
			(xy 37.74289 -202.889917) (xy 37.776942 -202.936775) (xy 37.803246 -202.988383) (xy 37.821153 -203.04347)
			(xy 37.830223 -203.10068) (xy 37.83076 -203.129642) (xy 37.83076 -209.502248) (xy 37.830226 -209.531213)
			(xy 37.821171 -209.588431) (xy 37.803277 -209.643528) (xy 37.776983 -209.695147) (xy 37.742938 -209.742018)
			(xy 37.72281 -209.762852) (xy 33.679638 -213.806278) (xy 33.672835 -213.813626) (xy 33.665125 -213.832089)
			(xy 33.664652 -213.842092) (xy 33.664652 -217.226388) (xy 33.665073 -217.236437) (xy 33.672774 -217.255002)
			(xy 33.687002 -217.269196) (xy 33.696148 -217.273378) (xy 33.710626 -217.27922)
		)
		(stroke
			(width 0)
			(type solid)
		)
		(fill yes)
		(layer "In2.Cu")
		(net "P3V3_AUX")
	)
	(gr_poly
		(pts
			(xy 14.772386 -213.400386) (xy 14.77983 -213.40708) (xy 14.798329 -213.41468) (xy 14.818328 -213.414669)
			(xy 14.827758 -213.411308) (xy 14.841982 -213.405466) (xy 14.859 -213.380066) (xy 14.879066 -213.36)
			(xy 20.561808 -213.36) (xy 20.571815 -213.35951) (xy 20.590304 -213.35185) (xy 20.604454 -213.337697)
			(xy 20.612112 -213.319207) (xy 20.612608 -213.3092) (xy 20.612608 -212.068664) (xy 20.612045 -212.057037)
			(xy 20.60187 -212.036126) (xy 20.59305 -212.028532) (xy 20.572333 -212.011788) (xy 20.535325 -211.973473)
			(xy 20.50401 -211.930381) (xy 20.478999 -211.883349) (xy 20.460777 -211.833293) (xy 20.449701 -211.781189)
			(xy 20.445984 -211.72805) (xy 20.449701 -211.674911) (xy 20.460777 -211.622807) (xy 20.478999 -211.572751)
			(xy 20.50401 -211.525719) (xy 20.535325 -211.482627) (xy 20.572333 -211.444312) (xy 20.59305 -211.427568)
			(xy 20.602448 -211.420202) (xy 20.612608 -211.39912) (xy 20.612608 -211.347558) (xy 20.612113 -211.337555)
			(xy 20.604446 -211.319077) (xy 20.590295 -211.304935) (xy 20.571811 -211.297281) (xy 20.561808 -211.296758)
			(xy 20.555204 -211.296758) (xy 20.548854 -211.298536) (xy 20.511463 -211.308061) (xy 20.435456 -211.321382)
			(xy 20.358583 -211.32808) (xy 20.32 -211.328508) (xy 20.278898 -211.328033) (xy 20.197043 -211.320448)
			(xy 20.116238 -211.305343) (xy 20.037171 -211.282847) (xy 19.960517 -211.253151) (xy 19.88693 -211.216509)
			(xy 19.817038 -211.173234) (xy 19.751437 -211.123694) (xy 19.690687 -211.068313) (xy 19.635306 -211.007563)
			(xy 19.585766 -210.941962) (xy 19.542491 -210.87207) (xy 19.505849 -210.798483) (xy 19.476153 -210.721829)
			(xy 19.453657 -210.642762) (xy 19.438552 -210.561957) (xy 19.430967 -210.480102) (xy 19.430492 -210.439)
			(xy 19.431055 -210.394022) (xy 19.440139 -210.304526) (xy 19.458225 -210.216406) (xy 19.471132 -210.173316)
			(xy 19.474434 -210.162648) (xy 19.471894 -210.141566) (xy 19.421348 -210.057238) (xy 19.403822 -210.045046)
			(xy 19.3929 -210.043014) (xy 19.352654 -210.034932) (xy 19.273735 -210.012329) (xy 19.197234 -209.98255)
			(xy 19.123802 -209.945849) (xy 19.054063 -209.902539) (xy 18.988612 -209.852988) (xy 18.928005 -209.797617)
			(xy 18.872757 -209.736897) (xy 18.823339 -209.671345) (xy 18.78017 -209.601519) (xy 18.743619 -209.528013)
			(xy 18.713996 -209.451451) (xy 18.691552 -209.372486) (xy 18.67648 -209.291789) (xy 18.668907 -209.210046)
			(xy 18.668492 -209.169) (xy 18.668996 -209.126652) (xy 18.677047 -209.042338) (xy 18.693076 -208.959172)
			(xy 18.716937 -208.877905) (xy 18.748416 -208.799275) (xy 18.787227 -208.723994) (xy 18.833017 -208.652742)
			(xy 18.885373 -208.586166) (xy 18.943821 -208.524868) (xy 19.007831 -208.469403) (xy 19.076823 -208.420274)
			(xy 19.150173 -208.377925) (xy 19.227216 -208.342741) (xy 19.307255 -208.315039) (xy 19.389564 -208.295071)
			(xy 19.473399 -208.283018) (xy 19.558 -208.278988) (xy 19.642601 -208.283018) (xy 19.726436 -208.295071)
			(xy 19.808745 -208.315039) (xy 19.888784 -208.342741) (xy 19.965827 -208.377925) (xy 20.039177 -208.420274)
			(xy 20.108169 -208.469403) (xy 20.172179 -208.524868) (xy 20.230627 -208.586166) (xy 20.282983 -208.652742)
			(xy 20.328773 -208.723994) (xy 20.367584 -208.799275) (xy 20.399063 -208.877905) (xy 20.422924 -208.959172)
			(xy 20.438953 -209.042338) (xy 20.447004 -209.126652) (xy 20.447508 -209.169) (xy 20.446945 -209.213978)
			(xy 20.437861 -209.303474) (xy 20.419775 -209.391594) (xy 20.406868 -209.434684) (xy 20.403566 -209.445352)
			(xy 20.406106 -209.466434) (xy 20.456652 -209.550762) (xy 20.474178 -209.562954) (xy 20.4851 -209.564986)
			(xy 20.49145 -209.566256) (xy 20.50288 -209.568288) (xy 20.52447 -209.562954) (xy 20.594066 -209.505804)
			(xy 20.602422 -209.498179) (xy 20.612028 -209.477733) (xy 20.612608 -209.466434) (xy 20.612608 -208.162144)
			(xy 20.612175 -208.152078) (xy 20.604447 -208.133488) (xy 20.597622 -208.126076) (xy 20.516342 -208.044796)
			(xy 20.50894 -208.037959) (xy 20.490342 -208.030246) (xy 20.480274 -208.02981) (xy 20.473416 -208.02981)
			(xy 18.900902 -206.457296) (xy 18.894056 -206.449897) (xy 18.886322 -206.431299) (xy 18.885916 -206.421228)
			(xy 18.885916 -205.22946) (xy 18.885486 -205.219393) (xy 18.877763 -205.200797) (xy 18.87093 -205.193392)
			(xy 18.789396 -205.111604) (xy 18.769269 -205.090754) (xy 18.735165 -205.043905) (xy 18.708811 -204.992297)
			(xy 18.690856 -204.937201) (xy 18.681742 -204.879974) (xy 18.681192 -204.851) (xy 18.681192 -203.424536)
			(xy 18.680706 -203.414574) (xy 18.673118 -203.39615) (xy 18.66646 -203.388722) (xy 18.433796 -203.155804)
			(xy 18.413669 -203.134954) (xy 18.379565 -203.088105) (xy 18.353211 -203.036497) (xy 18.335256 -202.981401)
			(xy 18.326142 -202.924174) (xy 18.325592 -202.8952) (xy 18.325592 -197.582536) (xy 18.325106 -197.572574)
			(xy 18.317518 -197.55415) (xy 18.31086 -197.546722) (xy 17.951196 -197.186804) (xy 17.931069 -197.165954)
			(xy 17.896965 -197.119105) (xy 17.870611 -197.067497) (xy 17.852656 -197.012401) (xy 17.843542 -196.955174)
			(xy 17.842992 -196.9262) (xy 17.842992 -196.349874) (xy 17.842513 -196.339909) (xy 17.834935 -196.321475)
			(xy 17.82826 -196.31406) (xy 17.787112 -196.272912) (xy 17.751552 -196.269356) (xy 17.736058 -196.279516)
			(xy 17.712554 -196.2944) (xy 17.662148 -196.317942) (xy 17.608859 -196.333919) (xy 17.553816 -196.341993)
			(xy 17.526 -196.342508) (xy 17.497938 -196.34201) (xy 17.442421 -196.333783) (xy 17.388709 -196.317507)
			(xy 17.337963 -196.293534) (xy 17.291279 -196.262381) (xy 17.249666 -196.224721) (xy 17.214023 -196.181368)
			(xy 17.199102 -196.157596) (xy 17.1958 -196.152262) (xy 16.630396 -195.586604) (xy 16.610269 -195.565754)
			(xy 16.576165 -195.518905) (xy 16.549811 -195.467297) (xy 16.531856 -195.412201) (xy 16.522742 -195.354974)
			(xy 16.522192 -195.326) (xy 16.522192 -191.165988) (xy 16.522748 -191.137013) (xy 16.531851 -191.079783)
			(xy 16.549799 -191.024683) (xy 16.57615 -190.973071) (xy 16.610254 -190.92622) (xy 16.630396 -190.905384)
			(xy 17.027652 -190.507874) (xy 17.034326 -190.500461) (xy 17.041891 -190.482025) (xy 17.042384 -190.47206)
			(xy 17.042384 -186.952128) (xy 17.041971 -186.942803) (xy 17.035291 -186.925391) (xy 17.022811 -186.911533)
			(xy 17.014698 -186.906916) (xy 16.920972 -186.859418) (xy 16.892524 -186.861704) (xy 16.88084 -186.87034)
			(xy 16.856118 -186.8878) (xy 16.802311 -186.915504) (xy 16.744804 -186.934363) (xy 16.68504 -186.943902)
			(xy 16.65478 -186.944508) (xy 16.62753 -186.944021) (xy 16.573584 -186.936262) (xy 16.521292 -186.920905)
			(xy 16.471717 -186.898263) (xy 16.425869 -186.868796) (xy 16.384681 -186.833105) (xy 16.348992 -186.791915)
			(xy 16.319528 -186.746065) (xy 16.296888 -186.696489) (xy 16.281534 -186.644196) (xy 16.273778 -186.59025)
			(xy 16.273778 -186.53575) (xy 16.281534 -186.481804) (xy 16.296888 -186.429511) (xy 16.319528 -186.379935)
			(xy 16.348992 -186.334085) (xy 16.384681 -186.292895) (xy 16.425869 -186.257204) (xy 16.471717 -186.227737)
			(xy 16.521292 -186.205095) (xy 16.573584 -186.189738) (xy 16.62753 -186.181979) (xy 16.65478 -186.181492)
			(xy 16.685042 -186.182069) (xy 16.744809 -186.191617) (xy 16.802319 -186.210477) (xy 16.856133 -186.238176)
			(xy 16.88084 -186.25566) (xy 16.892524 -186.264296) (xy 16.920972 -186.266582) (xy 17.014698 -186.219084)
			(xy 17.022806 -186.214466) (xy 17.035268 -186.200598) (xy 17.041954 -186.183194) (xy 17.042384 -186.173872)
			(xy 17.042384 -184.543446) (xy 17.042943 -184.514473) (xy 17.052052 -184.457246) (xy 17.070004 -184.402149)
			(xy 17.096359 -184.350542) (xy 17.130465 -184.303695) (xy 17.150588 -184.282842) (xy 17.654524 -183.778652)
			(xy 17.661214 -183.771244) (xy 17.668811 -183.752808) (xy 17.669256 -183.742838) (xy 17.669256 -183.534304)
			(xy 17.668876 -183.525134) (xy 17.6624 -183.507977) (xy 17.650252 -183.494239) (xy 17.642332 -183.4896)
			(xy 17.550638 -183.440578) (xy 17.522698 -183.442102) (xy 17.511014 -183.45023) (xy 17.487223 -183.465655)
			(xy 17.436048 -183.490061) (xy 17.381825 -183.506632) (xy 17.325749 -183.515001) (xy 17.2974 -183.515508)
			(xy 17.270149 -183.515022) (xy 17.216201 -183.507266) (xy 17.163906 -183.491911) (xy 17.114329 -183.469269)
			(xy 17.068479 -183.439803) (xy 17.027288 -183.404112) (xy 16.991597 -183.362921) (xy 16.962131 -183.317071)
			(xy 16.939489 -183.267494) (xy 16.924134 -183.215199) (xy 16.916378 -183.161251) (xy 16.916378 -183.106749)
			(xy 16.924134 -183.052801) (xy 16.939489 -183.000506) (xy 16.962131 -182.950929) (xy 16.991597 -182.905079)
			(xy 17.027288 -182.863888) (xy 17.068479 -182.828197) (xy 17.114329 -182.798731) (xy 17.163906 -182.776089)
			(xy 17.216201 -182.760734) (xy 17.270149 -182.752978) (xy 17.2974 -182.752492) (xy 17.32575 -182.75299)
			(xy 17.381831 -182.761346) (xy 17.436054 -182.777919) (xy 17.487224 -182.802342) (xy 17.511014 -182.81777)
			(xy 17.522698 -182.825898) (xy 17.550638 -182.827422) (xy 17.642332 -182.7784) (xy 17.650225 -182.773737)
			(xy 17.662318 -182.759976) (xy 17.668829 -182.742853) (xy 17.669256 -182.733696) (xy 17.669256 -182.240936)
			(xy 17.669816 -182.211963) (xy 17.678925 -182.154736) (xy 17.696878 -182.09964) (xy 17.723232 -182.048032)
			(xy 17.757337 -182.001185) (xy 17.77746 -181.980332) (xy 18.03527 -181.722268) (xy 18.042115 -181.714869)
			(xy 18.049842 -181.696271) (xy 18.050256 -181.6862) (xy 18.050256 -181.18201) (xy 18.049777 -181.172113)
			(xy 18.042271 -181.153796) (xy 18.028406 -181.139668) (xy 18.019522 -181.135274) (xy 17.919192 -181.092602)
			(xy 17.889728 -181.097936) (xy 17.878552 -181.108604) (xy 17.857114 -181.128316) (xy 17.809377 -181.161671)
			(xy 17.757127 -181.187389) (xy 17.701578 -181.204873) (xy 17.644018 -181.213718) (xy 17.6149 -181.214268)
			(xy 17.585804 -181.213719) (xy 17.528287 -181.204879) (xy 17.472782 -181.187403) (xy 17.420575 -181.161697)
			(xy 17.372879 -181.128359) (xy 17.330802 -181.088161) (xy 17.31264 -181.065424) (xy 17.305782 -181.056788)
			(xy 17.286732 -181.046628) (xy 17.19961 -181.040786) (xy 17.188677 -181.040579) (xy 17.16826 -181.048341)
			(xy 17.16024 -181.055772) (xy 13.79474 -184.421272) (xy 13.788047 -184.428678) (xy 13.780449 -184.447115)
			(xy 13.780008 -184.457086) (xy 13.780008 -188.087) (xy 14.50543 -188.087) (xy 14.509501 -188.031378)
			(xy 14.521627 -187.976941) (xy 14.54155 -187.92485) (xy 14.568846 -187.876215) (xy 14.602932 -187.832072)
			(xy 14.643081 -187.793363) (xy 14.688439 -187.760912) (xy 14.738039 -187.735411) (xy 14.790823 -187.717404)
			(xy 14.845666 -187.707274) (xy 14.9014 -187.705237) (xy 14.956837 -187.711337) (xy 15.010794 -187.725443)
			(xy 15.062123 -187.747255) (xy 15.109729 -187.776309) (xy 15.152597 -187.811984) (xy 15.189814 -187.853521)
			(xy 15.220587 -187.900034) (xy 15.244259 -187.950531) (xy 15.260327 -188.003938) (xy 15.268447 -188.059114)
			(xy 15.268956 -188.087) (xy 15.268447 -188.114886) (xy 15.260327 -188.170062) (xy 15.244259 -188.223469)
			(xy 15.220587 -188.273966) (xy 15.189814 -188.320479) (xy 15.152597 -188.362016) (xy 15.109729 -188.397691)
			(xy 15.062123 -188.426745) (xy 15.010794 -188.448557) (xy 14.956837 -188.462663) (xy 14.9014 -188.468763)
			(xy 14.845666 -188.466726) (xy 14.790823 -188.456596) (xy 14.738039 -188.438589) (xy 14.688439 -188.413088)
			(xy 14.643081 -188.380637) (xy 14.602932 -188.341928) (xy 14.568846 -188.297785) (xy 14.54155 -188.24915)
			(xy 14.521627 -188.197059) (xy 14.509501 -188.142622) (xy 14.50543 -188.087) (xy 13.780008 -188.087)
			(xy 13.780008 -193.5988) (xy 15.258286 -193.5988) (xy 15.262357 -193.543178) (xy 15.274483 -193.488741)
			(xy 15.294406 -193.43665) (xy 15.321702 -193.388015) (xy 15.355788 -193.343872) (xy 15.395937 -193.305163)
			(xy 15.441295 -193.272712) (xy 15.490895 -193.247211) (xy 15.543679 -193.229204) (xy 15.598522 -193.219074)
			(xy 15.654256 -193.217037) (xy 15.709693 -193.223137) (xy 15.76365 -193.237243) (xy 15.814979 -193.259055)
			(xy 15.862585 -193.288109) (xy 15.905453 -193.323784) (xy 15.94267 -193.365321) (xy 15.973443 -193.411834)
			(xy 15.997115 -193.462331) (xy 16.013183 -193.515738) (xy 16.021303 -193.570914) (xy 16.021812 -193.5988)
			(xy 16.021303 -193.626686) (xy 16.013183 -193.681862) (xy 15.997115 -193.735269) (xy 15.973443 -193.785766)
			(xy 15.94267 -193.832279) (xy 15.905453 -193.873816) (xy 15.862585 -193.909491) (xy 15.814979 -193.938545)
			(xy 15.76365 -193.960357) (xy 15.709693 -193.974463) (xy 15.654256 -193.980563) (xy 15.598522 -193.978526)
			(xy 15.543679 -193.968396) (xy 15.490895 -193.950389) (xy 15.441295 -193.924888) (xy 15.395937 -193.892437)
			(xy 15.355788 -193.853728) (xy 15.321702 -193.809585) (xy 15.294406 -193.76095) (xy 15.274483 -193.708859)
			(xy 15.262357 -193.654422) (xy 15.258286 -193.5988) (xy 13.780008 -193.5988) (xy 13.780008 -197.0532)
			(xy 14.520924 -197.0532) (xy 14.524995 -196.997578) (xy 14.537121 -196.943141) (xy 14.557044 -196.89105)
			(xy 14.58434 -196.842415) (xy 14.618426 -196.798272) (xy 14.658575 -196.759563) (xy 14.703933 -196.727112)
			(xy 14.753533 -196.701611) (xy 14.806317 -196.683604) (xy 14.86116 -196.673474) (xy 14.916894 -196.671437)
			(xy 14.972331 -196.677537) (xy 15.026288 -196.691643) (xy 15.077617 -196.713455) (xy 15.125223 -196.742509)
			(xy 15.168091 -196.778184) (xy 15.205308 -196.819721) (xy 15.236081 -196.866234) (xy 15.259753 -196.916731)
			(xy 15.275821 -196.970138) (xy 15.283941 -197.025314) (xy 15.28445 -197.0532) (xy 15.283941 -197.081086)
			(xy 15.280569 -197.104) (xy 16.381982 -197.104) (xy 16.386053 -197.048378) (xy 16.398179 -196.993941)
			(xy 16.418102 -196.94185) (xy 16.445398 -196.893215) (xy 16.479484 -196.849072) (xy 16.519633 -196.810363)
			(xy 16.564991 -196.777912) (xy 16.614591 -196.752411) (xy 16.667375 -196.734404) (xy 16.722218 -196.724274)
			(xy 16.777952 -196.722237) (xy 16.833389 -196.728337) (xy 16.887346 -196.742443) (xy 16.938675 -196.764255)
			(xy 16.986281 -196.793309) (xy 17.029149 -196.828984) (xy 17.066366 -196.870521) (xy 17.097139 -196.917034)
			(xy 17.120811 -196.967531) (xy 17.136879 -197.020938) (xy 17.144999 -197.076114) (xy 17.145508 -197.104)
			(xy 17.144999 -197.131886) (xy 17.136879 -197.187062) (xy 17.120811 -197.240469) (xy 17.097139 -197.290966)
			(xy 17.066366 -197.337479) (xy 17.029149 -197.379016) (xy 16.986281 -197.414691) (xy 16.938675 -197.443745)
			(xy 16.887346 -197.465557) (xy 16.833389 -197.479663) (xy 16.777952 -197.485763) (xy 16.722218 -197.483726)
			(xy 16.667375 -197.473596) (xy 16.614591 -197.455589) (xy 16.564991 -197.430088) (xy 16.519633 -197.397637)
			(xy 16.479484 -197.358928) (xy 16.445398 -197.314785) (xy 16.418102 -197.26615) (xy 16.398179 -197.214059)
			(xy 16.386053 -197.159622) (xy 16.381982 -197.104) (xy 15.280569 -197.104) (xy 15.275821 -197.136262)
			(xy 15.259753 -197.189669) (xy 15.236081 -197.240166) (xy 15.205308 -197.286679) (xy 15.168091 -197.328216)
			(xy 15.125223 -197.363891) (xy 15.077617 -197.392945) (xy 15.026288 -197.414757) (xy 14.972331 -197.428863)
			(xy 14.916894 -197.434963) (xy 14.86116 -197.432926) (xy 14.806317 -197.422796) (xy 14.753533 -197.404789)
			(xy 14.703933 -197.379288) (xy 14.658575 -197.346837) (xy 14.618426 -197.308128) (xy 14.58434 -197.263985)
			(xy 14.557044 -197.21535) (xy 14.537121 -197.163259) (xy 14.524995 -197.108822) (xy 14.520924 -197.0532)
			(xy 13.780008 -197.0532) (xy 13.780008 -199.076056) (xy 17.148554 -199.076056) (xy 17.152625 -199.020434)
			(xy 17.164751 -198.965997) (xy 17.184674 -198.913906) (xy 17.21197 -198.865271) (xy 17.246056 -198.821128)
			(xy 17.286205 -198.782419) (xy 17.331563 -198.749968) (xy 17.381163 -198.724467) (xy 17.433947 -198.70646)
			(xy 17.48879 -198.69633) (xy 17.544524 -198.694293) (xy 17.599961 -198.700393) (xy 17.653918 -198.714499)
			(xy 17.705247 -198.736311) (xy 17.752853 -198.765365) (xy 17.795721 -198.80104) (xy 17.832938 -198.842577)
			(xy 17.863711 -198.88909) (xy 17.887383 -198.939587) (xy 17.903451 -198.992994) (xy 17.911571 -199.04817)
			(xy 17.91208 -199.076056) (xy 17.911571 -199.103942) (xy 17.903451 -199.159118) (xy 17.887383 -199.212525)
			(xy 17.863711 -199.263022) (xy 17.832938 -199.309535) (xy 17.795721 -199.351072) (xy 17.752853 -199.386747)
			(xy 17.705247 -199.415801) (xy 17.653918 -199.437613) (xy 17.599961 -199.451719) (xy 17.544524 -199.457819)
			(xy 17.48879 -199.455782) (xy 17.433947 -199.445652) (xy 17.381163 -199.427645) (xy 17.331563 -199.402144)
			(xy 17.286205 -199.369693) (xy 17.246056 -199.330984) (xy 17.21197 -199.286841) (xy 17.184674 -199.238206)
			(xy 17.164751 -199.186115) (xy 17.152625 -199.131678) (xy 17.148554 -199.076056) (xy 13.780008 -199.076056)
			(xy 13.780008 -202.686996) (xy 14.350098 -202.686996) (xy 14.35273 -202.603188) (xy 14.363237 -202.519999)
			(xy 14.381527 -202.438169) (xy 14.407436 -202.358422) (xy 14.440735 -202.281468) (xy 14.481128 -202.207989)
			(xy 14.528257 -202.138637) (xy 14.581703 -202.074029) (xy 14.640992 -202.014736) (xy 14.705597 -201.961287)
			(xy 14.774946 -201.914154) (xy 14.848423 -201.873757) (xy 14.925375 -201.840454) (xy 15.00512 -201.81454)
			(xy 15.08695 -201.796246) (xy 15.170138 -201.785734) (xy 15.253946 -201.783097) (xy 15.337631 -201.788359)
			(xy 15.420448 -201.801472) (xy 15.501665 -201.822322) (xy 15.580558 -201.850721) (xy 15.656429 -201.88642)
			(xy 15.728604 -201.929099) (xy 15.796442 -201.978382) (xy 15.859341 -202.03383) (xy 15.916743 -202.094951)
			(xy 15.968138 -202.161203) (xy 16.013071 -202.231997) (xy 16.051142 -202.306706) (xy 16.082013 -202.384665)
			(xy 16.10541 -202.465184) (xy 16.121127 -202.547548) (xy 16.129022 -202.631025) (xy 16.129508 -202.67295)
			(xy 16.129071 -202.71241) (xy 16.12205 -202.791016) (xy 16.108095 -202.868692) (xy 16.087314 -202.944827)
			(xy 16.059872 -203.018822) (xy 16.025984 -203.090095) (xy 16.006318 -203.124308) (xy 16.000899 -203.134726)
			(xy 15.999231 -203.158124) (xy 16.00809 -203.179843) (xy 16.016478 -203.188062) (xy 16.036228 -203.206222)
			(xy 16.070887 -203.247178) (xy 16.099469 -203.292585) (xy 16.121412 -203.341546) (xy 16.136283 -203.393097)
			(xy 16.143788 -203.446223) (xy 16.14424 -203.47305) (xy 16.143698 -203.5003) (xy 16.135949 -203.554247)
			(xy 16.120601 -203.606541) (xy 16.097967 -203.656119) (xy 16.068507 -203.701971) (xy 16.032821 -203.743163)
			(xy 15.991636 -203.778858) (xy 15.945791 -203.808327) (xy 15.896218 -203.830972) (xy 15.843927 -203.846332)
			(xy 15.789982 -203.854092) (xy 15.762732 -203.854558) (xy 15.736081 -203.854113) (xy 15.6833 -203.846678)
			(xy 15.632067 -203.831974) (xy 15.583375 -203.810289) (xy 15.538173 -203.782043) (xy 15.497337 -203.747785)
			(xy 15.461663 -203.708182) (xy 15.431843 -203.664002) (xy 15.408456 -203.616105) (xy 15.399766 -203.590906)
			(xy 15.395666 -203.579941) (xy 15.379382 -203.563156) (xy 15.357346 -203.555323) (xy 15.345664 -203.556108)
			(xy 15.319348 -203.559068) (xy 15.266481 -203.562247) (xy 15.24 -203.562458) (xy 15.198075 -203.562024)
			(xy 15.114598 -203.554134) (xy 15.032233 -203.538422) (xy 14.951713 -203.515029) (xy 14.873751 -203.484162)
			(xy 14.79904 -203.446096) (xy 14.728243 -203.401167) (xy 14.661989 -203.349776) (xy 14.600865 -203.292377)
			(xy 14.545413 -203.229481) (xy 14.496127 -203.161646) (xy 14.453443 -203.089474) (xy 14.41774 -203.013605)
			(xy 14.389336 -202.934712) (xy 14.368482 -202.853497) (xy 14.355364 -202.77068) (xy 14.350098 -202.686996)
			(xy 13.780008 -202.686996) (xy 13.780008 -204.369924) (xy 16.382492 -204.369924) (xy 16.383022 -204.327606)
			(xy 16.391053 -204.243351) (xy 16.407053 -204.160241) (xy 16.430879 -204.079027) (xy 16.462314 -204.000445)
			(xy 16.501074 -203.925205) (xy 16.546808 -203.853989) (xy 16.599102 -203.787441) (xy 16.657484 -203.726164)
			(xy 16.721424 -203.670711) (xy 16.790344 -203.621585) (xy 16.86362 -203.579231) (xy 16.94059 -203.544031)
			(xy 16.980408 -203.529692) (xy 16.99085 -203.525315) (xy 17.00692 -203.509415) (xy 17.014645 -203.48817)
			(xy 17.01419 -203.47686) (xy 17.012666 -203.441554) (xy 17.013152 -203.414303) (xy 17.020908 -203.360355)
			(xy 17.036263 -203.30806) (xy 17.058905 -203.258483) (xy 17.088371 -203.212633) (xy 17.124062 -203.171442)
			(xy 17.165253 -203.135751) (xy 17.211103 -203.106285) (xy 17.26068 -203.083643) (xy 17.312975 -203.068288)
			(xy 17.366923 -203.060532) (xy 17.421425 -203.060532) (xy 17.475373 -203.068288) (xy 17.527668 -203.083643)
			(xy 17.577245 -203.106285) (xy 17.623095 -203.135751) (xy 17.664286 -203.171442) (xy 17.699977 -203.212633)
			(xy 17.729443 -203.258483) (xy 17.752085 -203.30806) (xy 17.76744 -203.360355) (xy 17.775196 -203.414303)
			(xy 17.775682 -203.441554) (xy 17.774955 -203.47536) (xy 17.763079 -203.54192) (xy 17.75206 -203.573888)
			(xy 17.748722 -203.584703) (xy 17.750686 -203.607218) (xy 17.76211 -203.626718) (xy 17.77111 -203.633578)
			(xy 17.806705 -203.658374) (xy 17.873431 -203.713818) (xy 17.934444 -203.775493) (xy 17.989163 -203.842814)
			(xy 18.037071 -203.915141) (xy 18.07771 -203.991788) (xy 18.110697 -204.072027) (xy 18.135716 -204.155096)
			(xy 18.152532 -204.240205) (xy 18.160983 -204.326547) (xy 18.161508 -204.369924) (xy 18.161004 -204.412272)
			(xy 18.152953 -204.496586) (xy 18.136924 -204.579752) (xy 18.113063 -204.661019) (xy 18.081584 -204.739649)
			(xy 18.042773 -204.81493) (xy 17.996983 -204.886182) (xy 17.944627 -204.952758) (xy 17.886179 -205.014056)
			(xy 17.822169 -205.069521) (xy 17.753177 -205.11865) (xy 17.679827 -205.160999) (xy 17.602784 -205.196183)
			(xy 17.522745 -205.223885) (xy 17.440436 -205.243853) (xy 17.356601 -205.255906) (xy 17.272 -205.259937)
			(xy 17.187399 -205.255906) (xy 17.103564 -205.243853) (xy 17.021255 -205.223885) (xy 16.941216 -205.196183)
			(xy 16.864173 -205.160999) (xy 16.790823 -205.11865) (xy 16.721831 -205.069521) (xy 16.657821 -205.014056)
			(xy 16.599373 -204.952758) (xy 16.547017 -204.886182) (xy 16.501227 -204.81493) (xy 16.462416 -204.739649)
			(xy 16.430937 -204.661019) (xy 16.407076 -204.579752) (xy 16.391047 -204.496586) (xy 16.382996 -204.412272)
			(xy 16.382492 -204.369924) (xy 13.780008 -204.369924) (xy 13.780008 -205.74) (xy 15.111982 -205.74)
			(xy 15.116053 -205.684378) (xy 15.128179 -205.629941) (xy 15.148102 -205.57785) (xy 15.175398 -205.529215)
			(xy 15.209484 -205.485072) (xy 15.249633 -205.446363) (xy 15.294991 -205.413912) (xy 15.344591 -205.388411)
			(xy 15.397375 -205.370404) (xy 15.452218 -205.360274) (xy 15.507952 -205.358237) (xy 15.563389 -205.364337)
			(xy 15.617346 -205.378443) (xy 15.668675 -205.400255) (xy 15.716281 -205.429309) (xy 15.759149 -205.464984)
			(xy 15.796366 -205.506521) (xy 15.827139 -205.553034) (xy 15.850811 -205.603531) (xy 15.866879 -205.656938)
			(xy 15.874999 -205.712114) (xy 15.875508 -205.74) (xy 15.874999 -205.767886) (xy 15.866879 -205.823062)
			(xy 15.850811 -205.876469) (xy 15.827139 -205.926966) (xy 15.796366 -205.973479) (xy 15.759149 -206.015016)
			(xy 15.716281 -206.050691) (xy 15.668675 -206.079745) (xy 15.617346 -206.101557) (xy 15.563389 -206.115663)
			(xy 15.507952 -206.121763) (xy 15.452218 -206.119726) (xy 15.397375 -206.109596) (xy 15.344591 -206.091589)
			(xy 15.294991 -206.066088) (xy 15.249633 -206.033637) (xy 15.209484 -205.994928) (xy 15.175398 -205.950785)
			(xy 15.148102 -205.90215) (xy 15.128179 -205.850059) (xy 15.116053 -205.795622) (xy 15.111982 -205.74)
			(xy 13.780008 -205.74) (xy 13.780008 -206.530702) (xy 13.781278 -206.536798) (xy 13.786598 -206.559477)
			(xy 13.792325 -206.605708) (xy 13.792708 -206.629) (xy 13.792222 -206.656251) (xy 13.784466 -206.710199)
			(xy 13.769111 -206.762494) (xy 13.746469 -206.812071) (xy 13.717003 -206.857921) (xy 13.681312 -206.899112)
			(xy 13.640121 -206.934803) (xy 13.594271 -206.964269) (xy 13.544694 -206.986911) (xy 13.492399 -207.002266)
			(xy 13.438451 -207.010022) (xy 13.4112 -207.010508) (xy 13.383295 -207.009978) (xy 13.328083 -207.001818)
			(xy 13.301218 -206.994252) (xy 13.289534 -206.990696) (xy 13.265912 -206.995014) (xy 13.190728 -207.050894)
			(xy 13.181627 -207.058499) (xy 13.171044 -207.07969) (xy 13.170408 -207.091534) (xy 13.170408 -207.938116)
			(xy 16.216882 -207.938116) (xy 16.220953 -207.882494) (xy 16.233079 -207.828057) (xy 16.253002 -207.775966)
			(xy 16.280298 -207.727331) (xy 16.314384 -207.683188) (xy 16.354533 -207.644479) (xy 16.399891 -207.612028)
			(xy 16.449491 -207.586527) (xy 16.502275 -207.56852) (xy 16.557118 -207.55839) (xy 16.612852 -207.556353)
			(xy 16.668289 -207.562453) (xy 16.722246 -207.576559) (xy 16.773575 -207.598371) (xy 16.821181 -207.627425)
			(xy 16.864049 -207.6631) (xy 16.901266 -207.704637) (xy 16.932039 -207.75115) (xy 16.955711 -207.801647)
			(xy 16.971779 -207.855054) (xy 16.979899 -207.91023) (xy 16.980408 -207.938116) (xy 16.979899 -207.966002)
			(xy 16.971779 -208.021178) (xy 16.955711 -208.074585) (xy 16.932039 -208.125082) (xy 16.901266 -208.171595)
			(xy 16.864049 -208.213132) (xy 16.821181 -208.248807) (xy 16.773575 -208.277861) (xy 16.722246 -208.299673)
			(xy 16.668289 -208.313779) (xy 16.612852 -208.319879) (xy 16.557118 -208.317842) (xy 16.502275 -208.307712)
			(xy 16.449491 -208.289705) (xy 16.399891 -208.264204) (xy 16.354533 -208.231753) (xy 16.314384 -208.193044)
			(xy 16.280298 -208.148901) (xy 16.253002 -208.100266) (xy 16.233079 -208.048175) (xy 16.220953 -207.993738)
			(xy 16.216882 -207.938116) (xy 13.170408 -207.938116) (xy 13.170408 -208.435956) (xy 15.054324 -208.435956)
			(xy 15.058395 -208.380334) (xy 15.070521 -208.325897) (xy 15.090444 -208.273806) (xy 15.11774 -208.225171)
			(xy 15.151826 -208.181028) (xy 15.191975 -208.142319) (xy 15.237333 -208.109868) (xy 15.286933 -208.084367)
			(xy 15.339717 -208.06636) (xy 15.39456 -208.05623) (xy 15.450294 -208.054193) (xy 15.505731 -208.060293)
			(xy 15.559688 -208.074399) (xy 15.611017 -208.096211) (xy 15.658623 -208.125265) (xy 15.701491 -208.16094)
			(xy 15.738708 -208.202477) (xy 15.769481 -208.24899) (xy 15.793153 -208.299487) (xy 15.809221 -208.352894)
			(xy 15.817341 -208.40807) (xy 15.81785 -208.435956) (xy 15.817341 -208.463842) (xy 15.809221 -208.519018)
			(xy 15.804714 -208.534) (xy 17.817082 -208.534) (xy 17.821153 -208.478378) (xy 17.833279 -208.423941)
			(xy 17.853202 -208.37185) (xy 17.880498 -208.323215) (xy 17.914584 -208.279072) (xy 17.954733 -208.240363)
			(xy 18.000091 -208.207912) (xy 18.049691 -208.182411) (xy 18.102475 -208.164404) (xy 18.157318 -208.154274)
			(xy 18.213052 -208.152237) (xy 18.268489 -208.158337) (xy 18.322446 -208.172443) (xy 18.373775 -208.194255)
			(xy 18.421381 -208.223309) (xy 18.464249 -208.258984) (xy 18.501466 -208.300521) (xy 18.532239 -208.347034)
			(xy 18.555911 -208.397531) (xy 18.571979 -208.450938) (xy 18.580099 -208.506114) (xy 18.580608 -208.534)
			(xy 18.580099 -208.561886) (xy 18.571979 -208.617062) (xy 18.555911 -208.670469) (xy 18.532239 -208.720966)
			(xy 18.501466 -208.767479) (xy 18.464249 -208.809016) (xy 18.421381 -208.844691) (xy 18.373775 -208.873745)
			(xy 18.322446 -208.895557) (xy 18.268489 -208.909663) (xy 18.213052 -208.915763) (xy 18.157318 -208.913726)
			(xy 18.102475 -208.903596) (xy 18.049691 -208.885589) (xy 18.000091 -208.860088) (xy 17.954733 -208.827637)
			(xy 17.914584 -208.788928) (xy 17.880498 -208.744785) (xy 17.853202 -208.69615) (xy 17.833279 -208.644059)
			(xy 17.821153 -208.589622) (xy 17.817082 -208.534) (xy 15.804714 -208.534) (xy 15.793153 -208.572425)
			(xy 15.769481 -208.622922) (xy 15.738708 -208.669435) (xy 15.701491 -208.710972) (xy 15.658623 -208.746647)
			(xy 15.611017 -208.775701) (xy 15.559688 -208.797513) (xy 15.505731 -208.811619) (xy 15.450294 -208.817719)
			(xy 15.39456 -208.815682) (xy 15.339717 -208.805552) (xy 15.286933 -208.787545) (xy 15.237333 -208.762044)
			(xy 15.191975 -208.729593) (xy 15.151826 -208.690884) (xy 15.11774 -208.646741) (xy 15.090444 -208.598106)
			(xy 15.070521 -208.546015) (xy 15.058395 -208.491578) (xy 15.054324 -208.435956) (xy 13.170408 -208.435956)
			(xy 13.170408 -210.252056) (xy 16.888204 -210.252056) (xy 16.892275 -210.196434) (xy 16.904401 -210.141997)
			(xy 16.924324 -210.089906) (xy 16.95162 -210.041271) (xy 16.985706 -209.997128) (xy 17.025855 -209.958419)
			(xy 17.071213 -209.925968) (xy 17.120813 -209.900467) (xy 17.173597 -209.88246) (xy 17.22844 -209.87233)
			(xy 17.284174 -209.870293) (xy 17.339611 -209.876393) (xy 17.393568 -209.890499) (xy 17.444897 -209.912311)
			(xy 17.492503 -209.941365) (xy 17.535371 -209.97704) (xy 17.572588 -210.018577) (xy 17.603361 -210.06509)
			(xy 17.627033 -210.115587) (xy 17.643101 -210.168994) (xy 17.651221 -210.22417) (xy 17.65173 -210.252056)
			(xy 17.651221 -210.279942) (xy 17.643101 -210.335118) (xy 17.627033 -210.388525) (xy 17.603361 -210.439022)
			(xy 17.572588 -210.485535) (xy 17.535371 -210.527072) (xy 17.492503 -210.562747) (xy 17.444897 -210.591801)
			(xy 17.393568 -210.613613) (xy 17.339611 -210.627719) (xy 17.284174 -210.633819) (xy 17.22844 -210.631782)
			(xy 17.173597 -210.621652) (xy 17.120813 -210.603645) (xy 17.071213 -210.578144) (xy 17.025855 -210.545693)
			(xy 16.985706 -210.506984) (xy 16.95162 -210.462841) (xy 16.924324 -210.414206) (xy 16.904401 -210.362115)
			(xy 16.892275 -210.307678) (xy 16.888204 -210.252056) (xy 13.170408 -210.252056) (xy 13.170408 -211.04225)
			(xy 15.420846 -211.04225) (xy 15.424917 -210.986628) (xy 15.437043 -210.932191) (xy 15.456966 -210.8801)
			(xy 15.484262 -210.831465) (xy 15.518348 -210.787322) (xy 15.558497 -210.748613) (xy 15.603855 -210.716162)
			(xy 15.653455 -210.690661) (xy 15.706239 -210.672654) (xy 15.761082 -210.662524) (xy 15.816816 -210.660487)
			(xy 15.872253 -210.666587) (xy 15.92621 -210.680693) (xy 15.977539 -210.702505) (xy 16.025145 -210.731559)
			(xy 16.068013 -210.767234) (xy 16.10523 -210.808771) (xy 16.136003 -210.855284) (xy 16.159675 -210.905781)
			(xy 16.175743 -210.959188) (xy 16.183863 -211.014364) (xy 16.184372 -211.04225) (xy 16.183863 -211.070136)
			(xy 16.175743 -211.125312) (xy 16.159675 -211.178719) (xy 16.136003 -211.229216) (xy 16.10523 -211.275729)
			(xy 16.068013 -211.317266) (xy 16.025145 -211.352941) (xy 15.977539 -211.381995) (xy 15.92621 -211.403807)
			(xy 15.872253 -211.417913) (xy 15.816816 -211.424013) (xy 15.761082 -211.421976) (xy 15.706239 -211.411846)
			(xy 15.653455 -211.393839) (xy 15.603855 -211.368338) (xy 15.558497 -211.335887) (xy 15.518348 -211.297178)
			(xy 15.484262 -211.253035) (xy 15.456966 -211.2044) (xy 15.437043 -211.152309) (xy 15.424917 -211.097872)
			(xy 15.420846 -211.04225) (xy 13.170408 -211.04225) (xy 13.170408 -212.045804) (xy 13.170883 -212.055771)
			(xy 13.178456 -212.074211) (xy 13.18514 -212.081618) (xy 13.641578 -212.538056) (xy 19.180554 -212.538056)
			(xy 19.184625 -212.482434) (xy 19.196751 -212.427997) (xy 19.216674 -212.375906) (xy 19.24397 -212.327271)
			(xy 19.278056 -212.283128) (xy 19.318205 -212.244419) (xy 19.363563 -212.211968) (xy 19.413163 -212.186467)
			(xy 19.465947 -212.16846) (xy 19.52079 -212.15833) (xy 19.576524 -212.156293) (xy 19.631961 -212.162393)
			(xy 19.685918 -212.176499) (xy 19.737247 -212.198311) (xy 19.784853 -212.227365) (xy 19.827721 -212.26304)
			(xy 19.864938 -212.304577) (xy 19.895711 -212.35109) (xy 19.919383 -212.401587) (xy 19.935451 -212.454994)
			(xy 19.943571 -212.51017) (xy 19.94408 -212.538056) (xy 19.943571 -212.565942) (xy 19.935451 -212.621118)
			(xy 19.919383 -212.674525) (xy 19.895711 -212.725022) (xy 19.864938 -212.771535) (xy 19.827721 -212.813072)
			(xy 19.784853 -212.848747) (xy 19.737247 -212.877801) (xy 19.685918 -212.899613) (xy 19.631961 -212.913719)
			(xy 19.576524 -212.919819) (xy 19.52079 -212.917782) (xy 19.465947 -212.907652) (xy 19.413163 -212.889645)
			(xy 19.363563 -212.864144) (xy 19.318205 -212.831693) (xy 19.278056 -212.792984) (xy 19.24397 -212.748841)
			(xy 19.216674 -212.700206) (xy 19.196751 -212.648115) (xy 19.184625 -212.593678) (xy 19.180554 -212.538056)
			(xy 13.641578 -212.538056) (xy 13.813536 -212.710014) (xy 13.820932 -212.716864) (xy 13.839531 -212.724599)
			(xy 13.849604 -212.725) (xy 14.075918 -212.725) (xy 14.085987 -212.725427) (xy 14.104586 -212.733146)
			(xy 14.111986 -212.739986)
		)
		(stroke
			(width 0)
			(type solid)
		)
		(fill yes)
		(layer "In2.Cu")
		(net "P3V3_AUX")
	)
	(gr_poly
		(pts
			(xy 6.315456 -140.208) (xy 6.325522 -140.207566) (xy 6.344111 -140.199838) (xy 6.351524 -140.193014)
			(xy 9.80186 -136.742678) (xy 9.808603 -136.735308) (xy 9.816194 -136.716846) (xy 9.816592 -136.706864)
			(xy 9.816592 -132.650992) (xy 9.815948 -132.638437) (xy 9.804091 -132.616305) (xy 9.793986 -132.608828)
			(xy 9.712452 -132.55498) (xy 9.687052 -132.552694) (xy 9.675114 -132.557774) (xy 9.6513 -132.567509)
			(xy 9.601708 -132.581205) (xy 9.550724 -132.588095) (xy 9.525 -132.588508) (xy 9.497749 -132.588022)
			(xy 9.443801 -132.580266) (xy 9.391506 -132.564911) (xy 9.341929 -132.542269) (xy 9.296079 -132.512803)
			(xy 9.254888 -132.477112) (xy 9.219197 -132.435921) (xy 9.189731 -132.390071) (xy 9.167089 -132.340494)
			(xy 9.151734 -132.288199) (xy 9.143978 -132.234251) (xy 9.143978 -132.179749) (xy 9.151734 -132.125801)
			(xy 9.167089 -132.073506) (xy 9.189731 -132.023929) (xy 9.219197 -131.978079) (xy 9.254888 -131.936888)
			(xy 9.296079 -131.901197) (xy 9.341929 -131.871731) (xy 9.391506 -131.849089) (xy 9.443801 -131.833734)
			(xy 9.497749 -131.825978) (xy 9.525 -131.825492) (xy 9.550722 -131.825917) (xy 9.601701 -131.832827)
			(xy 9.651293 -131.84651) (xy 9.675114 -131.856226) (xy 9.687052 -131.861306) (xy 9.712452 -131.85902)
			(xy 9.793986 -131.805172) (xy 9.804037 -131.79765) (xy 9.815871 -131.775543) (xy 9.816592 -131.763008)
			(xy 9.816592 -130.618992) (xy 9.815948 -130.606437) (xy 9.804091 -130.584305) (xy 9.793986 -130.576828)
			(xy 9.712452 -130.52298) (xy 9.687052 -130.520694) (xy 9.675114 -130.525774) (xy 9.6513 -130.535509)
			(xy 9.601708 -130.549205) (xy 9.550724 -130.556095) (xy 9.525 -130.556508) (xy 9.497749 -130.556022)
			(xy 9.443801 -130.548266) (xy 9.391506 -130.532911) (xy 9.341929 -130.510269) (xy 9.296079 -130.480803)
			(xy 9.254888 -130.445112) (xy 9.219197 -130.403921) (xy 9.189731 -130.358071) (xy 9.167089 -130.308494)
			(xy 9.151734 -130.256199) (xy 9.143978 -130.202251) (xy 9.143978 -130.147749) (xy 9.151734 -130.093801)
			(xy 9.167089 -130.041506) (xy 9.189731 -129.991929) (xy 9.219197 -129.946079) (xy 9.254888 -129.904888)
			(xy 9.296079 -129.869197) (xy 9.341929 -129.839731) (xy 9.391506 -129.817089) (xy 9.443801 -129.801734)
			(xy 9.497749 -129.793978) (xy 9.525 -129.793492) (xy 9.542049 -129.793674) (xy 9.57601 -129.796728)
			(xy 9.592818 -129.799588) (xy 9.603994 -129.80162) (xy 9.625838 -129.795778) (xy 9.694418 -129.738628)
			(xy 9.70259 -129.730986) (xy 9.711937 -129.710689) (xy 9.712452 -129.699512) (xy 9.712452 -119.45366)
			(xy 9.71301 -119.424686) (xy 9.722116 -119.367457) (xy 9.740066 -119.312359) (xy 9.766417 -119.260748)
			(xy 9.800521 -119.213897) (xy 9.820656 -119.193056) (xy 10.258552 -118.754906) (xy 10.265405 -118.74751)
			(xy 10.273149 -118.728912) (xy 10.273538 -118.718838) (xy 10.273538 -116.781072) (xy 10.273967 -116.771005)
			(xy 10.281693 -116.752411) (xy 10.288524 -116.745004) (xy 10.57656 -116.456968) (xy 10.583301 -116.449597)
			(xy 10.590889 -116.431135) (xy 10.591292 -116.421154) (xy 10.591292 -108.796836) (xy 10.590806 -108.786874)
			(xy 10.583218 -108.76845) (xy 10.57656 -108.761022) (xy 9.198356 -107.382818) (xy 9.162796 -107.379008)
			(xy 9.147302 -107.389168) (xy 9.114078 -107.410497) (xy 9.044246 -107.447342) (xy 8.971171 -107.477245)
			(xy 8.895541 -107.499925) (xy 8.81807 -107.515169) (xy 8.739486 -107.522832) (xy 8.700008 -107.52328)
			(xy 8.660077 -107.52279) (xy 8.580599 -107.514962) (xy 8.502271 -107.499382) (xy 8.425847 -107.476199)
			(xy 8.352064 -107.445636) (xy 8.281632 -107.407989) (xy 8.215229 -107.36362) (xy 8.153494 -107.312956)
			(xy 8.097023 -107.256484) (xy 8.046359 -107.19475) (xy 8.00199 -107.128346) (xy 7.964343 -107.057914)
			(xy 7.933781 -106.984131) (xy 7.910598 -106.907707) (xy 7.895018 -106.829379) (xy 7.88719 -106.749901)
			(xy 7.88719 -106.670039) (xy 7.895018 -106.590561) (xy 7.910598 -106.512233) (xy 7.933781 -106.435809)
			(xy 7.964343 -106.362026) (xy 8.00199 -106.291594) (xy 8.046359 -106.22519) (xy 8.097023 -106.163456)
			(xy 8.153494 -106.106984) (xy 8.215229 -106.05632) (xy 8.281632 -106.011951) (xy 8.352064 -105.974304)
			(xy 8.425847 -105.943741) (xy 8.502271 -105.920558) (xy 8.580599 -105.904978) (xy 8.660077 -105.89715)
			(xy 8.700008 -105.896664) (xy 8.740091 -105.897143) (xy 8.819868 -105.905027) (xy 8.898482 -105.920722)
			(xy 8.97517 -105.944078) (xy 9.049187 -105.974866) (xy 9.119816 -106.012788) (xy 9.18637 -106.057477)
			(xy 9.248204 -106.108497) (xy 9.304716 -106.165355) (xy 9.35536 -106.227498) (xy 9.399643 -106.294323)
			(xy 9.437135 -106.365181) (xy 9.467472 -106.439384) (xy 9.49036 -106.516213) (xy 9.505577 -106.594921)
			(xy 9.50976 -106.634788) (xy 9.510776 -106.643678) (xy 9.518142 -106.65968) (xy 10.285476 -107.427014)
			(xy 10.292874 -107.433858) (xy 10.311474 -107.441578) (xy 10.321544 -107.442) (xy 10.773918 -107.442)
			(xy 10.783987 -107.441573) (xy 10.802586 -107.433854) (xy 10.809986 -107.427014) (xy 10.907014 -107.329986)
			(xy 10.913868 -107.322591) (xy 10.92161 -107.303992) (xy 10.922 -107.293918) (xy 10.922 -106.574082)
			(xy 10.922427 -106.564013) (xy 10.930146 -106.545414) (xy 10.936986 -106.538014) (xy 11.10996 -106.36504)
			(xy 11.116655 -106.357634) (xy 11.124258 -106.339198) (xy 11.124692 -106.329226) (xy 11.124692 -105.8799)
			(xy 11.125247 -105.850925) (xy 11.134349 -105.793694) (xy 11.152295 -105.738593) (xy 11.178645 -105.686979)
			(xy 11.212749 -105.640126) (xy 11.232896 -105.619296) (xy 19.42846 -97.423478) (xy 19.435203 -97.416108)
			(xy 19.442794 -97.397646) (xy 19.443192 -97.387664) (xy 19.443192 -89.467182) (xy 19.442758 -89.456833)
			(xy 19.434667 -89.437789) (xy 19.419695 -89.423507) (xy 19.410172 -89.41943) (xy 19.305524 -89.380822)
			(xy 19.27479 -89.38895) (xy 19.264376 -89.401142) (xy 19.246173 -89.421821) (xy 19.204832 -89.458237)
			(xy 19.15868 -89.48832) (xy 19.108677 -89.511446) (xy 19.055865 -89.527131) (xy 19.001346 -89.535048)
			(xy 18.9738 -89.535508) (xy 18.946549 -89.535022) (xy 18.892601 -89.527266) (xy 18.840306 -89.511911)
			(xy 18.790729 -89.489269) (xy 18.744879 -89.459803) (xy 18.703688 -89.424112) (xy 18.667997 -89.382921)
			(xy 18.638531 -89.337071) (xy 18.615889 -89.287494) (xy 18.600534 -89.235199) (xy 18.592778 -89.181251)
			(xy 18.592292 -89.154) (xy 18.592764 -89.12663) (xy 18.600587 -89.072452) (xy 18.616074 -89.019948)
			(xy 18.638906 -88.970196) (xy 18.668614 -88.924219) (xy 18.686272 -88.903302) (xy 18.692368 -88.89619)
			(xy 18.698718 -88.879172) (xy 18.698718 -88.793828) (xy 18.692368 -88.77681) (xy 18.686272 -88.769698)
			(xy 18.668629 -88.748766) (xy 18.638901 -88.702799) (xy 18.616053 -88.653053) (xy 18.600555 -88.600551)
			(xy 18.592725 -88.546371) (xy 18.592725 -88.491629) (xy 18.600555 -88.437449) (xy 18.616053 -88.384947)
			(xy 18.638901 -88.335201) (xy 18.668629 -88.289234) (xy 18.686272 -88.268302) (xy 18.692368 -88.26119)
			(xy 18.698718 -88.244172) (xy 18.698718 -88.158828) (xy 18.692368 -88.14181) (xy 18.686272 -88.134698)
			(xy 18.668631 -88.113766) (xy 18.638908 -88.067799) (xy 18.616066 -88.018052) (xy 18.600578 -87.965549)
			(xy 18.59276 -87.91137) (xy 18.592292 -87.884) (xy 18.592778 -87.856749) (xy 18.600534 -87.802801)
			(xy 18.615889 -87.750506) (xy 18.638531 -87.700929) (xy 18.667997 -87.655079) (xy 18.703688 -87.613888)
			(xy 18.744879 -87.578197) (xy 18.790729 -87.548731) (xy 18.840306 -87.526089) (xy 18.892601 -87.510734)
			(xy 18.946549 -87.502978) (xy 18.9738 -87.502492) (xy 19.001342 -87.502983) (xy 19.055851 -87.51092)
			(xy 19.108653 -87.526613) (xy 19.158648 -87.549737) (xy 19.204798 -87.57981) (xy 19.246143 -87.616208)
			(xy 19.264376 -87.636858) (xy 19.27479 -87.64905) (xy 19.305524 -87.657178) (xy 19.410172 -87.61857)
			(xy 19.419673 -87.614477) (xy 19.43459 -87.600171) (xy 19.442684 -87.581153) (xy 19.443192 -87.570818)
			(xy 19.443192 -86.17839) (xy 19.442716 -86.168423) (xy 19.435142 -86.149985) (xy 19.42846 -86.142576)
			(xy 19.167094 -85.88121) (xy 19.160258 -85.874827) (xy 19.143201 -85.867184) (xy 19.124535 -85.866224)
			(xy 19.115532 -85.868764) (xy 19.01571 -85.901276) (xy 18.997168 -85.922866) (xy 18.994882 -85.93709)
			(xy 18.990279 -85.963403) (xy 18.97467 -86.01449) (xy 18.952075 -86.062895) (xy 18.922937 -86.107667)
			(xy 18.905728 -86.128098) (xy 18.899632 -86.13521) (xy 18.893282 -86.152228) (xy 18.893282 -86.237572)
			(xy 18.899632 -86.25459) (xy 18.905728 -86.261702) (xy 18.923369 -86.282634) (xy 18.953092 -86.328601)
			(xy 18.975934 -86.378348) (xy 18.991422 -86.430851) (xy 18.99924 -86.48503) (xy 18.999708 -86.5124)
			(xy 18.999222 -86.539651) (xy 18.991466 -86.593599) (xy 18.976111 -86.645894) (xy 18.953469 -86.695471)
			(xy 18.924003 -86.741321) (xy 18.888312 -86.782512) (xy 18.847121 -86.818203) (xy 18.801271 -86.847669)
			(xy 18.751694 -86.870311) (xy 18.699399 -86.885666) (xy 18.645451 -86.893422) (xy 18.590949 -86.893422)
			(xy 18.537001 -86.885666) (xy 18.484706 -86.870311) (xy 18.435129 -86.847669) (xy 18.389279 -86.818203)
			(xy 18.348088 -86.782512) (xy 18.312397 -86.741321) (xy 18.282931 -86.695471) (xy 18.260289 -86.645894)
			(xy 18.244934 -86.593599) (xy 18.237178 -86.539651) (xy 18.236692 -86.5124) (xy 18.237164 -86.48503)
			(xy 18.244987 -86.430852) (xy 18.260474 -86.378348) (xy 18.283306 -86.328596) (xy 18.313014 -86.282619)
			(xy 18.330672 -86.261702) (xy 18.336768 -86.25459) (xy 18.343118 -86.237572) (xy 18.343118 -86.152228)
			(xy 18.336768 -86.13521) (xy 18.330672 -86.128098) (xy 18.313031 -86.107166) (xy 18.283308 -86.061199)
			(xy 18.260466 -86.011452) (xy 18.244978 -85.958949) (xy 18.23716 -85.90477) (xy 18.236692 -85.8774)
			(xy 18.237178 -85.850149) (xy 18.244934 -85.796201) (xy 18.260289 -85.743906) (xy 18.282931 -85.694329)
			(xy 18.312397 -85.648479) (xy 18.348088 -85.607288) (xy 18.389279 -85.571597) (xy 18.435129 -85.542131)
			(xy 18.484706 -85.519489) (xy 18.537001 -85.504134) (xy 18.590949 -85.496378) (xy 18.6182 -85.495892)
			(xy 18.6563 -85.497924) (xy 18.667984 -85.49894) (xy 18.689066 -85.49132) (xy 18.697194 -85.483192)
			(xy 18.703903 -85.475759) (xy 18.711525 -85.457267) (xy 18.711511 -85.437265) (xy 18.703864 -85.418782)
			(xy 18.697194 -85.41131) (xy 18.675096 -85.388958) (xy 18.654972 -85.368107) (xy 18.620873 -85.321257)
			(xy 18.594525 -85.269648) (xy 18.576577 -85.214552) (xy 18.567471 -85.157326) (xy 18.566892 -85.128354)
			(xy 18.566892 -77.117448) (xy 18.566521 -77.108405) (xy 18.560231 -77.091448) (xy 18.548449 -77.077724)
			(xy 18.54073 -77.072998) (xy 18.450814 -77.023214) (xy 18.423382 -77.023976) (xy 18.411444 -77.031342)
			(xy 18.388591 -77.045132) (xy 18.339849 -77.066883) (xy 18.288549 -77.081621) (xy 18.235694 -77.089055)
			(xy 18.209006 -77.089508) (xy 18.181753 -77.089045) (xy 18.127801 -77.081289) (xy 18.075503 -77.065933)
			(xy 18.025922 -77.043291) (xy 17.980068 -77.013823) (xy 17.938875 -76.97813) (xy 17.90318 -76.936937)
			(xy 17.873712 -76.891083) (xy 17.851069 -76.841503) (xy 17.835712 -76.789205) (xy 17.827955 -76.735253)
			(xy 17.827955 -76.680747) (xy 17.835712 -76.626795) (xy 17.851069 -76.574497) (xy 17.873712 -76.524917)
			(xy 17.90318 -76.479063) (xy 17.938875 -76.43787) (xy 17.980068 -76.402177) (xy 18.025922 -76.372709)
			(xy 18.075503 -76.350067) (xy 18.127801 -76.334711) (xy 18.181753 -76.326955) (xy 18.209006 -76.326492)
			(xy 18.235694 -76.326938) (xy 18.288549 -76.334379) (xy 18.33985 -76.349115) (xy 18.388597 -76.370857)
			(xy 18.411444 -76.384658) (xy 18.423382 -76.392024) (xy 18.450814 -76.392786) (xy 18.54073 -76.343002)
			(xy 18.548463 -76.338295) (xy 18.560245 -76.324566) (xy 18.566519 -76.307598) (xy 18.566892 -76.298552)
			(xy 18.566892 -63.154814) (xy 18.566796 -63.149796) (xy 18.56487 -63.139947) (xy 18.563082 -63.135256)
			(xy 14.48308 -53.285136) (xy 14.474237 -53.262698) (xy 14.461793 -53.216101) (xy 14.455526 -53.168281)
			(xy 14.45514 -53.144166) (xy 14.45514 -40.0558) (xy 14.454653 -40.045789) (xy 14.446994 -40.027291)
			(xy 14.432843 -40.013128) (xy 14.41435 -40.005455) (xy 14.40434 -40.005) (xy 14.4018 -40.005) (xy 14.391792 -40.004512)
			(xy 14.373301 -39.996852) (xy 14.359148 -39.982699) (xy 14.351488 -39.964208) (xy 14.351 -39.9542)
			(xy 14.351 -30.912816) (xy 14.350561 -30.902753) (xy 14.342826 -30.88417) (xy 14.336014 -30.876748)
			(xy 12.566396 -29.106876) (xy 12.546271 -29.086026) (xy 12.51217 -29.039176) (xy 12.48582 -28.987567)
			(xy 12.467869 -28.932471) (xy 12.45876 -28.875245) (xy 12.458192 -28.846272) (xy 12.458192 -18.588736)
			(xy 12.457706 -18.578774) (xy 12.450118 -18.56035) (xy 12.44346 -18.552922) (xy 9.06399 -15.173452)
			(xy 9.056668 -15.166643) (xy 9.038245 -15.158911) (xy 9.018265 -15.158849) (xy 9.008872 -15.162276)
			(xy 8.972048 -15.176878) (xy 8.896184 -15.199695) (xy 8.818463 -15.215034) (xy 8.739618 -15.22275)
			(xy 8.700008 -15.223236) (xy 8.660077 -15.222746) (xy 8.580599 -15.214918) (xy 8.502272 -15.199338)
			(xy 8.425849 -15.176155) (xy 8.352066 -15.145593) (xy 8.281634 -15.107946) (xy 8.215231 -15.063577)
			(xy 8.153497 -15.012913) (xy 8.097026 -14.956441) (xy 8.046362 -14.894707) (xy 8.001993 -14.828304)
			(xy 7.964346 -14.757872) (xy 7.933784 -14.684089) (xy 7.910602 -14.607666) (xy 7.895022 -14.529338)
			(xy 7.887194 -14.44986) (xy 7.887194 -14.369998) (xy 7.895022 -14.290521) (xy 7.910602 -14.212193)
			(xy 7.933785 -14.13577) (xy 7.964347 -14.061987) (xy 8.001994 -13.991555) (xy 8.046363 -13.925152)
			(xy 8.097027 -13.863418) (xy 8.153498 -13.806947) (xy 8.215232 -13.756283) (xy 8.281635 -13.711914)
			(xy 8.352067 -13.674267) (xy 8.42585 -13.643705) (xy 8.502273 -13.620522) (xy 8.580601 -13.604942)
			(xy 8.660078 -13.597114) (xy 8.73994 -13.597114) (xy 8.819418 -13.604942) (xy 8.897746 -13.620522)
			(xy 8.974169 -13.643704) (xy 9.047952 -13.674266) (xy 9.118384 -13.711913) (xy 9.184787 -13.756282)
			(xy 9.246521 -13.806946) (xy 9.302993 -13.863417) (xy 9.353657 -13.925151) (xy 9.398026 -13.991554)
			(xy 9.435673 -14.061986) (xy 9.466235 -14.135769) (xy 9.489418 -14.212192) (xy 9.504998 -14.290519)
			(xy 9.512826 -14.369997) (xy 9.513316 -14.409928) (xy 9.512994 -14.44252) (xy 9.507783 -14.507496)
			(xy 9.502902 -14.539722) (xy 9.50087 -14.551914) (xy 9.50849 -14.575028) (xy 11.149213 -16.215868)
			(xy 16.995646 -16.215868) (xy 16.999717 -16.160246) (xy 17.011843 -16.105809) (xy 17.031766 -16.053718)
			(xy 17.059062 -16.005083) (xy 17.093148 -15.96094) (xy 17.133297 -15.922231) (xy 17.178655 -15.88978)
			(xy 17.228255 -15.864279) (xy 17.281039 -15.846272) (xy 17.335882 -15.836142) (xy 17.391616 -15.834105)
			(xy 17.447053 -15.840205) (xy 17.50101 -15.854311) (xy 17.552339 -15.876123) (xy 17.599945 -15.905177)
			(xy 17.642813 -15.940852) (xy 17.68003 -15.982389) (xy 17.710803 -16.028902) (xy 17.734475 -16.079399)
			(xy 17.750543 -16.132806) (xy 17.758663 -16.187982) (xy 17.759172 -16.215868) (xy 17.758663 -16.243754)
			(xy 17.750543 -16.29893) (xy 17.734475 -16.352337) (xy 17.710803 -16.402834) (xy 17.68003 -16.449347)
			(xy 17.642813 -16.490884) (xy 17.599945 -16.526559) (xy 17.552339 -16.555613) (xy 17.50101 -16.577425)
			(xy 17.447053 -16.591531) (xy 17.391616 -16.597631) (xy 17.335882 -16.595594) (xy 17.281039 -16.585464)
			(xy 17.228255 -16.567457) (xy 17.178655 -16.541956) (xy 17.133297 -16.509505) (xy 17.093148 -16.470796)
			(xy 17.059062 -16.426653) (xy 17.031766 -16.378018) (xy 17.011843 -16.325927) (xy 16.999717 -16.27149)
			(xy 16.995646 -16.215868) (xy 11.149213 -16.215868) (xy 11.92589 -16.9926) (xy 15.188182 -16.9926)
			(xy 15.192253 -16.936978) (xy 15.204379 -16.882541) (xy 15.224302 -16.83045) (xy 15.251598 -16.781815)
			(xy 15.285684 -16.737672) (xy 15.325833 -16.698963) (xy 15.371191 -16.666512) (xy 15.420791 -16.641011)
			(xy 15.473575 -16.623004) (xy 15.528418 -16.612874) (xy 15.584152 -16.610837) (xy 15.639589 -16.616937)
			(xy 15.693546 -16.631043) (xy 15.744875 -16.652855) (xy 15.792481 -16.681909) (xy 15.835349 -16.717584)
			(xy 15.872566 -16.759121) (xy 15.903339 -16.805634) (xy 15.927011 -16.856131) (xy 15.943079 -16.909538)
			(xy 15.951199 -16.964714) (xy 15.951708 -16.9926) (xy 15.951199 -17.020486) (xy 15.943079 -17.075662)
			(xy 15.927011 -17.129069) (xy 15.903339 -17.179566) (xy 15.872566 -17.226079) (xy 15.835349 -17.267616)
			(xy 15.792481 -17.303291) (xy 15.744875 -17.332345) (xy 15.693546 -17.354157) (xy 15.639589 -17.368263)
			(xy 15.584152 -17.374363) (xy 15.528418 -17.372326) (xy 15.473575 -17.362196) (xy 15.420791 -17.344189)
			(xy 15.371191 -17.318688) (xy 15.325833 -17.286237) (xy 15.285684 -17.247528) (xy 15.251598 -17.203385)
			(xy 15.224302 -17.15475) (xy 15.204379 -17.102659) (xy 15.192253 -17.048222) (xy 15.188182 -16.9926)
			(xy 11.92589 -16.9926) (xy 13.087604 -18.154396) (xy 13.107731 -18.175246) (xy 13.141835 -18.222095)
			(xy 13.168189 -18.273703) (xy 13.186144 -18.328799) (xy 13.195258 -18.386026) (xy 13.195808 -18.415)
			(xy 13.195808 -19.9898) (xy 13.196162 -19.999833) (xy 13.203757 -20.018399) (xy 13.21793 -20.032596)
			(xy 13.22705 -20.03679) (xy 13.241528 -20.042632) (xy 13.271246 -20.03679) (xy 16.423894 -16.884396)
			(xy 16.444744 -16.864269) (xy 16.491593 -16.830165) (xy 16.543201 -16.80381) (xy 16.598297 -16.785855)
			(xy 16.655524 -16.776741) (xy 16.684498 -16.776192) (xy 18.793206 -16.776192) (xy 18.803173 -16.775716)
			(xy 18.821612 -16.768143) (xy 18.82902 -16.76146) (xy 19.544538 -16.046196) (xy 19.565388 -16.026072)
			(xy 19.612239 -15.991973) (xy 19.663848 -15.965624) (xy 19.718944 -15.947675) (xy 19.776169 -15.938569)
			(xy 19.805142 -15.937992) (xy 21.339302 -15.937992) (xy 21.345398 -15.936722) (xy 21.368077 -15.931402)
			(xy 21.414308 -15.925675) (xy 21.4376 -15.925292) (xy 21.464851 -15.925778) (xy 21.518799 -15.933534)
			(xy 21.571094 -15.948889) (xy 21.620671 -15.971531) (xy 21.666521 -16.000997) (xy 21.707712 -16.036688)
			(xy 21.743403 -16.077879) (xy 21.772869 -16.123729) (xy 21.795511 -16.173306) (xy 21.810866 -16.225601)
			(xy 21.818622 -16.279549) (xy 21.818622 -16.334051) (xy 21.810866 -16.387999) (xy 21.795511 -16.440294)
			(xy 21.772869 -16.489871) (xy 21.743403 -16.535721) (xy 21.707712 -16.576912) (xy 21.666521 -16.612603)
			(xy 21.620671 -16.642069) (xy 21.571094 -16.664711) (xy 21.518799 -16.680066) (xy 21.464851 -16.687822)
			(xy 21.4376 -16.688308) (xy 21.414308 -16.68793) (xy 21.368076 -16.682203) (xy 21.345398 -16.676878)
			(xy 21.339302 -16.675608) (xy 19.978878 -16.675608) (xy 19.968912 -16.676086) (xy 19.950477 -16.683664)
			(xy 19.943064 -16.69034) (xy 19.227546 -17.405604) (xy 19.206695 -17.425727) (xy 19.159844 -17.459824)
			(xy 19.108235 -17.486171) (xy 19.053139 -17.504117) (xy 18.995914 -17.513221) (xy 18.966942 -17.513808)
			(xy 17.853152 -17.513808) (xy 17.8409 -17.514523) (xy 17.819141 -17.525797) (xy 17.811496 -17.535398)
			(xy 17.756632 -17.61363) (xy 17.75333 -17.638268) (xy 17.757648 -17.649952) (xy 17.768295 -17.681405)
			(xy 17.779784 -17.746801) (xy 17.780508 -17.78) (xy 17.780022 -17.807251) (xy 17.772266 -17.861199)
			(xy 17.756911 -17.913494) (xy 17.734269 -17.963071) (xy 17.704803 -18.008921) (xy 17.669112 -18.050112)
			(xy 17.627921 -18.085803) (xy 17.582071 -18.115269) (xy 17.532494 -18.137911) (xy 17.480199 -18.153266)
			(xy 17.426251 -18.161022) (xy 17.399 -18.161508) (xy 17.375708 -18.16113) (xy 17.329476 -18.155403)
			(xy 17.306798 -18.150078) (xy 17.300702 -18.148808) (xy 16.977614 -18.148808) (xy 16.967654 -18.149298)
			(xy 16.949235 -18.156892) (xy 16.9418 -18.16354) (xy 16.266992 -18.838348) (xy 19.557996 -18.838348)
			(xy 19.557996 -18.753652) (xy 19.566047 -18.669338) (xy 19.582076 -18.586172) (xy 19.605937 -18.504905)
			(xy 19.637416 -18.426275) (xy 19.676227 -18.350994) (xy 19.722017 -18.279742) (xy 19.774373 -18.213166)
			(xy 19.832821 -18.151868) (xy 19.896831 -18.096403) (xy 19.965823 -18.047274) (xy 20.039173 -18.004925)
			(xy 20.116216 -17.969741) (xy 20.196255 -17.942039) (xy 20.278564 -17.922071) (xy 20.362399 -17.910018)
			(xy 20.447 -17.905988) (xy 20.531601 -17.910018) (xy 20.615436 -17.922071) (xy 20.697745 -17.942039)
			(xy 20.777784 -17.969741) (xy 20.854827 -18.004925) (xy 20.928177 -18.047274) (xy 20.997169 -18.096403)
			(xy 21.061179 -18.151868) (xy 21.119627 -18.213166) (xy 21.171983 -18.279742) (xy 21.217773 -18.350994)
			(xy 21.256584 -18.426275) (xy 21.288063 -18.504905) (xy 21.311924 -18.586172) (xy 21.327953 -18.669338)
			(xy 21.336004 -18.753652) (xy 21.336508 -18.796) (xy 21.336004 -18.838348) (xy 21.327953 -18.922662)
			(xy 21.311924 -19.005828) (xy 21.288063 -19.087095) (xy 21.256584 -19.165725) (xy 21.217773 -19.241006)
			(xy 21.17729 -19.304) (xy 28.192982 -19.304) (xy 28.197053 -19.248378) (xy 28.209179 -19.193941)
			(xy 28.229102 -19.14185) (xy 28.256398 -19.093215) (xy 28.290484 -19.049072) (xy 28.330633 -19.010363)
			(xy 28.375991 -18.977912) (xy 28.425591 -18.952411) (xy 28.478375 -18.934404) (xy 28.533218 -18.924274)
			(xy 28.588952 -18.922237) (xy 28.644389 -18.928337) (xy 28.698346 -18.942443) (xy 28.749675 -18.964255)
			(xy 28.797281 -18.993309) (xy 28.840149 -19.028984) (xy 28.877366 -19.070521) (xy 28.908139 -19.117034)
			(xy 28.931811 -19.167531) (xy 28.947879 -19.220938) (xy 28.955999 -19.276114) (xy 28.956508 -19.304)
			(xy 28.955999 -19.331886) (xy 28.947879 -19.387062) (xy 28.931811 -19.440469) (xy 28.908139 -19.490966)
			(xy 28.877366 -19.537479) (xy 28.840149 -19.579016) (xy 28.797281 -19.614691) (xy 28.749675 -19.643745)
			(xy 28.698346 -19.665557) (xy 28.644389 -19.679663) (xy 28.588952 -19.685763) (xy 28.533218 -19.683726)
			(xy 28.478375 -19.673596) (xy 28.425591 -19.655589) (xy 28.375991 -19.630088) (xy 28.330633 -19.597637)
			(xy 28.290484 -19.558928) (xy 28.256398 -19.514785) (xy 28.229102 -19.46615) (xy 28.209179 -19.414059)
			(xy 28.197053 -19.359622) (xy 28.192982 -19.304) (xy 21.17729 -19.304) (xy 21.171983 -19.312258)
			(xy 21.119627 -19.378834) (xy 21.061179 -19.440132) (xy 20.997169 -19.495597) (xy 20.928177 -19.544726)
			(xy 20.854827 -19.587075) (xy 20.777784 -19.622259) (xy 20.697745 -19.649961) (xy 20.615436 -19.669929)
			(xy 20.531601 -19.681982) (xy 20.447 -19.686013) (xy 20.362399 -19.681982) (xy 20.278564 -19.669929)
			(xy 20.196255 -19.649961) (xy 20.116216 -19.622259) (xy 20.039173 -19.587075) (xy 19.965823 -19.544726)
			(xy 19.896831 -19.495597) (xy 19.832821 -19.440132) (xy 19.774373 -19.378834) (xy 19.722017 -19.312258)
			(xy 19.676227 -19.241006) (xy 19.637416 -19.165725) (xy 19.605937 -19.087095) (xy 19.582076 -19.005828)
			(xy 19.566047 -18.922662) (xy 19.557996 -18.838348) (xy 16.266992 -18.838348) (xy 15.915386 -19.189954)
			(xy 15.908539 -19.197351) (xy 15.900811 -19.215951) (xy 15.9004 -19.226022) (xy 15.9004 -19.3294)
			(xy 17.169382 -19.3294) (xy 17.173453 -19.273778) (xy 17.185579 -19.219341) (xy 17.205502 -19.16725)
			(xy 17.232798 -19.118615) (xy 17.266884 -19.074472) (xy 17.307033 -19.035763) (xy 17.352391 -19.003312)
			(xy 17.401991 -18.977811) (xy 17.454775 -18.959804) (xy 17.509618 -18.949674) (xy 17.565352 -18.947637)
			(xy 17.620789 -18.953737) (xy 17.674746 -18.967843) (xy 17.726075 -18.989655) (xy 17.773681 -19.018709)
			(xy 17.816549 -19.054384) (xy 17.853766 -19.095921) (xy 17.884539 -19.142434) (xy 17.908211 -19.192931)
			(xy 17.924279 -19.246338) (xy 17.932399 -19.301514) (xy 17.932908 -19.3294) (xy 17.932399 -19.357286)
			(xy 17.924279 -19.412462) (xy 17.908211 -19.465869) (xy 17.884539 -19.516366) (xy 17.853766 -19.562879)
			(xy 17.816549 -19.604416) (xy 17.773681 -19.640091) (xy 17.726075 -19.669145) (xy 17.674746 -19.690957)
			(xy 17.620789 -19.705063) (xy 17.565352 -19.711163) (xy 17.509618 -19.709126) (xy 17.454775 -19.698996)
			(xy 17.401991 -19.680989) (xy 17.352391 -19.655488) (xy 17.307033 -19.623037) (xy 17.266884 -19.584328)
			(xy 17.232798 -19.540185) (xy 17.205502 -19.49155) (xy 17.185579 -19.439459) (xy 17.173453 -19.385022)
			(xy 17.169382 -19.3294) (xy 15.9004 -19.3294) (xy 15.9004 -19.812) (xy 18.711924 -19.812) (xy 18.715995 -19.756378)
			(xy 18.728121 -19.701941) (xy 18.748044 -19.64985) (xy 18.77534 -19.601215) (xy 18.809426 -19.557072)
			(xy 18.849575 -19.518363) (xy 18.894933 -19.485912) (xy 18.944533 -19.460411) (xy 18.997317 -19.442404)
			(xy 19.05216 -19.432274) (xy 19.107894 -19.430237) (xy 19.163331 -19.436337) (xy 19.217288 -19.450443)
			(xy 19.268617 -19.472255) (xy 19.316223 -19.501309) (xy 19.359091 -19.536984) (xy 19.396308 -19.578521)
			(xy 19.427081 -19.625034) (xy 19.450753 -19.675531) (xy 19.466821 -19.728938) (xy 19.474941 -19.784114)
			(xy 19.47545 -19.812) (xy 19.474941 -19.839886) (xy 19.466821 -19.895062) (xy 19.450753 -19.948469)
			(xy 19.427081 -19.998966) (xy 19.396308 -20.045479) (xy 19.359091 -20.087016) (xy 19.316223 -20.122691)
			(xy 19.268617 -20.151745) (xy 19.217288 -20.173557) (xy 19.163331 -20.187663) (xy 19.107894 -20.193763)
			(xy 19.05216 -20.191726) (xy 18.997317 -20.181596) (xy 18.944533 -20.163589) (xy 18.894933 -20.138088)
			(xy 18.849575 -20.105637) (xy 18.809426 -20.066928) (xy 18.77534 -20.022785) (xy 18.748044 -19.97415)
			(xy 18.728121 -19.922059) (xy 18.715995 -19.867622) (xy 18.711924 -19.812) (xy 15.9004 -19.812) (xy 15.9004 -21.1582)
			(xy 21.842982 -21.1582) (xy 21.847053 -21.102578) (xy 21.859179 -21.048141) (xy 21.879102 -20.99605)
			(xy 21.906398 -20.947415) (xy 21.940484 -20.903272) (xy 21.980633 -20.864563) (xy 22.025991 -20.832112)
			(xy 22.075591 -20.806611) (xy 22.128375 -20.788604) (xy 22.183218 -20.778474) (xy 22.238952 -20.776437)
			(xy 22.294389 -20.782537) (xy 22.348346 -20.796643) (xy 22.399675 -20.818455) (xy 22.447281 -20.847509)
			(xy 22.490149 -20.883184) (xy 22.527366 -20.924721) (xy 22.558139 -20.971234) (xy 22.581811 -21.021731)
			(xy 22.597879 -21.075138) (xy 22.605999 -21.130314) (xy 22.606508 -21.1582) (xy 22.605999 -21.186086)
			(xy 22.597879 -21.241262) (xy 22.581811 -21.294669) (xy 22.558139 -21.345166) (xy 22.527366 -21.391679)
			(xy 22.490149 -21.433216) (xy 22.447281 -21.468891) (xy 22.399675 -21.497945) (xy 22.348346 -21.519757)
			(xy 22.294389 -21.533863) (xy 22.238952 -21.539963) (xy 22.183218 -21.537926) (xy 22.128375 -21.527796)
			(xy 22.075591 -21.509789) (xy 22.025991 -21.484288) (xy 21.980633 -21.451837) (xy 21.940484 -21.413128)
			(xy 21.906398 -21.368985) (xy 21.879102 -21.32035) (xy 21.859179 -21.268259) (xy 21.847053 -21.213822)
			(xy 21.842982 -21.1582) (xy 15.9004 -21.1582) (xy 15.9004 -22.102318) (xy 15.900827 -22.112387) (xy 15.908546 -22.130986)
			(xy 15.915386 -22.138386) (xy 16.876014 -23.099014) (xy 16.882868 -23.106409) (xy 16.89061 -23.125008)
			(xy 16.891 -23.135082) (xy 16.891 -23.941786) (xy 17.817082 -23.941786) (xy 17.821153 -23.886164)
			(xy 17.833279 -23.831727) (xy 17.853202 -23.779636) (xy 17.880498 -23.731001) (xy 17.914584 -23.686858)
			(xy 17.954733 -23.648149) (xy 18.000091 -23.615698) (xy 18.049691 -23.590197) (xy 18.102475 -23.57219)
			(xy 18.157318 -23.56206) (xy 18.213052 -23.560023) (xy 18.268489 -23.566123) (xy 18.322446 -23.580229)
			(xy 18.373775 -23.602041) (xy 18.421381 -23.631095) (xy 18.464249 -23.66677) (xy 18.501466 -23.708307)
			(xy 18.532239 -23.75482) (xy 18.555911 -23.805317) (xy 18.571979 -23.858724) (xy 18.580099 -23.9139)
			(xy 18.580608 -23.941786) (xy 18.580099 -23.969672) (xy 18.571979 -24.024848) (xy 18.555911 -24.078255)
			(xy 18.532239 -24.128752) (xy 18.501466 -24.175265) (xy 18.464249 -24.216802) (xy 18.421381 -24.252477)
			(xy 18.373775 -24.281531) (xy 18.322446 -24.303343) (xy 18.268489 -24.317449) (xy 18.213052 -24.323549)
			(xy 18.157318 -24.321512) (xy 18.102475 -24.311382) (xy 18.049691 -24.293375) (xy 18.000091 -24.267874)
			(xy 17.954733 -24.235423) (xy 17.914584 -24.196714) (xy 17.880498 -24.152571) (xy 17.853202 -24.103936)
			(xy 17.833279 -24.051845) (xy 17.821153 -23.997408) (xy 17.817082 -23.941786) (xy 16.891 -23.941786)
			(xy 16.891 -24.60371) (xy 16.891425 -24.613779) (xy 16.899142 -24.632381) (xy 16.905986 -24.639778)
			(xy 17.532604 -25.26665) (xy 17.552727 -25.287501) (xy 17.586825 -25.334352) (xy 17.613172 -25.385961)
			(xy 17.631119 -25.441056) (xy 17.640224 -25.498282) (xy 17.640808 -25.527254) (xy 17.640808 -27.0256)
			(xy 17.641228 -27.035621) (xy 17.648898 -27.054136) (xy 17.66307 -27.068307) (xy 17.681587 -27.075974)
			(xy 17.691608 -27.0764) (xy 18.470118 -27.0764) (xy 18.480187 -27.076827) (xy 18.498786 -27.084546)
			(xy 18.506186 -27.091386) (xy 18.781014 -27.366214) (xy 18.788409 -27.373068) (xy 18.807008 -27.38081)
			(xy 18.817082 -27.3812) (xy 19.62531 -27.3812) (xy 19.635266 -27.38067) (xy 19.653654 -27.373014)
			(xy 19.667773 -27.358964) (xy 19.672046 -27.349958) (xy 19.678142 -27.33548) (xy 19.6723 -27.305508)
			(xy 19.297396 -26.930604) (xy 19.277269 -26.909754) (xy 19.243165 -26.862905) (xy 19.216811 -26.811297)
			(xy 19.198856 -26.756201) (xy 19.189742 -26.698974) (xy 19.189192 -26.67) (xy 19.189192 -25.654)
			(xy 19.189747 -25.625025) (xy 19.198849 -25.567794) (xy 19.216795 -25.512693) (xy 19.243145 -25.461079)
			(xy 19.277249 -25.414226) (xy 19.297396 -25.393396) (xy 19.80946 -24.881078) (xy 19.816203 -24.873708)
			(xy 19.823794 -24.855246) (xy 19.824192 -24.845264) (xy 19.824192 -22.177248) (xy 19.822922 -22.171152)
			(xy 19.817599 -22.148473) (xy 19.811866 -22.102242) (xy 19.811492 -22.07895) (xy 19.811978 -22.051699)
			(xy 19.819734 -21.997751) (xy 19.835089 -21.945456) (xy 19.857731 -21.895879) (xy 19.887197 -21.850029)
			(xy 19.922888 -21.808838) (xy 19.964079 -21.773147) (xy 20.009929 -21.743681) (xy 20.059506 -21.721039)
			(xy 20.111801 -21.705684) (xy 20.165749 -21.697928) (xy 20.220251 -21.697928) (xy 20.274199 -21.705684)
			(xy 20.326494 -21.721039) (xy 20.376071 -21.743681) (xy 20.421921 -21.773147) (xy 20.463112 -21.808838)
			(xy 20.498803 -21.850029) (xy 20.528269 -21.895879) (xy 20.550911 -21.945456) (xy 20.566266 -21.997751)
			(xy 20.574022 -22.051699) (xy 20.574508 -22.07895) (xy 20.574127 -22.102242) (xy 20.568394 -22.148472)
			(xy 20.563078 -22.171152) (xy 20.561808 -22.177248) (xy 20.561808 -25.019) (xy 20.561253 -25.047975)
			(xy 20.552151 -25.105206) (xy 20.534205 -25.160307) (xy 20.507855 -25.211921) (xy 20.473751 -25.258774)
			(xy 20.453604 -25.279604) (xy 19.94154 -25.791922) (xy 19.934797 -25.799292) (xy 19.927206 -25.817754)
			(xy 19.926808 -25.827736) (xy 19.926808 -26.069798) (xy 19.927534 -26.082044) (xy 19.93882 -26.103786)
			(xy 19.948398 -26.111454) (xy 20.02663 -26.166318) (xy 20.051268 -26.16962) (xy 20.062952 -26.165302)
			(xy 20.094405 -26.154655) (xy 20.159801 -26.143168) (xy 20.193 -26.142442) (xy 20.220922 -26.142936)
			(xy 20.276168 -26.151093) (xy 20.329634 -26.167217) (xy 20.380178 -26.190965) (xy 20.426719 -26.221828)
			(xy 20.468263 -26.259148) (xy 20.503922 -26.302125) (xy 20.532933 -26.349843) (xy 20.544282 -26.37536)
			(xy 20.548346 -26.384504) (xy 21.749004 -27.585416) (xy 21.769129 -27.606266) (xy 21.803231 -27.653116)
			(xy 21.829583 -27.704724) (xy 21.847535 -27.759821) (xy 21.856645 -27.817047) (xy 21.857208 -27.84602)
			(xy 21.857208 -28.8798) (xy 21.857628 -28.889821) (xy 21.865298 -28.908336) (xy 21.87947 -28.922507)
			(xy 21.897987 -28.930174) (xy 21.908008 -28.9306) (xy 22.026118 -28.9306) (xy 22.036187 -28.931027)
			(xy 22.054786 -28.938746) (xy 22.062186 -28.945586) (xy 22.210014 -29.093414) (xy 22.216868 -29.100809)
			(xy 22.22461 -29.119408) (xy 22.225 -29.129482) (xy 22.225 -29.798518) (xy 22.224573 -29.808587)
			(xy 22.216854 -29.827186) (xy 22.210014 -29.834586) (xy 21.960586 -30.084014) (xy 21.953191 -30.090868)
			(xy 21.934592 -30.09861) (xy 21.924518 -30.099) (xy 21.908008 -30.099) (xy 21.897986 -30.099418)
			(xy 21.879466 -30.107087) (xy 21.865291 -30.121259) (xy 21.85762 -30.139778) (xy 21.857208 -30.1498)
			(xy 21.857208 -30.218126) (xy 21.857687 -30.228091) (xy 21.865265 -30.246525) (xy 21.87194 -30.25394)
			(xy 21.956014 -30.338014) (xy 21.962868 -30.345409) (xy 21.97061 -30.364008) (xy 21.971 -30.374082)
			(xy 21.971 -30.859476) (xy 21.971437 -30.86954) (xy 21.979171 -30.888124) (xy 21.985986 -30.895544)
			(xy 22.638004 -31.547816) (xy 22.656038 -31.56712) (xy 22.712172 -31.546038) (xy 22.721645 -31.541971)
			(xy 22.736544 -31.527751) (xy 22.744691 -31.508836) (xy 22.745192 -31.49854) (xy 22.745192 -30.781244)
			(xy 22.74474 -30.770338) (xy 22.735791 -30.750452) (xy 22.72792 -30.74289) (xy 22.662134 -30.685232)
			(xy 22.64156 -30.678882) (xy 22.630384 -30.680406) (xy 22.617995 -30.681942) (xy 22.593083 -30.683595)
			(xy 22.5806 -30.683708) (xy 22.553349 -30.683222) (xy 22.499401 -30.675466) (xy 22.447106 -30.660111)
			(xy 22.397529 -30.637469) (xy 22.351679 -30.608003) (xy 22.310488 -30.572312) (xy 22.274797 -30.531121)
			(xy 22.245331 -30.485271) (xy 22.222689 -30.435694) (xy 22.207334 -30.383399) (xy 22.199578 -30.329451)
			(xy 22.199578 -30.274949) (xy 22.207334 -30.221001) (xy 22.222689 -30.168706) (xy 22.245331 -30.119129)
			(xy 22.274797 -30.073279) (xy 22.310488 -30.032088) (xy 22.351679 -29.996397) (xy 22.397529 -29.966931)
			(xy 22.447106 -29.944289) (xy 22.499401 -29.928934) (xy 22.553349 -29.921178) (xy 22.5806 -29.920692)
			(xy 22.593083 -29.9208) (xy 22.617996 -29.922452) (xy 22.630384 -29.923994) (xy 22.64156 -29.925518)
			(xy 22.662134 -29.919168) (xy 22.72792 -29.86151) (xy 22.735768 -29.853928) (xy 22.744739 -29.834057)
			(xy 22.745192 -29.823156) (xy 22.745192 -27.859736) (xy 22.744706 -27.849774) (xy 22.737118 -27.83135)
			(xy 22.73046 -27.823922) (xy 21.583396 -26.676604) (xy 21.563269 -26.655754) (xy 21.529165 -26.608905)
			(xy 21.502811 -26.557297) (xy 21.484856 -26.502201) (xy 21.475742 -26.444974) (xy 21.475192 -26.416)
			(xy 21.475192 -23.466298) (xy 21.473922 -23.460202) (xy 21.468602 -23.437523) (xy 21.462875 -23.391292)
			(xy 21.462492 -23.368) (xy 21.462978 -23.340749) (xy 21.470734 -23.286801) (xy 21.486089 -23.234506)
			(xy 21.508731 -23.184929) (xy 21.538197 -23.139079) (xy 21.573888 -23.097888) (xy 21.615079 -23.062197)
			(xy 21.660929 -23.032731) (xy 21.710506 -23.010089) (xy 21.762801 -22.994734) (xy 21.816749 -22.986978)
			(xy 21.871251 -22.986978) (xy 21.925199 -22.994734) (xy 21.977494 -23.010089) (xy 22.027071 -23.032731)
			(xy 22.072921 -23.062197) (xy 22.114112 -23.097888) (xy 22.149803 -23.139079) (xy 22.179269 -23.184929)
			(xy 22.201911 -23.234506) (xy 22.217266 -23.286801) (xy 22.225022 -23.340749) (xy 22.225508 -23.368)
			(xy 22.22513 -23.391292) (xy 22.219403 -23.437524) (xy 22.214078 -23.460202) (xy 22.212808 -23.466298)
			(xy 22.212808 -24.03602) (xy 22.746968 -24.03602) (xy 22.751039 -23.980398) (xy 22.763165 -23.925961)
			(xy 22.783088 -23.87387) (xy 22.810384 -23.825235) (xy 22.84447 -23.781092) (xy 22.884619 -23.742383)
			(xy 22.929977 -23.709932) (xy 22.979577 -23.684431) (xy 23.032361 -23.666424) (xy 23.087204 -23.656294)
			(xy 23.142938 -23.654257) (xy 23.198375 -23.660357) (xy 23.252332 -23.674463) (xy 23.303661 -23.696275)
			(xy 23.351267 -23.725329) (xy 23.394135 -23.761004) (xy 23.431352 -23.802541) (xy 23.462125 -23.849054)
			(xy 23.485797 -23.899551) (xy 23.501865 -23.952958) (xy 23.509985 -24.008134) (xy 23.510494 -24.03602)
			(xy 23.509985 -24.063906) (xy 23.501865 -24.119082) (xy 23.485797 -24.172489) (xy 23.462125 -24.222986)
			(xy 23.431352 -24.269499) (xy 23.394135 -24.311036) (xy 23.351267 -24.346711) (xy 23.303661 -24.375765)
			(xy 23.252332 -24.397577) (xy 23.198375 -24.411683) (xy 23.142938 -24.417783) (xy 23.087204 -24.415746)
			(xy 23.032361 -24.405616) (xy 22.979577 -24.387609) (xy 22.929977 -24.362108) (xy 22.884619 -24.329657)
			(xy 22.84447 -24.290948) (xy 22.810384 -24.246805) (xy 22.783088 -24.19817) (xy 22.763165 -24.146079)
			(xy 22.751039 -24.091642) (xy 22.746968 -24.03602) (xy 22.212808 -24.03602) (xy 22.212808 -26.242264)
			(xy 22.213294 -26.252226) (xy 22.220882 -26.27065) (xy 22.22754 -26.278078) (xy 22.322261 -26.37282)
			(xy 23.603202 -26.37282) (xy 23.607273 -26.317198) (xy 23.619399 -26.262761) (xy 23.639322 -26.21067)
			(xy 23.666618 -26.162035) (xy 23.700704 -26.117892) (xy 23.740853 -26.079183) (xy 23.786211 -26.046732)
			(xy 23.835811 -26.021231) (xy 23.888595 -26.003224) (xy 23.943438 -25.993094) (xy 23.999172 -25.991057)
			(xy 24.054609 -25.997157) (xy 24.108566 -26.011263) (xy 24.159895 -26.033075) (xy 24.207501 -26.062129)
			(xy 24.250369 -26.097804) (xy 24.287586 -26.139341) (xy 24.318359 -26.185854) (xy 24.342031 -26.236351)
			(xy 24.358099 -26.289758) (xy 24.366219 -26.344934) (xy 24.366728 -26.37282) (xy 24.366219 -26.400706)
			(xy 24.358099 -26.455882) (xy 24.342031 -26.509289) (xy 24.318359 -26.559786) (xy 24.287586 -26.606299)
			(xy 24.250369 -26.647836) (xy 24.207501 -26.683511) (xy 24.159895 -26.712565) (xy 24.108566 -26.734377)
			(xy 24.054609 -26.748483) (xy 23.999172 -26.754583) (xy 23.943438 -26.752546) (xy 23.888595 -26.742416)
			(xy 23.835811 -26.724409) (xy 23.786211 -26.698908) (xy 23.740853 -26.666457) (xy 23.700704 -26.627748)
			(xy 23.666618 -26.583605) (xy 23.639322 -26.53497) (xy 23.619399 -26.482879) (xy 23.607273 -26.428442)
			(xy 23.603202 -26.37282) (xy 22.322261 -26.37282) (xy 23.374604 -27.425396) (xy 23.394731 -27.446246)
			(xy 23.428835 -27.493095) (xy 23.455189 -27.544703) (xy 23.473144 -27.599799) (xy 23.482258 -27.657026)
			(xy 23.482808 -27.686) (xy 23.482808 -33.977326) (xy 23.483287 -33.987291) (xy 23.490865 -34.005725)
			(xy 23.49754 -34.01314) (xy 23.592028 -34.107628) (xy 23.599406 -34.114441) (xy 23.617936 -34.122143)
			(xy 23.638002 -34.122143) (xy 23.656532 -34.114441) (xy 23.66391 -34.107628) (xy 26.64206 -31.129224)
			(xy 26.648752 -31.121818) (xy 26.656349 -31.103381) (xy 26.656792 -31.09341) (xy 26.656792 -23.9522)
			(xy 26.657347 -23.923225) (xy 26.666449 -23.865994) (xy 26.684395 -23.810893) (xy 26.710745 -23.759279)
			(xy 26.744849 -23.712426) (xy 26.764996 -23.691596) (xy 27.798014 -22.658324) (xy 27.804858 -22.650926)
			(xy 27.812578 -22.632326) (xy 27.813 -22.622256) (xy 27.813 -22.525482) (xy 27.813427 -22.515413)
			(xy 27.821146 -22.496814) (xy 27.827986 -22.489414) (xy 28.610814 -21.706586) (xy 28.618209 -21.699732)
			(xy 28.636808 -21.69199) (xy 28.646882 -21.6916) (xy 29.525722 -21.6916) (xy 29.53579 -21.691173)
			(xy 29.554389 -21.683453) (xy 29.56179 -21.676614) (xy 29.709364 -21.52904) (xy 29.716058 -21.521634)
			(xy 29.723661 -21.503198) (xy 29.724096 -21.493226) (xy 29.724096 -21.307552) (xy 29.722572 -21.301456)
			(xy 29.717236 -21.278715) (xy 29.711502 -21.232356) (xy 29.711142 -21.209) (xy 29.711717 -21.179176)
			(xy 29.720997 -21.120254) (xy 29.73933 -21.063493) (xy 29.76627 -21.010275) (xy 29.801161 -20.961896)
			(xy 29.843154 -20.919534) (xy 29.866844 -20.901406) (xy 29.875988 -20.894802) (xy 29.886656 -20.875498)
			(xy 29.89326 -20.787614) (xy 29.893605 -20.776579) (xy 29.885971 -20.75589) (xy 29.878528 -20.747736)
			(xy 29.182568 -20.051522) (xy 29.162437 -20.030675) (xy 29.128324 -19.983828) (xy 29.101961 -19.93222)
			(xy 29.084 -19.877123) (xy 29.074882 -19.819893) (xy 29.074364 -19.790918) (xy 29.074364 -19.313398)
			(xy 29.073094 -19.307302) (xy 29.067774 -19.284623) (xy 29.062048 -19.238392) (xy 29.061664 -19.2151)
			(xy 29.062169 -19.187361) (xy 29.070214 -19.132468) (xy 29.086121 -19.079318) (xy 29.109554 -19.029031)
			(xy 29.140019 -18.982665) (xy 29.176876 -18.941198) (xy 29.219347 -18.905502) (xy 29.266538 -18.876331)
			(xy 29.291788 -18.864834) (xy 29.303472 -18.860008) (xy 29.318966 -18.840196) (xy 29.337254 -18.7452)
			(xy 29.339016 -18.73283) (xy 29.331693 -18.708974) (xy 29.323284 -18.699734) (xy 28.151836 -17.52854)
			(xy 28.14443 -17.521846) (xy 28.125994 -17.514244) (xy 28.116022 -17.513808) (xy 25.526746 -17.513808)
			(xy 25.497773 -17.513249) (xy 25.440546 -17.50414) (xy 25.38545 -17.486187) (xy 25.333843 -17.459832)
			(xy 25.286996 -17.425726) (xy 25.266142 -17.405604) (xy 24.885396 -17.024858) (xy 24.865272 -17.004007)
			(xy 24.831173 -16.957157) (xy 24.804825 -16.905548) (xy 24.786877 -16.850452) (xy 24.777771 -16.793226)
			(xy 24.777192 -16.764254) (xy 24.777192 -15.592298) (xy 24.775922 -15.586202) (xy 24.770602 -15.563523)
			(xy 24.764875 -15.517292) (xy 24.764492 -15.494) (xy 24.764978 -15.466749) (xy 24.772734 -15.412801)
			(xy 24.788089 -15.360506) (xy 24.810731 -15.310929) (xy 24.840197 -15.265079) (xy 24.875888 -15.223888)
			(xy 24.917079 -15.188197) (xy 24.962929 -15.158731) (xy 25.012506 -15.136089) (xy 25.064801 -15.120734)
			(xy 25.118749 -15.112978) (xy 25.173251 -15.112978) (xy 25.227199 -15.120734) (xy 25.279494 -15.136089)
			(xy 25.329071 -15.158731) (xy 25.374921 -15.188197) (xy 25.416112 -15.223888) (xy 25.451803 -15.265079)
			(xy 25.481269 -15.310929) (xy 25.503911 -15.360506) (xy 25.519266 -15.412801) (xy 25.527022 -15.466749)
			(xy 25.527508 -15.494) (xy 25.52713 -15.517292) (xy 25.521403 -15.563524) (xy 25.516078 -15.586202)
			(xy 25.514808 -15.592298) (xy 25.514808 -16.590518) (xy 25.515286 -16.600484) (xy 25.522862 -16.61892)
			(xy 25.52954 -16.626332) (xy 25.664668 -16.76146) (xy 25.672074 -16.768154) (xy 25.69051 -16.775754)
			(xy 25.700482 -16.776192) (xy 28.263596 -16.776192) (xy 28.273629 -16.775838) (xy 28.292197 -16.768244)
			(xy 28.306394 -16.754072) (xy 28.310586 -16.74495) (xy 28.316428 -16.730472) (xy 28.310586 -16.700754)
			(xy 26.598372 -14.98854) (xy 26.591001 -14.981798) (xy 26.572539 -14.974209) (xy 26.562558 -14.973808)
			(xy 25.46858 -14.973808) (xy 25.462484 -14.975078) (xy 25.439805 -14.980403) (xy 25.393574 -14.98614)
			(xy 25.370282 -14.986508) (xy 25.343032 -14.986021) (xy 25.289086 -14.978262) (xy 25.236793 -14.962906)
			(xy 25.187218 -14.940264) (xy 25.14137 -14.910797) (xy 25.100182 -14.875105) (xy 25.064492 -14.833915)
			(xy 25.035028 -14.788066) (xy 25.012388 -14.73849) (xy 24.997034 -14.686197) (xy 24.989278 -14.63225)
			(xy 24.989278 -14.57775) (xy 24.997034 -14.523803) (xy 25.012388 -14.47151) (xy 25.035028 -14.421934)
			(xy 25.064492 -14.376085) (xy 25.100182 -14.334895) (xy 25.14137 -14.299203) (xy 25.187218 -14.269736)
			(xy 25.236793 -14.247094) (xy 25.289086 -14.231738) (xy 25.343032 -14.223979) (xy 25.370282 -14.223492)
			(xy 25.393573 -14.223875) (xy 25.439803 -14.229611) (xy 25.462484 -14.234922) (xy 25.46858 -14.236192)
			(xy 26.736294 -14.236192) (xy 26.765266 -14.236754) (xy 26.82249 -14.245869) (xy 26.877582 -14.263826)
			(xy 26.929184 -14.290184) (xy 26.976026 -14.324294) (xy 26.996898 -14.344396) (xy 27.80785 -15.155348)
			(xy 30.479996 -15.155348) (xy 30.479996 -15.070652) (xy 30.488047 -14.986338) (xy 30.504076 -14.903172)
			(xy 30.527937 -14.821905) (xy 30.559416 -14.743275) (xy 30.598227 -14.667994) (xy 30.644017 -14.596742)
			(xy 30.696373 -14.530166) (xy 30.754821 -14.468868) (xy 30.818831 -14.413403) (xy 30.887823 -14.364274)
			(xy 30.961173 -14.321925) (xy 31.038216 -14.286741) (xy 31.118255 -14.259039) (xy 31.200564 -14.239071)
			(xy 31.284399 -14.227018) (xy 31.369 -14.222988) (xy 31.453601 -14.227018) (xy 31.537436 -14.239071)
			(xy 31.619745 -14.259039) (xy 31.699784 -14.286741) (xy 31.776827 -14.321925) (xy 31.850177 -14.364274)
			(xy 31.914289 -14.409928) (xy 42.1861 -14.409928) (xy 42.190144 -14.328898) (xy 42.202236 -14.248674)
			(xy 42.222255 -14.170052) (xy 42.250004 -14.093814) (xy 42.285205 -14.020718) (xy 42.327509 -13.95149)
			(xy 42.376496 -13.886818) (xy 42.431679 -13.827346) (xy 42.492509 -13.773663) (xy 42.558382 -13.726303)
			(xy 42.628643 -13.685738) (xy 42.702594 -13.65237) (xy 42.7795 -13.626531) (xy 42.858597 -13.608478)
			(xy 42.939098 -13.59839) (xy 43.020203 -13.596367) (xy 43.101107 -13.60243) (xy 43.181005 -13.616518)
			(xy 43.259103 -13.638491) (xy 43.334625 -13.668132) (xy 43.406821 -13.705144) (xy 43.474973 -13.749161)
			(xy 43.538403 -13.799746) (xy 43.596482 -13.856394) (xy 43.648632 -13.918544) (xy 43.694334 -13.985577)
			(xy 43.733135 -14.056827) (xy 43.764649 -14.131587) (xy 43.788563 -14.209113) (xy 43.804638 -14.288635)
			(xy 43.812716 -14.369363) (xy 43.813222 -14.409928) (xy 43.812716 -14.450493) (xy 43.804638 -14.531221)
			(xy 43.788563 -14.610743) (xy 43.764649 -14.688269) (xy 43.733135 -14.763029) (xy 43.694334 -14.834279)
			(xy 43.648632 -14.901312) (xy 43.596482 -14.963462) (xy 43.538403 -15.02011) (xy 43.474973 -15.070695)
			(xy 43.406821 -15.114712) (xy 43.334625 -15.151724) (xy 43.259103 -15.181365) (xy 43.181005 -15.203338)
			(xy 43.101107 -15.217426) (xy 43.020203 -15.223489) (xy 42.939098 -15.221466) (xy 42.858597 -15.211378)
			(xy 42.7795 -15.193325) (xy 42.702594 -15.167486) (xy 42.628643 -15.134118) (xy 42.558382 -15.093553)
			(xy 42.492509 -15.046193) (xy 42.431679 -14.99251) (xy 42.376496 -14.933038) (xy 42.327509 -14.868366)
			(xy 42.285205 -14.799138) (xy 42.250004 -14.726042) (xy 42.222255 -14.649804) (xy 42.202236 -14.571182)
			(xy 42.190144 -14.490958) (xy 42.1861 -14.409928) (xy 31.914289 -14.409928) (xy 31.919169 -14.413403)
			(xy 31.983179 -14.468868) (xy 32.041627 -14.530166) (xy 32.093983 -14.596742) (xy 32.139773 -14.667994)
			(xy 32.178584 -14.743275) (xy 32.210063 -14.821905) (xy 32.233924 -14.903172) (xy 32.249953 -14.986338)
			(xy 32.258004 -15.070652) (xy 32.258508 -15.113) (xy 32.258004 -15.155348) (xy 32.249953 -15.239662)
			(xy 32.233924 -15.322828) (xy 32.210063 -15.404095) (xy 32.178584 -15.482725) (xy 32.139773 -15.558006)
			(xy 32.093983 -15.629258) (xy 32.041627 -15.695834) (xy 31.983179 -15.757132) (xy 31.919169 -15.812597)
			(xy 31.850177 -15.861726) (xy 31.776827 -15.904075) (xy 31.699784 -15.939259) (xy 31.619745 -15.966961)
			(xy 31.537436 -15.986929) (xy 31.453601 -15.998982) (xy 31.369 -16.003013) (xy 31.284399 -15.998982)
			(xy 31.200564 -15.986929) (xy 31.118255 -15.966961) (xy 31.038216 -15.939259) (xy 30.961173 -15.904075)
			(xy 30.887823 -15.861726) (xy 30.818831 -15.812597) (xy 30.754821 -15.757132) (xy 30.696373 -15.695834)
			(xy 30.644017 -15.629258) (xy 30.598227 -15.558006) (xy 30.559416 -15.482725) (xy 30.527937 -15.404095)
			(xy 30.504076 -15.322828) (xy 30.488047 -15.239662) (xy 30.479996 -15.155348) (xy 27.80785 -15.155348)
			(xy 30.544516 -17.892014) (xy 34.034982 -17.892014) (xy 34.039053 -17.836392) (xy 34.051179 -17.781955)
			(xy 34.071102 -17.729864) (xy 34.098398 -17.681229) (xy 34.132484 -17.637086) (xy 34.172633 -17.598377)
			(xy 34.217991 -17.565926) (xy 34.267591 -17.540425) (xy 34.320375 -17.522418) (xy 34.375218 -17.512288)
			(xy 34.430952 -17.510251) (xy 34.486389 -17.516351) (xy 34.540346 -17.530457) (xy 34.591675 -17.552269)
			(xy 34.639281 -17.581323) (xy 34.682149 -17.616998) (xy 34.719366 -17.658535) (xy 34.750139 -17.705048)
			(xy 34.773811 -17.755545) (xy 34.789879 -17.808952) (xy 34.797999 -17.864128) (xy 34.798508 -17.892014)
			(xy 34.797999 -17.9199) (xy 34.789879 -17.975076) (xy 34.773811 -18.028483) (xy 34.750139 -18.07898)
			(xy 34.719366 -18.125493) (xy 34.682149 -18.16703) (xy 34.639281 -18.202705) (xy 34.591675 -18.231759)
			(xy 34.540346 -18.253571) (xy 34.486389 -18.267677) (xy 34.430952 -18.273777) (xy 34.375218 -18.27174)
			(xy 34.320375 -18.26161) (xy 34.267591 -18.243603) (xy 34.217991 -18.218102) (xy 34.172633 -18.185651)
			(xy 34.132484 -18.146942) (xy 34.098398 -18.102799) (xy 34.071102 -18.054164) (xy 34.051179 -18.002073)
			(xy 34.039053 -17.947636) (xy 34.034982 -17.892014) (xy 30.544516 -17.892014) (xy 31.062422 -18.40992)
			(xy 41.678035 -18.40992) (xy 41.682167 -18.305487) (xy 41.694539 -18.201706) (xy 41.715073 -18.099228)
			(xy 41.74364 -17.998693) (xy 41.780062 -17.90073) (xy 41.824111 -17.805951) (xy 41.875512 -17.714949)
			(xy 41.933943 -17.628293) (xy 41.999039 -17.546525) (xy 42.070392 -17.470157) (xy 42.147557 -17.399666)
			(xy 42.23005 -17.335492) (xy 42.317357 -17.278038) (xy 42.40893 -17.227663) (xy 42.456354 -17.205706)
			(xy 42.468292 -17.200118) (xy 42.48404 -17.17929) (xy 42.499026 -17.067784) (xy 42.489628 -17.0434)
			(xy 42.479468 -17.035018) (xy 42.449356 -17.009276) (xy 42.393697 -16.952897) (xy 42.343782 -16.891374)
			(xy 42.300084 -16.82529) (xy 42.263018 -16.755271) (xy 42.232934 -16.68198) (xy 42.210118 -16.606112)
			(xy 42.194785 -16.528386) (xy 42.187081 -16.449536) (xy 42.186606 -16.409924) (xy 42.187089 -16.369992)
			(xy 42.194915 -16.290512) (xy 42.210494 -16.212183) (xy 42.233676 -16.135757) (xy 42.264237 -16.061972)
			(xy 42.301883 -15.991538) (xy 42.346253 -15.925133) (xy 42.396917 -15.863397) (xy 42.453389 -15.806924)
			(xy 42.515125 -15.756259) (xy 42.581529 -15.711889) (xy 42.651963 -15.674241) (xy 42.725748 -15.643679)
			(xy 42.802173 -15.620496) (xy 42.880503 -15.604917) (xy 42.959982 -15.59709) (xy 42.999914 -15.596616)
			(xy 43.039527 -15.597095) (xy 43.118377 -15.604798) (xy 43.196106 -15.620128) (xy 43.271975 -15.642942)
			(xy 43.345269 -15.673023) (xy 43.415291 -15.710085) (xy 43.481378 -15.753779) (xy 43.542906 -15.80369)
			(xy 43.59929 -15.859345) (xy 43.625008 -15.889478) (xy 43.63339 -15.899638) (xy 43.657774 -15.909036)
			(xy 43.76928 -15.89405) (xy 43.790108 -15.878302) (xy 43.795696 -15.866364) (xy 43.818014 -15.818223)
			(xy 43.869291 -15.725312) (xy 43.927857 -15.636816) (xy 43.993333 -15.553302) (xy 44.065298 -15.475311)
			(xy 44.143288 -15.403345) (xy 44.226801 -15.337867) (xy 44.315297 -15.279301) (xy 44.408206 -15.228022)
			(xy 44.45635 -15.20571) (xy 44.468288 -15.200122) (xy 44.484036 -15.179294) (xy 44.499022 -15.067788)
			(xy 44.489624 -15.043404) (xy 44.479464 -15.035022) (xy 44.449353 -15.009279) (xy 44.393694 -14.9529)
			(xy 44.343779 -14.891377) (xy 44.300082 -14.825293) (xy 44.263015 -14.755274) (xy 44.232931 -14.681984)
			(xy 44.210115 -14.606116) (xy 44.194782 -14.528389) (xy 44.187077 -14.44954) (xy 44.186602 -14.409928)
			(xy 44.187092 -14.369997) (xy 44.19492 -14.290519) (xy 44.2105 -14.212191) (xy 44.233683 -14.135768)
			(xy 44.264245 -14.061984) (xy 44.301892 -13.991552) (xy 44.346261 -13.925149) (xy 44.396925 -13.863414)
			(xy 44.453396 -13.806943) (xy 44.515131 -13.756279) (xy 44.581534 -13.71191) (xy 44.651966 -13.674263)
			(xy 44.72575 -13.643701) (xy 44.802173 -13.620518) (xy 44.880501 -13.604938) (xy 44.959979 -13.59711)
			(xy 45.039841 -13.59711) (xy 45.119319 -13.604938) (xy 45.197647 -13.620518) (xy 45.27407 -13.643701)
			(xy 45.347854 -13.674263) (xy 45.418286 -13.71191) (xy 45.484689 -13.756279) (xy 45.546424 -13.806943)
			(xy 45.602895 -13.863414) (xy 45.653559 -13.925149) (xy 45.697928 -13.991552) (xy 45.735575 -14.061984)
			(xy 45.766137 -14.135768) (xy 45.78932 -14.212191) (xy 45.8049 -14.290519) (xy 45.812728 -14.369997)
			(xy 45.813218 -14.409928) (xy 45.812737 -14.449541) (xy 45.805033 -14.528391) (xy 45.789702 -14.606119)
			(xy 45.766888 -14.681988) (xy 45.736807 -14.755281) (xy 45.699745 -14.825303) (xy 45.656052 -14.891391)
			(xy 45.606142 -14.952918) (xy 45.550488 -15.009304) (xy 45.520356 -15.035022) (xy 45.510196 -15.043404)
			(xy 45.500798 -15.067788) (xy 45.515784 -15.179294) (xy 45.531532 -15.200122) (xy 45.54347 -15.20571)
			(xy 45.590897 -15.22766) (xy 45.68247 -15.278036) (xy 45.769777 -15.335491) (xy 45.85227 -15.399665)
			(xy 45.929435 -15.470156) (xy 46.000788 -15.546525) (xy 46.065883 -15.628293) (xy 46.124314 -15.714949)
			(xy 46.175715 -15.805951) (xy 46.219764 -15.90073) (xy 46.256186 -15.998694) (xy 46.284753 -16.099229)
			(xy 46.305287 -16.201708) (xy 46.317658 -16.305488) (xy 46.321791 -16.409922) (xy 46.317658 -16.514355)
			(xy 46.305286 -16.618136) (xy 46.284752 -16.720614) (xy 46.256185 -16.821149) (xy 46.219763 -16.919113)
			(xy 46.175713 -17.013892) (xy 46.124312 -17.104894) (xy 46.065881 -17.19155) (xy 46.000786 -17.273318)
			(xy 45.929432 -17.349686) (xy 45.852268 -17.420178) (xy 45.769774 -17.484351) (xy 45.682467 -17.541805)
			(xy 45.590894 -17.592181) (xy 45.54347 -17.614138) (xy 45.531532 -17.619726) (xy 45.515784 -17.640554)
			(xy 45.500798 -17.75206) (xy 45.510196 -17.776444) (xy 45.520356 -17.784826) (xy 45.550495 -17.810538)
			(xy 45.606152 -17.866922) (xy 45.656065 -17.928449) (xy 45.69976 -17.994537) (xy 45.736823 -18.06456)
			(xy 45.766903 -18.137854) (xy 45.789716 -18.213725) (xy 45.805045 -18.291455) (xy 45.812745 -18.370307)
			(xy 45.813218 -18.40992) (xy 45.812737 -18.449851) (xy 45.804908 -18.529329) (xy 45.789326 -18.607657)
			(xy 45.766141 -18.68408) (xy 45.735578 -18.757863) (xy 45.69793 -18.828295) (xy 45.65356 -18.894697)
			(xy 45.602896 -18.956432) (xy 45.546424 -19.012902) (xy 45.484689 -19.063566) (xy 45.418286 -19.107936)
			(xy 45.347854 -19.145583) (xy 45.27407 -19.176145) (xy 45.197647 -19.199328) (xy 45.119319 -19.214909)
			(xy 45.039841 -19.222738) (xy 44.99991 -19.223228) (xy 44.960298 -19.222716) (xy 44.881449 -19.215016)
			(xy 44.803722 -19.199689) (xy 44.727853 -19.176878) (xy 44.65456 -19.146802) (xy 44.584538 -19.109743)
			(xy 44.51845 -19.066054) (xy 44.456921 -19.016147) (xy 44.400535 -18.960497) (xy 44.374816 -18.930366)
			(xy 44.366434 -18.920206) (xy 44.34205 -18.910808) (xy 44.230544 -18.925794) (xy 44.209716 -18.941542)
			(xy 44.204128 -18.95348) (xy 44.181818 -19.001625) (xy 44.130539 -19.094534) (xy 44.071972 -19.18303)
			(xy 44.006494 -19.266543) (xy 43.934528 -19.344533) (xy 43.856537 -19.416499) (xy 43.773024 -19.481977)
			(xy 43.684528 -19.540543) (xy 43.591618 -19.591822) (xy 43.543474 -19.614134) (xy 43.531536 -19.619722)
			(xy 43.515788 -19.64055) (xy 43.500802 -19.752056) (xy 43.5102 -19.77644) (xy 43.52036 -19.784822)
			(xy 43.550498 -19.810535) (xy 43.606155 -19.866919) (xy 43.656067 -19.928446) (xy 43.699762 -19.994534)
			(xy 43.736826 -20.064557) (xy 43.766906 -20.137851) (xy 43.789719 -20.213722) (xy 43.805049 -20.291451)
			(xy 43.812749 -20.370303) (xy 43.813222 -20.409916) (xy 43.812732 -20.449847) (xy 43.804904 -20.529325)
			(xy 43.789324 -20.607653) (xy 43.766141 -20.684076) (xy 43.735579 -20.75786) (xy 43.697932 -20.828292)
			(xy 43.653563 -20.894695) (xy 43.602899 -20.95643) (xy 43.546428 -21.012901) (xy 43.484693 -21.063565)
			(xy 43.41829 -21.107934) (xy 43.347858 -21.145581) (xy 43.274074 -21.176143) (xy 43.197651 -21.199326)
			(xy 43.119323 -21.214906) (xy 43.039845 -21.222734) (xy 42.959983 -21.222734) (xy 42.880505 -21.214906)
			(xy 42.802177 -21.199326) (xy 42.725754 -21.176143) (xy 42.65197 -21.145581) (xy 42.581538 -21.107934)
			(xy 42.515135 -21.063565) (xy 42.4534 -21.012901) (xy 42.396929 -20.95643) (xy 42.346265 -20.894695)
			(xy 42.301896 -20.828292) (xy 42.264249 -20.75786) (xy 42.233687 -20.684076) (xy 42.210504 -20.607653)
			(xy 42.194924 -20.529325) (xy 42.187096 -20.449847) (xy 42.186606 -20.409916) (xy 42.18711 -20.370304)
			(xy 42.19481 -20.291454) (xy 42.210138 -20.213727) (xy 42.232948 -20.137857) (xy 42.263026 -20.064564)
			(xy 42.300085 -19.994542) (xy 42.343776 -19.928454) (xy 42.393684 -19.866926) (xy 42.449336 -19.81054)
			(xy 42.479468 -19.784822) (xy 42.489628 -19.77644) (xy 42.499026 -19.752056) (xy 42.48404 -19.64055)
			(xy 42.468292 -19.619722) (xy 42.456354 -19.614134) (xy 42.40893 -19.592177) (xy 42.317357 -19.541802)
			(xy 42.23005 -19.484348) (xy 42.147557 -19.420174) (xy 42.070392 -19.349683) (xy 41.999039 -19.273315)
			(xy 41.933943 -19.191547) (xy 41.875512 -19.104891) (xy 41.824111 -19.013889) (xy 41.780062 -18.91911)
			(xy 41.74364 -18.821147) (xy 41.715073 -18.720612) (xy 41.694539 -18.618134) (xy 41.682167 -18.514353)
			(xy 41.678035 -18.40992) (xy 31.062422 -18.40992) (xy 31.15056 -18.498058) (xy 31.170685 -18.518908)
			(xy 31.204786 -18.565758) (xy 31.231135 -18.617367) (xy 31.249083 -18.672463) (xy 31.258188 -18.729689)
			(xy 31.258764 -18.758662) (xy 31.258764 -18.94205) (xy 35.685982 -18.94205) (xy 35.690053 -18.886428)
			(xy 35.702179 -18.831991) (xy 35.722102 -18.7799) (xy 35.749398 -18.731265) (xy 35.783484 -18.687122)
			(xy 35.823633 -18.648413) (xy 35.868991 -18.615962) (xy 35.918591 -18.590461) (xy 35.971375 -18.572454)
			(xy 36.026218 -18.562324) (xy 36.081952 -18.560287) (xy 36.137389 -18.566387) (xy 36.191346 -18.580493)
			(xy 36.242675 -18.602305) (xy 36.290281 -18.631359) (xy 36.333149 -18.667034) (xy 36.370366 -18.708571)
			(xy 36.401139 -18.755084) (xy 36.424811 -18.805581) (xy 36.440879 -18.858988) (xy 36.448999 -18.914164)
			(xy 36.449508 -18.94205) (xy 36.448999 -18.969936) (xy 36.440879 -19.025112) (xy 36.424811 -19.078519)
			(xy 36.401139 -19.129016) (xy 36.370366 -19.175529) (xy 36.333149 -19.217066) (xy 36.290281 -19.252741)
			(xy 36.242675 -19.281795) (xy 36.191346 -19.303607) (xy 36.137389 -19.317713) (xy 36.081952 -19.323813)
			(xy 36.026218 -19.321776) (xy 35.971375 -19.311646) (xy 35.918591 -19.293639) (xy 35.868991 -19.268138)
			(xy 35.823633 -19.235687) (xy 35.783484 -19.196978) (xy 35.749398 -19.152835) (xy 35.722102 -19.1042)
			(xy 35.702179 -19.052109) (xy 35.690053 -18.997672) (xy 35.685982 -18.94205) (xy 31.258764 -18.94205)
			(xy 31.258764 -19.03222) (xy 31.259241 -19.042187) (xy 31.266813 -19.060626) (xy 31.273496 -19.068034)
			(xy 31.751524 -19.546062) (xy 31.760585 -19.554127) (xy 31.783651 -19.56153) (xy 31.79572 -19.560286)
			(xy 31.8897 -19.544284) (xy 31.909258 -19.529806) (xy 31.914592 -19.51863) (xy 31.926656 -19.494795)
			(xy 31.956451 -19.450455) (xy 31.992134 -19.4107) (xy 32.033008 -19.376304) (xy 32.078277 -19.34794)
			(xy 32.127056 -19.326161) (xy 32.178394 -19.311391) (xy 32.23129 -19.303919) (xy 32.258 -19.303492)
			(xy 32.281292 -19.30387) (xy 32.327524 -19.309597) (xy 32.350202 -19.314922) (xy 32.356298 -19.316192)
			(xy 32.36595 -19.316192) (xy 32.394923 -19.316751) (xy 32.452151 -19.325859) (xy 32.507247 -19.343812)
			(xy 32.558855 -19.370166) (xy 32.605702 -19.404272) (xy 32.626554 -19.424396) (xy 33.1851 -19.982942)
			(xy 33.205224 -20.003792) (xy 33.239323 -20.050643) (xy 33.265671 -20.102252) (xy 33.28362 -20.157348)
			(xy 33.292726 -20.214574) (xy 33.293304 -20.243546) (xy 33.293304 -20.279868) (xy 35.87064 -20.279868)
			(xy 35.874711 -20.224246) (xy 35.886837 -20.169809) (xy 35.90676 -20.117718) (xy 35.934056 -20.069083)
			(xy 35.968142 -20.02494) (xy 36.008291 -19.986231) (xy 36.053649 -19.95378) (xy 36.103249 -19.928279)
			(xy 36.156033 -19.910272) (xy 36.210876 -19.900142) (xy 36.26661 -19.898105) (xy 36.322047 -19.904205)
			(xy 36.376004 -19.918311) (xy 36.427333 -19.940123) (xy 36.474939 -19.969177) (xy 36.517807 -20.004852)
			(xy 36.555024 -20.046389) (xy 36.585797 -20.092902) (xy 36.609469 -20.143399) (xy 36.625537 -20.196806)
			(xy 36.633657 -20.251982) (xy 36.634166 -20.279868) (xy 36.633657 -20.307754) (xy 36.625537 -20.36293)
			(xy 36.609469 -20.416337) (xy 36.585797 -20.466834) (xy 36.555024 -20.513347) (xy 36.517807 -20.554884)
			(xy 36.474939 -20.590559) (xy 36.427333 -20.619613) (xy 36.376004 -20.641425) (xy 36.322047 -20.655531)
			(xy 36.26661 -20.661631) (xy 36.210876 -20.659594) (xy 36.156033 -20.649464) (xy 36.103249 -20.631457)
			(xy 36.053649 -20.605956) (xy 36.008291 -20.573505) (xy 35.968142 -20.534796) (xy 35.934056 -20.490653)
			(xy 35.90676 -20.442018) (xy 35.886837 -20.389927) (xy 35.874711 -20.33549) (xy 35.87064 -20.279868)
			(xy 33.293304 -20.279868) (xy 33.293304 -22.449832) (xy 42.187078 -22.449832) (xy 42.187078 -22.369968)
			(xy 42.194906 -22.290489) (xy 42.210487 -22.21216) (xy 42.233671 -22.135735) (xy 42.264233 -22.061951)
			(xy 42.301881 -21.991518) (xy 42.346251 -21.925114) (xy 42.396917 -21.863379) (xy 42.453389 -21.806907)
			(xy 42.515125 -21.756243) (xy 42.58153 -21.711874) (xy 42.651964 -21.674227) (xy 42.725749 -21.643666)
			(xy 42.802174 -21.620484) (xy 42.880503 -21.604904) (xy 42.959982 -21.597078) (xy 42.999914 -21.596604)
			(xy 43.039527 -21.597087) (xy 43.118377 -21.60479) (xy 43.196105 -21.62012) (xy 43.271975 -21.642934)
			(xy 43.345268 -21.673014) (xy 43.41529 -21.710076) (xy 43.481377 -21.753769) (xy 43.542905 -21.803679)
			(xy 43.59929 -21.859333) (xy 43.625008 -21.889466) (xy 43.63339 -21.899626) (xy 43.657774 -21.909024)
			(xy 43.76928 -21.894038) (xy 43.790108 -21.87829) (xy 43.795696 -21.866352) (xy 43.818009 -21.818208)
			(xy 43.869287 -21.725298) (xy 43.927853 -21.636802) (xy 43.99333 -21.553289) (xy 44.065296 -21.475298)
			(xy 44.143287 -21.403332) (xy 44.2268 -21.337855) (xy 44.315296 -21.279288) (xy 44.408206 -21.22801)
			(xy 44.45635 -21.205698) (xy 44.468288 -21.20011) (xy 44.484036 -21.179282) (xy 44.499022 -21.067776)
			(xy 44.489624 -21.043392) (xy 44.479464 -21.03501) (xy 44.449347 -21.009273) (xy 44.393688 -20.952893)
			(xy 44.343774 -20.89137) (xy 44.300077 -20.825285) (xy 44.263011 -20.755265) (xy 44.232928 -20.681974)
			(xy 44.210112 -20.606105) (xy 44.19478 -20.528378) (xy 44.187077 -20.449529) (xy 44.186602 -20.409916)
			(xy 44.187092 -20.369985) (xy 44.19492 -20.290507) (xy 44.2105 -20.212179) (xy 44.233683 -20.135756)
			(xy 44.264245 -20.061972) (xy 44.301892 -19.99154) (xy 44.346261 -19.925137) (xy 44.396925 -19.863402)
			(xy 44.453396 -19.806931) (xy 44.515131 -19.756267) (xy 44.581534 -19.711898) (xy 44.651966 -19.674251)
			(xy 44.72575 -19.643689) (xy 44.802173 -19.620506) (xy 44.880501 -19.604926) (xy 44.959979 -19.597098)
			(xy 45.039841 -19.597098) (xy 45.119319 -19.604926) (xy 45.197647 -19.620506) (xy 45.27407 -19.643689)
			(xy 45.347854 -19.674251) (xy 45.418286 -19.711898) (xy 45.484689 -19.756267) (xy 45.546424 -19.806931)
			(xy 45.602895 -19.863402) (xy 45.653559 -19.925137) (xy 45.697928 -19.99154) (xy 45.735575 -20.061972)
			(xy 45.766137 -20.135756) (xy 45.78932 -20.212179) (xy 45.8049 -20.290507) (xy 45.812728 -20.369985)
			(xy 45.813218 -20.409916) (xy 45.812728 -20.449528) (xy 45.805026 -20.528378) (xy 45.789696 -20.606106)
			(xy 45.766883 -20.681975) (xy 45.736803 -20.755268) (xy 45.699742 -20.82529) (xy 45.65605 -20.891378)
			(xy 45.606141 -20.952906) (xy 45.550488 -21.009292) (xy 45.520356 -21.03501) (xy 45.510196 -21.043392)
			(xy 45.500798 -21.067776) (xy 45.515784 -21.179282) (xy 45.531532 -21.20011) (xy 45.54347 -21.205698)
			(xy 45.590895 -21.227652) (xy 45.682468 -21.278028) (xy 45.769775 -21.335482) (xy 45.852268 -21.399655)
			(xy 45.929433 -21.470147) (xy 46.000786 -21.546515) (xy 46.065881 -21.628283) (xy 46.124312 -21.714939)
			(xy 46.175713 -21.805941) (xy 46.219762 -21.90072) (xy 46.256184 -21.998684) (xy 46.284751 -22.099219)
			(xy 46.305285 -22.201697) (xy 46.317656 -22.305477) (xy 46.321789 -22.409911) (xy 46.317656 -22.514344)
			(xy 46.305284 -22.618124) (xy 46.284751 -22.720603) (xy 46.256183 -22.821138) (xy 46.219761 -22.919101)
			(xy 46.175712 -23.01388) (xy 46.124311 -23.104882) (xy 46.06588 -23.191538) (xy 46.000785 -23.273306)
			(xy 45.929432 -23.349674) (xy 45.852267 -23.420166) (xy 45.769774 -23.484339) (xy 45.682467 -23.541793)
			(xy 45.590894 -23.592169) (xy 45.54347 -23.614126) (xy 45.531532 -23.619714) (xy 45.515784 -23.640542)
			(xy 45.500798 -23.752048) (xy 45.510196 -23.776432) (xy 45.520356 -23.784814) (xy 45.550489 -23.810532)
			(xy 45.606147 -23.866915) (xy 45.656059 -23.928442) (xy 45.699755 -23.994529) (xy 45.736819 -24.064551)
			(xy 45.7669 -24.137844) (xy 45.789713 -24.213715) (xy 45.805043 -24.291444) (xy 45.812744 -24.370295)
			(xy 45.813218 -24.409908) (xy 45.812728 -24.449839) (xy 45.8049 -24.529317) (xy 45.78932 -24.607645)
			(xy 45.766137 -24.684068) (xy 45.735575 -24.757852) (xy 45.697928 -24.828284) (xy 45.653559 -24.894687)
			(xy 45.602895 -24.956422) (xy 45.546424 -25.012893) (xy 45.484689 -25.063557) (xy 45.418286 -25.107926)
			(xy 45.347854 -25.145573) (xy 45.27407 -25.176135) (xy 45.197647 -25.199318) (xy 45.119319 -25.214898)
			(xy 45.039841 -25.222726) (xy 44.959979 -25.222726) (xy 44.880501 -25.214898) (xy 44.802173 -25.199318)
			(xy 44.72575 -25.176135) (xy 44.651966 -25.145573) (xy 44.581534 -25.107926) (xy 44.515131 -25.063557)
			(xy 44.453396 -25.012893) (xy 44.396925 -24.956422) (xy 44.346261 -24.894687) (xy 44.301892 -24.828284)
			(xy 44.264245 -24.757852) (xy 44.233683 -24.684068) (xy 44.2105 -24.607645) (xy 44.19492 -24.529317)
			(xy 44.187092 -24.449839) (xy 44.186602 -24.409908) (xy 44.187102 -24.370296) (xy 44.194802 -24.291446)
			(xy 44.210131 -24.213719) (xy 44.232942 -24.137849) (xy 44.26302 -24.064556) (xy 44.30008 -23.994534)
			(xy 44.343771 -23.928446) (xy 44.393679 -23.866918) (xy 44.449332 -23.810532) (xy 44.479464 -23.784814)
			(xy 44.489624 -23.776432) (xy 44.499022 -23.752048) (xy 44.484036 -23.640542) (xy 44.468288 -23.619714)
			(xy 44.45635 -23.614126) (xy 44.40821 -23.591804) (xy 44.315301 -23.540527) (xy 44.226804 -23.481962)
			(xy 44.143291 -23.416486) (xy 44.0653 -23.344521) (xy 43.993333 -23.266531) (xy 43.927855 -23.18302)
			(xy 43.869288 -23.094524) (xy 43.818009 -23.001616) (xy 43.795696 -22.953472) (xy 43.790108 -22.941534)
			(xy 43.76928 -22.925786) (xy 43.657774 -22.9108) (xy 43.63339 -22.920198) (xy 43.625008 -22.930358)
			(xy 43.599278 -22.960481) (xy 43.542897 -23.016139) (xy 43.481372 -23.066052) (xy 43.415286 -23.109748)
			(xy 43.345266 -23.146813) (xy 43.271974 -23.176896) (xy 43.196104 -23.199711) (xy 43.118377 -23.215042)
			(xy 43.039527 -23.222745) (xy 42.999914 -23.22322) (xy 42.959982 -23.222722) (xy 42.880503 -23.214896)
			(xy 42.802174 -23.199316) (xy 42.725749 -23.176134) (xy 42.651964 -23.145573) (xy 42.58153 -23.107926)
			(xy 42.515125 -23.063557) (xy 42.453389 -23.012893) (xy 42.396917 -22.956421) (xy 42.346251 -22.894686)
			(xy 42.301881 -22.828282) (xy 42.264233 -22.757849) (xy 42.233671 -22.684065) (xy 42.210487 -22.60764)
			(xy 42.194906 -22.529311) (xy 42.187078 -22.449832) (xy 33.293304 -22.449832) (xy 33.293304 -23.29434)
			(xy 33.293665 -23.304369) (xy 33.301269 -23.322923) (xy 33.315442 -23.337108) (xy 33.324546 -23.34133)
			(xy 33.339024 -23.347172) (xy 33.368742 -23.34133) (xy 33.749234 -22.961092) (xy 33.770085 -22.940968)
			(xy 33.816935 -22.906869) (xy 33.868544 -22.88052) (xy 33.92364 -22.862571) (xy 33.980865 -22.853463)
			(xy 34.009838 -22.852888) (xy 36.556696 -22.852888) (xy 36.585668 -22.853451) (xy 36.642891 -22.862565)
			(xy 36.697983 -22.880522) (xy 36.749586 -22.906881) (xy 36.796428 -22.94099) (xy 36.8173 -22.961092)
			(xy 38.360604 -24.504396) (xy 38.380731 -24.525246) (xy 38.414835 -24.572095) (xy 38.441189 -24.623703)
			(xy 38.459144 -24.678799) (xy 38.468258 -24.736026) (xy 38.468808 -24.765) (xy 38.468808 -28.297124)
			(xy 38.469167 -28.307154) (xy 38.476767 -28.325713) (xy 38.49094 -28.339902) (xy 38.50005 -28.344114)
			(xy 38.514528 -28.349956) (xy 38.544246 -28.344114) (xy 42.2148 -24.67356) (xy 42.221658 -24.64689)
			(xy 42.217848 -24.633428) (xy 42.207898 -24.597016) (xy 42.19399 -24.522819) (xy 42.18702 -24.447653)
			(xy 42.186606 -24.409908) (xy 42.187095 -24.369978) (xy 42.194922 -24.290501) (xy 42.210502 -24.212175)
			(xy 42.233683 -24.135752) (xy 42.264244 -24.06197) (xy 42.301889 -23.991539) (xy 42.346257 -23.925136)
			(xy 42.396919 -23.863402) (xy 42.453389 -23.806932) (xy 42.515122 -23.756268) (xy 42.581523 -23.711899)
			(xy 42.651954 -23.674252) (xy 42.725735 -23.643689) (xy 42.802157 -23.620506) (xy 42.880483 -23.604925)
			(xy 42.95996 -23.597096) (xy 43.03982 -23.597095) (xy 43.119297 -23.604922) (xy 43.197623 -23.620501)
			(xy 43.274046 -23.643683) (xy 43.347828 -23.674243) (xy 43.41826 -23.711888) (xy 43.484662 -23.756256)
			(xy 43.546396 -23.806918) (xy 43.602867 -23.863388) (xy 43.653531 -23.92512) (xy 43.6979 -23.991521)
			(xy 43.735548 -24.061952) (xy 43.76611 -24.135733) (xy 43.789294 -24.212155) (xy 43.804875 -24.290481)
			(xy 43.812704 -24.369958) (xy 43.812705 -24.449818) (xy 43.804878 -24.529295) (xy 43.789299 -24.607622)
			(xy 43.766118 -24.684044) (xy 43.735558 -24.757826) (xy 43.697913 -24.828258) (xy 43.653545 -24.894661)
			(xy 43.602883 -24.956395) (xy 43.546414 -25.012866) (xy 43.484681 -25.06353) (xy 43.41828 -25.107899)
			(xy 43.34785 -25.145547) (xy 43.274069 -25.176109) (xy 43.197647 -25.199293) (xy 43.119321 -25.214874)
			(xy 43.039844 -25.222704) (xy 42.999914 -25.223216) (xy 42.96217 -25.222798) (xy 42.887004 -25.215823)
			(xy 42.812808 -25.201914) (xy 42.776394 -25.191974) (xy 42.762932 -25.188164) (xy 42.736262 -25.195022)
			(xy 41.561309 -26.369975) (xy 42.187052 -26.369975) (xy 42.194879 -26.290494) (xy 42.21046 -26.212163)
			(xy 42.233643 -26.135736) (xy 42.264206 -26.061949) (xy 42.301853 -25.991514) (xy 42.346224 -25.925108)
			(xy 42.39689 -25.86337) (xy 42.453363 -25.806896) (xy 42.5151 -25.75623) (xy 42.581505 -25.711859)
			(xy 42.65194 -25.67421) (xy 42.725726 -25.643646) (xy 42.802153 -25.620462) (xy 42.880484 -25.604881)
			(xy 42.959965 -25.597052) (xy 43.039831 -25.597052) (xy 43.119312 -25.60488) (xy 43.197643 -25.620461)
			(xy 43.27407 -25.643645) (xy 43.347856 -25.674208) (xy 43.418291 -25.711856) (xy 43.484697 -25.756227)
			(xy 43.546434 -25.806894) (xy 43.602908 -25.863367) (xy 43.653574 -25.925104) (xy 43.697945 -25.99151)
			(xy 43.735593 -26.061946) (xy 43.766156 -26.135732) (xy 43.789339 -26.212159) (xy 43.80492 -26.29049)
			(xy 43.812748 -26.369971) (xy 43.813222 -26.409904) (xy 43.812786 -26.449034) (xy 43.805267 -26.526933)
			(xy 43.7903 -26.603749) (xy 43.768023 -26.678772) (xy 43.738642 -26.751309) (xy 43.702429 -26.820687)
			(xy 43.659718 -26.886265) (xy 43.635676 -26.917142) (xy 43.625516 -26.929842) (xy 43.623484 -26.961846)
			(xy 43.691048 -27.070812) (xy 43.720512 -27.083258) (xy 43.73626 -27.079956) (xy 43.788329 -27.069362)
			(xy 43.893742 -27.055933) (xy 43.999912 -27.051446) (xy 44.106082 -27.055933) (xy 44.211495 -27.069362)
			(xy 44.263564 -27.079956) (xy 44.279312 -27.083258) (xy 44.308776 -27.070812) (xy 44.37634 -26.961846)
			(xy 44.374308 -26.929842) (xy 44.364148 -26.917142) (xy 44.340103 -26.886268) (xy 44.297401 -26.820686)
			(xy 44.261195 -26.751306) (xy 44.231821 -26.678769) (xy 44.209548 -26.603746) (xy 44.194585 -26.526931)
			(xy 44.187068 -26.449034) (xy 44.186602 -26.409904) (xy 44.187078 -26.369973) (xy 44.194905 -26.290495)
			(xy 44.210485 -26.212166) (xy 44.233668 -26.135742) (xy 44.264229 -26.061959) (xy 44.301876 -25.991526)
			(xy 44.346245 -25.925122) (xy 44.396909 -25.863387) (xy 44.45338 -25.806916) (xy 44.515114 -25.756251)
			(xy 44.581517 -25.711881) (xy 44.65195 -25.674234) (xy 44.725733 -25.643671) (xy 44.802157 -25.620488)
			(xy 44.880485 -25.604907) (xy 44.959963 -25.597078) (xy 45.039825 -25.597077) (xy 45.119304 -25.604905)
			(xy 45.197632 -25.620485) (xy 45.274056 -25.643667) (xy 45.347839 -25.674228) (xy 45.418272 -25.711875)
			(xy 45.484676 -25.756244) (xy 45.546411 -25.806907) (xy 45.602883 -25.863378) (xy 45.653548 -25.925113)
			(xy 45.697918 -25.991516) (xy 45.735566 -26.061948) (xy 45.766128 -26.135731) (xy 45.789312 -26.212155)
			(xy 45.804893 -26.290483) (xy 45.812722 -26.369961) (xy 45.812723 -26.449823) (xy 45.804896 -26.529302)
			(xy 45.789316 -26.60763) (xy 45.766134 -26.684054) (xy 45.735572 -26.757838) (xy 45.697926 -26.828271)
			(xy 45.653558 -26.894675) (xy 45.602894 -26.95641) (xy 45.546423 -27.012882) (xy 45.484689 -27.063547)
			(xy 45.418286 -27.107917) (xy 45.347854 -27.145565) (xy 45.274071 -27.176128) (xy 45.197647 -27.199312)
			(xy 45.119319 -27.214893) (xy 45.039841 -27.222722) (xy 44.99991 -27.223212) (xy 44.985356 -27.223155)
			(xy 44.956266 -27.222141) (xy 44.941744 -27.22118) (xy 44.925488 -27.21991) (xy 44.898056 -27.23642)
			(xy 44.846494 -27.353768) (xy 44.852844 -27.38501) (xy 44.864528 -27.396186) (xy 44.90049 -27.430901)
			(xy 44.967413 -27.505157) (xy 45.028231 -27.584492) (xy 45.08256 -27.668403) (xy 45.130057 -27.756362)
			(xy 45.170422 -27.847813) (xy 45.203401 -27.94218) (xy 45.228785 -28.038867) (xy 45.246415 -28.137263)
			(xy 45.256179 -28.236749) (xy 45.258016 -28.336696) (xy 45.251913 -28.436473) (xy 45.23791 -28.535451)
			(xy 45.216095 -28.633005) (xy 45.186605 -28.728519) (xy 45.149627 -28.821392) (xy 45.105394 -28.911037)
			(xy 45.054185 -28.996887) (xy 44.996323 -29.078402) (xy 44.932173 -29.155067) (xy 44.862141 -29.226398)
			(xy 44.786667 -29.291946) (xy 44.706229 -29.351296) (xy 44.621334 -29.404074) (xy 44.532517 -29.449946)
			(xy 44.440339 -29.488625) (xy 44.345383 -29.519864) (xy 44.248246 -29.543468) (xy 44.149542 -29.559287)
			(xy 44.049894 -29.567222) (xy 43.94993 -29.567222) (xy 43.850282 -29.559287) (xy 43.751578 -29.543468)
			(xy 43.654441 -29.519864) (xy 43.559485 -29.488625) (xy 43.467307 -29.449946) (xy 43.37849 -29.404074)
			(xy 43.293595 -29.351296) (xy 43.213157 -29.291946) (xy 43.137683 -29.226398) (xy 43.067651 -29.155067)
			(xy 43.003501 -29.078402) (xy 42.945639 -28.996887) (xy 42.89443 -28.911037) (xy 42.850197 -28.821392)
			(xy 42.813219 -28.728519) (xy 42.783729 -28.633005) (xy 42.761914 -28.535451) (xy 42.747911 -28.436473)
			(xy 42.741808 -28.336696) (xy 42.743645 -28.236749) (xy 42.753409 -28.137263) (xy 42.771039 -28.038867)
			(xy 42.796423 -27.94218) (xy 42.829402 -27.847813) (xy 42.869767 -27.756362) (xy 42.917264 -27.668403)
			(xy 42.971593 -27.584492) (xy 43.032411 -27.505157) (xy 43.099334 -27.430901) (xy 43.135296 -27.396186)
			(xy 43.14698 -27.38501) (xy 43.15333 -27.353768) (xy 43.101768 -27.23642) (xy 43.074336 -27.21991)
			(xy 43.05808 -27.22118) (xy 43.043558 -27.222145) (xy 43.014468 -27.223161) (xy 42.999914 -27.223212)
			(xy 42.959981 -27.222748) (xy 42.8805 -27.214922) (xy 42.802169 -27.199342) (xy 42.725742 -27.176159)
			(xy 42.651955 -27.145597) (xy 42.581519 -27.10795) (xy 42.515113 -27.06358) (xy 42.453375 -27.012914)
			(xy 42.3969 -26.956441) (xy 42.346233 -26.894705) (xy 42.301862 -26.8283) (xy 42.264212 -26.757865)
			(xy 42.233648 -26.684079) (xy 42.210464 -26.607653) (xy 42.194882 -26.529322) (xy 42.187053 -26.449841)
			(xy 42.187052 -26.369975) (xy 41.561309 -26.369975) (xy 39.11854 -28.812744) (xy 39.111843 -28.820149)
			(xy 39.104234 -28.838585) (xy 39.103808 -28.848558) (xy 39.103808 -34.4678) (xy 39.103253 -34.496775)
			(xy 39.094151 -34.554006) (xy 39.076205 -34.609107) (xy 39.049855 -34.660721) (xy 39.015751 -34.707574)
			(xy 38.995604 -34.728404) (xy 37.528754 -36.195508) (xy 37.521587 -36.20338) (xy 37.513857 -36.223188)
			(xy 37.514836 -36.244428) (xy 37.519102 -36.254182) (xy 37.569394 -36.35502) (xy 37.59835 -36.37026)
			(xy 37.614606 -36.367974) (xy 37.64537 -36.363921) (xy 37.707276 -36.359602) (xy 37.738304 -36.359338)
			(xy 37.7847 -36.359923) (xy 37.87699 -36.369557) (xy 37.967775 -36.388752) (xy 38.056066 -36.417297)
			(xy 38.09873 -36.435538) (xy 38.10867 -36.439358) (xy 38.129938 -36.439358) (xy 38.139878 -36.435538)
			(xy 38.182543 -36.417299) (xy 38.270836 -36.38876) (xy 38.36162 -36.369564) (xy 38.453908 -36.359918)
			(xy 38.500304 -36.359338) (xy 38.5467 -36.359923) (xy 38.63899 -36.369557) (xy 38.729775 -36.388752)
			(xy 38.818066 -36.417297) (xy 38.86073 -36.435538) (xy 38.87067 -36.439358) (xy 38.891938 -36.439358)
			(xy 38.901878 -36.435538) (xy 38.944543 -36.417299) (xy 39.032836 -36.38876) (xy 39.12362 -36.369564)
			(xy 39.215908 -36.359918) (xy 39.262304 -36.359338) (xy 39.303406 -36.359798) (xy 39.38526 -36.367384)
			(xy 39.466065 -36.38249) (xy 39.545131 -36.404987) (xy 39.621784 -36.434684) (xy 39.69537 -36.471327)
			(xy 39.765261 -36.514604) (xy 39.83086 -36.564144) (xy 39.891608 -36.619527) (xy 39.946987 -36.680278)
			(xy 39.996525 -36.745881) (xy 40.039797 -36.815774) (xy 40.076436 -36.889362) (xy 40.106129 -36.966016)
			(xy 40.128622 -37.045084) (xy 40.143723 -37.125889) (xy 40.151304 -37.207744) (xy 40.151812 -37.248846)
			(xy 40.151404 -37.287136) (xy 40.144799 -37.36343) (xy 40.131652 -37.438873) (xy 40.11206 -37.512905)
			(xy 40.099488 -37.549074) (xy 40.096855 -37.557512) (xy 40.09687 -37.575174) (xy 40.099488 -37.583618)
			(xy 40.112033 -37.619796) (xy 40.13161 -37.693828) (xy 40.144759 -37.769268) (xy 40.151381 -37.845558)
			(xy 40.151812 -37.883846) (xy 40.151335 -37.924947) (xy 40.143747 -38.006799) (xy 40.128638 -38.087601)
			(xy 40.106139 -38.166664) (xy 40.076441 -38.243314) (xy 40.039798 -38.316898) (xy 39.996522 -38.386786)
			(xy 39.946982 -38.452384) (xy 39.891601 -38.513131) (xy 39.830851 -38.568509) (xy 39.765252 -38.618046)
			(xy 39.695361 -38.661318) (xy 39.621776 -38.697958) (xy 39.545124 -38.727653) (xy 39.46606 -38.750148)
			(xy 39.385257 -38.765252) (xy 39.303405 -38.772837) (xy 39.262304 -38.773354) (xy 39.215908 -38.772769)
			(xy 39.123618 -38.763136) (xy 39.032833 -38.743942) (xy 38.944541 -38.715397) (xy 38.901878 -38.697154)
			(xy 38.891938 -38.693334) (xy 38.87067 -38.693334) (xy 38.86073 -38.697154) (xy 38.818066 -38.715393)
			(xy 38.729772 -38.743933) (xy 38.638988 -38.763131) (xy 38.5467 -38.772777) (xy 38.500304 -38.773354)
			(xy 38.453908 -38.772769) (xy 38.361618 -38.763136) (xy 38.270833 -38.743942) (xy 38.182541 -38.715397)
			(xy 38.139878 -38.697154) (xy 38.129938 -38.693334) (xy 38.10867 -38.693334) (xy 38.09873 -38.697154)
			(xy 38.056066 -38.715393) (xy 37.967772 -38.743933) (xy 37.876988 -38.763131) (xy 37.7847 -38.772777)
			(xy 37.738304 -38.773354) (xy 37.69447 -38.772842) (xy 37.607226 -38.764243) (xy 37.521252 -38.747099)
			(xy 37.437383 -38.721576) (xy 37.356433 -38.687922) (xy 37.279188 -38.646464) (xy 37.242496 -38.622478)
			(xy 37.230812 -38.614604) (xy 37.202872 -38.61308) (xy 37.111178 -38.661848) (xy 37.103278 -38.666548)
			(xy 37.091217 -38.680403) (xy 37.084813 -38.69762) (xy 37.084508 -38.706806) (xy 37.084508 -40.029454)
			(xy 48.188561 -40.029454) (xy 48.188561 -39.974946) (xy 48.196319 -39.920994) (xy 48.211676 -39.868695)
			(xy 48.23432 -39.819114) (xy 48.26379 -39.77326) (xy 48.299486 -39.732068) (xy 48.340681 -39.696374)
			(xy 48.386537 -39.666908) (xy 48.436119 -39.644267) (xy 48.488419 -39.628913) (xy 48.542372 -39.62116)
			(xy 48.569626 -39.620698) (xy 48.596997 -39.621149) (xy 48.651176 -39.628971) (xy 48.70368 -39.644463)
			(xy 48.753426 -39.667308) (xy 48.799393 -39.697036) (xy 48.820324 -39.714678) (xy 48.827436 -39.720774)
			(xy 48.844454 -39.727124) (xy 48.929798 -39.727124) (xy 48.946816 -39.720774) (xy 48.953928 -39.714678)
			(xy 48.974874 -39.697056) (xy 49.020843 -39.667342) (xy 49.070587 -39.644503) (xy 49.123085 -39.629008)
			(xy 49.177258 -39.621175) (xy 49.204626 -39.620698) (xy 49.231876 -39.621174) (xy 49.285822 -39.628933)
			(xy 49.338115 -39.644291) (xy 49.387689 -39.666934) (xy 49.433537 -39.696401) (xy 49.474725 -39.732093)
			(xy 49.510414 -39.773284) (xy 49.539879 -39.819133) (xy 49.562518 -39.86871) (xy 49.577872 -39.921003)
			(xy 49.585628 -39.97495) (xy 49.585628 -40.02945) (xy 49.577872 -40.083397) (xy 49.562518 -40.13569)
			(xy 49.539879 -40.185267) (xy 49.510414 -40.231116) (xy 49.474725 -40.272307) (xy 49.433537 -40.307999)
			(xy 49.387689 -40.337466) (xy 49.338115 -40.360109) (xy 49.285822 -40.375467) (xy 49.231876 -40.383226)
			(xy 49.204626 -40.383714) (xy 49.177256 -40.383229) (xy 49.123078 -40.375415) (xy 49.070576 -40.359931)
			(xy 49.020828 -40.337093) (xy 48.974861 -40.307373) (xy 48.953928 -40.289734) (xy 48.946816 -40.283638)
			(xy 48.929798 -40.277288) (xy 48.844454 -40.277288) (xy 48.827436 -40.283638) (xy 48.820324 -40.289734)
			(xy 48.799398 -40.307381) (xy 48.753423 -40.33709) (xy 48.703674 -40.359924) (xy 48.651172 -40.375414)
			(xy 48.596995 -40.38324) (xy 48.569626 -40.383714) (xy 48.542372 -40.38324) (xy 48.488419 -40.375487)
			(xy 48.436119 -40.360133) (xy 48.386537 -40.337492) (xy 48.340681 -40.308026) (xy 48.299486 -40.272332)
			(xy 48.26379 -40.23114) (xy 48.23432 -40.185286) (xy 48.211676 -40.135705) (xy 48.196319 -40.083406)
			(xy 48.188561 -40.029454) (xy 37.084508 -40.029454) (xy 37.084508 -41.478962) (xy 37.085012 -41.489815)
			(xy 37.093982 -41.50958) (xy 37.110331 -41.523858) (xy 37.120576 -41.527476) (xy 37.230304 -41.560242)
			(xy 37.261546 -41.548812) (xy 37.270944 -41.534588) (xy 37.295556 -41.498056) (xy 37.350926 -41.429542)
			(xy 37.412798 -41.366835) (xy 37.480564 -41.310552) (xy 37.553562 -41.261242) (xy 37.631076 -41.21939)
			(xy 37.712348 -41.185404) (xy 37.796581 -41.159618) (xy 37.882951 -41.142284) (xy 37.97061 -41.133573)
			(xy 38.014656 -41.133014) (xy 38.05576 -41.133472) (xy 38.137618 -41.141054) (xy 38.218427 -41.156156)
			(xy 38.297498 -41.178651) (xy 38.374156 -41.208345) (xy 38.447746 -41.244986) (xy 38.517642 -41.288262)
			(xy 38.583247 -41.337802) (xy 38.644 -41.393185) (xy 38.699384 -41.453937) (xy 38.748926 -41.51954)
			(xy 38.792203 -41.589435) (xy 38.828846 -41.663024) (xy 38.858542 -41.739681) (xy 38.881039 -41.818752)
			(xy 38.896143 -41.89956) (xy 38.903727 -41.981418) (xy 38.904164 -42.022522) (xy 38.903578 -42.068918)
			(xy 38.893942 -42.161207) (xy 38.874746 -42.251991) (xy 38.846199 -42.340282) (xy 38.827964 -42.382948)
			(xy 38.82415 -42.392888) (xy 38.824158 -42.414152) (xy 38.827964 -42.424096) (xy 38.846202 -42.466761)
			(xy 38.874739 -42.555054) (xy 38.893934 -42.645838) (xy 38.903577 -42.738127) (xy 38.904164 -42.784522)
			(xy 38.903578 -42.830918) (xy 38.893942 -42.923207) (xy 38.874746 -43.013991) (xy 38.846199 -43.102282)
			(xy 38.827964 -43.144948) (xy 38.82415 -43.154888) (xy 38.824158 -43.176152) (xy 38.827964 -43.186096)
			(xy 38.846202 -43.228761) (xy 38.874739 -43.317054) (xy 38.891032 -43.394114) (xy 47.792682 -43.394114)
			(xy 47.796409 -43.340866) (xy 47.807522 -43.288658) (xy 47.825804 -43.238508) (xy 47.850897 -43.191396)
			(xy 47.882311 -43.148241) (xy 47.919435 -43.109887) (xy 47.940214 -43.093132) (xy 47.94896 -43.085554)
			(xy 47.959152 -43.064808) (xy 47.959772 -43.053254) (xy 47.959772 -42.97299) (xy 47.959217 -42.96142)
			(xy 47.949012 -42.940649) (xy 47.940214 -42.933112) (xy 47.919455 -42.916331) (xy 47.882329 -42.87798)
			(xy 47.850911 -42.834827) (xy 47.825815 -42.787717) (xy 47.80753 -42.737568) (xy 47.796413 -42.685361)
			(xy 47.792682 -42.632114) (xy 47.796409 -42.578866) (xy 47.807522 -42.526658) (xy 47.825804 -42.476508)
			(xy 47.850897 -42.429396) (xy 47.882311 -42.386241) (xy 47.919435 -42.347887) (xy 47.940214 -42.331132)
			(xy 47.94896 -42.323554) (xy 47.959152 -42.302808) (xy 47.959772 -42.291254) (xy 47.959772 -42.21099)
			(xy 47.959217 -42.19942) (xy 47.949012 -42.178649) (xy 47.940214 -42.171112) (xy 47.917739 -42.152911)
			(xy 47.878003 -42.110893) (xy 47.845062 -42.063361) (xy 47.819672 -42.011402) (xy 47.802414 -41.956206)
			(xy 47.793684 -41.899037) (xy 47.793148 -41.870122) (xy 47.793699 -41.842873) (xy 47.801451 -41.78893)
			(xy 47.816801 -41.736639) (xy 47.839436 -41.687065) (xy 47.868896 -41.641217) (xy 47.904581 -41.600028)
			(xy 47.945764 -41.564336) (xy 47.991607 -41.534868) (xy 48.041178 -41.512224) (xy 48.093466 -41.496865)
			(xy 48.147407 -41.489103) (xy 48.174656 -41.488614) (xy 48.202025 -41.489102) (xy 48.256204 -41.496914)
			(xy 48.308707 -41.512398) (xy 48.358454 -41.535235) (xy 48.404422 -41.564955) (xy 48.425354 -41.582594)
			(xy 48.432466 -41.58869) (xy 48.449484 -41.59504) (xy 48.534828 -41.59504) (xy 48.551846 -41.58869)
			(xy 48.558958 -41.582594) (xy 48.579894 -41.56496) (xy 48.625866 -41.535248) (xy 48.675612 -41.512411)
			(xy 48.728112 -41.496919) (xy 48.782287 -41.489089) (xy 48.809656 -41.488614) (xy 48.836909 -41.489096)
			(xy 48.89086 -41.496848) (xy 48.943159 -41.512199) (xy 48.99274 -41.534838) (xy 49.038595 -41.564304)
			(xy 49.079789 -41.599996) (xy 49.115483 -41.641188) (xy 49.144951 -41.68704) (xy 49.167593 -41.73662)
			(xy 49.182947 -41.788918) (xy 49.190702 -41.842869) (xy 49.191164 -41.870122) (xy 49.190603 -41.899037)
			(xy 49.181885 -41.956207) (xy 49.164636 -42.011406) (xy 49.139253 -42.063368) (xy 49.106316 -42.110903)
			(xy 49.066581 -42.152921) (xy 49.044098 -42.171112) (xy 49.035335 -42.178673) (xy 49.025152 -42.199432)
			(xy 49.02454 -42.21099) (xy 49.02454 -42.291254) (xy 49.025123 -42.302821) (xy 49.035307 -42.323593)
			(xy 49.044098 -42.331132) (xy 49.064905 -42.347858) (xy 49.102039 -42.386213) (xy 49.133464 -42.42937)
			(xy 49.158566 -42.476486) (xy 49.176853 -42.526642) (xy 49.18797 -42.578858) (xy 49.191699 -42.632114)
			(xy 49.187966 -42.685369) (xy 49.176846 -42.737584) (xy 49.158555 -42.787738) (xy 49.13345 -42.834853)
			(xy 49.102022 -42.878008) (xy 49.064885 -42.91636) (xy 49.044098 -42.933112) (xy 49.035335 -42.940673)
			(xy 49.025152 -42.961432) (xy 49.02454 -42.97299) (xy 49.02454 -43.053254) (xy 49.025123 -43.064821)
			(xy 49.035307 -43.085593) (xy 49.044098 -43.093132) (xy 49.064905 -43.109858) (xy 49.102039 -43.148213)
			(xy 49.133464 -43.19137) (xy 49.158566 -43.238486) (xy 49.176853 -43.288642) (xy 49.18797 -43.340858)
			(xy 49.191699 -43.394114) (xy 49.187966 -43.447369) (xy 49.176846 -43.499584) (xy 49.158555 -43.549738)
			(xy 49.13345 -43.596853) (xy 49.102022 -43.640008) (xy 49.064885 -43.67836) (xy 49.044098 -43.695112)
			(xy 49.035335 -43.702673) (xy 49.025152 -43.723432) (xy 49.02454 -43.73499) (xy 49.02454 -43.815254)
			(xy 49.025123 -43.826821) (xy 49.035307 -43.847593) (xy 49.044098 -43.855132) (xy 49.066596 -43.873305)
			(xy 49.106331 -43.915329) (xy 49.139268 -43.962867) (xy 49.164654 -44.014832) (xy 49.181907 -44.070033)
			(xy 49.190631 -44.127205) (xy 49.191164 -44.156122) (xy 49.190765 -44.183377) (xy 49.183004 -44.237333)
			(xy 49.167643 -44.289635) (xy 49.144995 -44.339218) (xy 49.115521 -44.385073) (xy 49.07982 -44.426267)
			(xy 49.03862 -44.46196) (xy 48.99276 -44.491427) (xy 48.943173 -44.514066) (xy 48.890868 -44.529418)
			(xy 48.836912 -44.53717) (xy 48.809656 -44.53763) (xy 48.782286 -44.537148) (xy 48.728107 -44.529337)
			(xy 48.675603 -44.513852) (xy 48.625856 -44.491014) (xy 48.579889 -44.461291) (xy 48.558958 -44.44365)
			(xy 48.551846 -44.437554) (xy 48.534828 -44.431204) (xy 48.449484 -44.431204) (xy 48.432466 -44.437554)
			(xy 48.425354 -44.44365) (xy 48.404406 -44.461269) (xy 48.358438 -44.490986) (xy 48.308695 -44.513826)
			(xy 48.256198 -44.529322) (xy 48.202024 -44.537154) (xy 48.174656 -44.53763) (xy 48.147405 -44.537163)
			(xy 48.093457 -44.529401) (xy 48.041164 -44.514042) (xy 47.991588 -44.491397) (xy 47.945739 -44.461928)
			(xy 47.904549 -44.426235) (xy 47.868859 -44.385044) (xy 47.839392 -44.339193) (xy 47.816751 -44.289616)
			(xy 47.801394 -44.237321) (xy 47.793635 -44.183373) (xy 47.793148 -44.156122) (xy 47.793664 -44.127205)
			(xy 47.802391 -44.070033) (xy 47.819648 -44.014833) (xy 47.84504 -43.962871) (xy 47.877985 -43.915337)
			(xy 47.917728 -43.873321) (xy 47.940214 -43.855132) (xy 47.94896 -43.847554) (xy 47.959152 -43.826808)
			(xy 47.959772 -43.815254) (xy 47.959772 -43.73499) (xy 47.959217 -43.72342) (xy 47.949012 -43.702649)
			(xy 47.940214 -43.695112) (xy 47.919455 -43.678331) (xy 47.882329 -43.63998) (xy 47.850911 -43.596827)
			(xy 47.825815 -43.549717) (xy 47.80753 -43.499568) (xy 47.796413 -43.447361) (xy 47.792682 -43.394114)
			(xy 38.891032 -43.394114) (xy 38.893934 -43.407838) (xy 38.903577 -43.500127) (xy 38.904164 -43.546522)
			(xy 38.903578 -43.592918) (xy 38.893942 -43.685207) (xy 38.874746 -43.775991) (xy 38.846199 -43.864282)
			(xy 38.827964 -43.906948) (xy 38.82415 -43.916888) (xy 38.824158 -43.938152) (xy 38.827964 -43.948096)
			(xy 38.846202 -43.990761) (xy 38.874739 -44.079054) (xy 38.893934 -44.169838) (xy 38.903577 -44.262127)
			(xy 38.904164 -44.308522) (xy 38.903703 -44.349624) (xy 38.896116 -44.431476) (xy 38.881009 -44.51228)
			(xy 38.85851 -44.591345) (xy 38.828813 -44.667996) (xy 38.792169 -44.741581) (xy 38.748892 -44.81147)
			(xy 38.699351 -44.877068) (xy 38.643969 -44.937816) (xy 38.583218 -44.993193) (xy 38.517616 -45.04273)
			(xy 38.447723 -45.086001) (xy 38.374136 -45.122639) (xy 38.297482 -45.152331) (xy 38.218416 -45.174824)
			(xy 38.137611 -45.189925) (xy 38.055758 -45.197506) (xy 38.014656 -45.19803) (xy 37.970608 -45.197496)
			(xy 37.882944 -45.188792) (xy 37.796569 -45.171463) (xy 37.712331 -45.145681) (xy 37.631054 -45.111696)
			(xy 37.553536 -45.069843) (xy 37.480535 -45.02053) (xy 37.412767 -44.964243) (xy 37.350895 -44.901531)
			(xy 37.295527 -44.833009) (xy 37.270944 -44.796456) (xy 37.261546 -44.782232) (xy 37.230304 -44.770802)
			(xy 37.120576 -44.803568) (xy 37.110357 -44.807216) (xy 37.094062 -44.821515) (xy 37.085076 -44.841245)
			(xy 37.084508 -44.852082) (xy 37.084508 -51.445922) (xy 37.084082 -51.470045) (xy 37.077732 -51.517872)
			(xy 37.065207 -51.564464) (xy 37.056314 -51.586892) (xy 36.494027 -52.944522) (xy 40.985948 -52.944522)
			(xy 40.986534 -52.898126) (xy 40.996177 -52.805838) (xy 41.015372 -52.715054) (xy 41.04391 -52.626761)
			(xy 41.062148 -52.584096) (xy 41.065954 -52.574152) (xy 41.065962 -52.552888) (xy 41.062148 -52.542948)
			(xy 41.043914 -52.500281) (xy 41.015366 -52.411991) (xy 40.99617 -52.321207) (xy 40.986534 -52.228918)
			(xy 40.985948 -52.182522) (xy 40.986435 -52.139315) (xy 40.994822 -52.053307) (xy 41.01151 -51.968519)
			(xy 41.03634 -51.885748) (xy 41.06908 -51.805775) (xy 41.10942 -51.729354) (xy 41.156981 -51.657205)
			(xy 41.211314 -51.590007) (xy 41.271906 -51.528395) (xy 41.304718 -51.500278) (xy 41.313608 -51.492912)
			(xy 41.322752 -51.473354) (xy 41.32453 -51.37404) (xy 41.315894 -51.353974) (xy 41.307512 -51.346608)
			(xy 41.276898 -51.318519) (xy 41.22043 -51.257566) (xy 41.169894 -51.191613) (xy 41.125729 -51.121234)
			(xy 41.08832 -51.047042) (xy 41.057993 -50.969685) (xy 41.035014 -50.889837) (xy 41.019581 -50.808193)
			(xy 41.01183 -50.725467) (xy 41.011348 -50.683922) (xy 41.011934 -50.637526) (xy 41.021577 -50.545238)
			(xy 41.040772 -50.454454) (xy 41.06931 -50.366161) (xy 41.087548 -50.323496) (xy 41.091354 -50.313552)
			(xy 41.091362 -50.292288) (xy 41.087548 -50.282348) (xy 41.069314 -50.239681) (xy 41.040766 -50.151391)
			(xy 41.02157 -50.060607) (xy 41.011934 -49.968318) (xy 41.011348 -49.921922) (xy 41.011899 -49.878262)
			(xy 41.020444 -49.791361) (xy 41.037465 -49.705715) (xy 41.062796 -49.62215) (xy 41.096195 -49.54147)
			(xy 41.137339 -49.464451) (xy 41.185834 -49.391834) (xy 41.241211 -49.32432) (xy 41.302937 -49.262557)
			(xy 41.37042 -49.207141) (xy 41.443008 -49.158605) (xy 41.520003 -49.117415) (xy 41.600664 -49.08397)
			(xy 41.642284 -49.070768) (xy 41.658032 -49.065942) (xy 41.677844 -49.040034) (xy 41.681146 -48.910748)
			(xy 41.662858 -48.883824) (xy 41.647364 -48.878236) (xy 41.608244 -48.863487) (xy 41.532712 -48.82763)
			(xy 41.460877 -48.784845) (xy 41.393374 -48.735509) (xy 41.330797 -48.680057) (xy 41.2737 -48.618979)
			(xy 41.222584 -48.552812) (xy 41.177902 -48.482142) (xy 41.140048 -48.407591) (xy 41.109356 -48.329818)
			(xy 41.086096 -48.249507) (xy 41.070474 -48.167369) (xy 41.062627 -48.084127) (xy 41.062148 -48.042322)
			(xy 41.062734 -47.995926) (xy 41.072377 -47.903638) (xy 41.091572 -47.812854) (xy 41.12011 -47.724561)
			(xy 41.138348 -47.681896) (xy 41.142154 -47.671952) (xy 41.142162 -47.650688) (xy 41.138348 -47.640748)
			(xy 41.120114 -47.598081) (xy 41.091566 -47.509791) (xy 41.07237 -47.419007) (xy 41.062734 -47.326718)
			(xy 41.062148 -47.280322) (xy 41.062652 -47.237974) (xy 41.070703 -47.15366) (xy 41.086732 -47.070494)
			(xy 41.110593 -46.989227) (xy 41.142072 -46.910597) (xy 41.180883 -46.835316) (xy 41.226673 -46.764064)
			(xy 41.279029 -46.697488) (xy 41.337477 -46.63619) (xy 41.401487 -46.580725) (xy 41.470479 -46.531596)
			(xy 41.543829 -46.489247) (xy 41.620872 -46.454063) (xy 41.700911 -46.426361) (xy 41.78322 -46.406393)
			(xy 41.867055 -46.39434) (xy 41.951656 -46.39031) (xy 42.036257 -46.39434) (xy 42.120092 -46.406393)
			(xy 42.202401 -46.426361) (xy 42.28244 -46.454063) (xy 42.359483 -46.489247) (xy 42.432833 -46.531596)
			(xy 42.501825 -46.580725) (xy 42.565835 -46.63619) (xy 42.624283 -46.697488) (xy 42.676639 -46.764064)
			(xy 42.722429 -46.835316) (xy 42.76124 -46.910597) (xy 42.792719 -46.989227) (xy 42.81658 -47.070494)
			(xy 42.832609 -47.15366) (xy 42.84066 -47.237974) (xy 42.841164 -47.280322) (xy 42.840557 -47.326717)
			(xy 42.83092 -47.419005) (xy 42.811731 -47.509789) (xy 42.783199 -47.598083) (xy 42.764964 -47.640748)
			(xy 42.761132 -47.650684) (xy 42.76114 -47.671956) (xy 42.764964 -47.681896) (xy 42.783213 -47.724556)
			(xy 42.811757 -47.812849) (xy 42.830949 -47.903635) (xy 42.84058 -47.995926) (xy 42.840844 -48.016922)
			(xy 47.107348 -48.016922) (xy 47.107864 -47.988005) (xy 47.116591 -47.930833) (xy 47.133848 -47.875633)
			(xy 47.15924 -47.823671) (xy 47.192185 -47.776137) (xy 47.231928 -47.734121) (xy 47.254414 -47.715932)
			(xy 47.26316 -47.708354) (xy 47.273352 -47.687608) (xy 47.273972 -47.676054) (xy 47.273972 -47.59579)
			(xy 47.273417 -47.58422) (xy 47.263212 -47.563449) (xy 47.254414 -47.555912) (xy 47.231939 -47.537711)
			(xy 47.192203 -47.495693) (xy 47.159262 -47.448161) (xy 47.133872 -47.396202) (xy 47.116614 -47.341006)
			(xy 47.107884 -47.283837) (xy 47.107348 -47.254922) (xy 47.107834 -47.227671) (xy 47.11559 -47.173723)
			(xy 47.130945 -47.121428) (xy 47.153587 -47.071851) (xy 47.183053 -47.026001) (xy 47.218744 -46.98481)
			(xy 47.259935 -46.949119) (xy 47.305785 -46.919653) (xy 47.355362 -46.897011) (xy 47.407657 -46.881656)
			(xy 47.461605 -46.8739) (xy 47.516107 -46.8739) (xy 47.570055 -46.881656) (xy 47.62235 -46.897011)
			(xy 47.671927 -46.919653) (xy 47.717777 -46.949119) (xy 47.758968 -46.98481) (xy 47.794659 -47.026001)
			(xy 47.824125 -47.071851) (xy 47.846767 -47.121428) (xy 47.862122 -47.173723) (xy 47.869878 -47.227671)
			(xy 47.870364 -47.254922) (xy 47.869803 -47.283837) (xy 47.861085 -47.341007) (xy 47.843836 -47.396206)
			(xy 47.818453 -47.448168) (xy 47.785516 -47.495703) (xy 47.745781 -47.537721) (xy 47.723298 -47.555912)
			(xy 47.714535 -47.563473) (xy 47.704352 -47.584232) (xy 47.70374 -47.59579) (xy 47.70374 -47.676054)
			(xy 47.704323 -47.687621) (xy 47.714507 -47.708393) (xy 47.723298 -47.715932) (xy 47.745796 -47.734105)
			(xy 47.785531 -47.776129) (xy 47.818468 -47.823667) (xy 47.843854 -47.875632) (xy 47.861107 -47.930833)
			(xy 47.869831 -47.988005) (xy 47.870364 -48.016922) (xy 47.869878 -48.044173) (xy 47.862122 -48.098121)
			(xy 47.846767 -48.150416) (xy 47.824125 -48.199993) (xy 47.794659 -48.245843) (xy 47.758968 -48.287034)
			(xy 47.717777 -48.322725) (xy 47.671927 -48.352191) (xy 47.62235 -48.374833) (xy 47.570055 -48.390188)
			(xy 47.516107 -48.397944) (xy 47.461605 -48.397944) (xy 47.407657 -48.390188) (xy 47.355362 -48.374833)
			(xy 47.305785 -48.352191) (xy 47.259935 -48.322725) (xy 47.218744 -48.287034) (xy 47.183053 -48.245843)
			(xy 47.153587 -48.199993) (xy 47.130945 -48.150416) (xy 47.11559 -48.098121) (xy 47.107834 -48.044173)
			(xy 47.107348 -48.016922) (xy 42.840844 -48.016922) (xy 42.841164 -48.042322) (xy 42.840645 -48.085983)
			(xy 42.832095 -48.172885) (xy 42.815071 -48.25853) (xy 42.789736 -48.342096) (xy 42.756334 -48.422776)
			(xy 42.715186 -48.499795) (xy 42.66669 -48.572411) (xy 42.61131 -48.639925) (xy 42.549581 -48.701687)
			(xy 42.482097 -48.757103) (xy 42.409507 -48.805639) (xy 42.332511 -48.846828) (xy 42.251848 -48.880274)
			(xy 42.210228 -48.893476) (xy 42.19448 -48.898302) (xy 42.174668 -48.92421) (xy 42.171366 -49.053496)
			(xy 42.189654 -49.08042) (xy 42.205148 -49.086008) (xy 42.244252 -49.100798) (xy 42.319782 -49.136653)
			(xy 42.391615 -49.179435) (xy 42.459117 -49.228768) (xy 42.521693 -49.284217) (xy 42.578791 -49.345292)
			(xy 42.629907 -49.411455) (xy 42.67459 -49.482121) (xy 42.712447 -49.556668) (xy 42.743142 -49.634438)
			(xy 42.766405 -49.714744) (xy 42.782031 -49.796879) (xy 42.789883 -49.880118) (xy 42.790364 -49.921922)
			(xy 42.789757 -49.968317) (xy 42.78012 -50.060605) (xy 42.760931 -50.151389) (xy 42.732399 -50.239683)
			(xy 42.714164 -50.282348) (xy 42.710332 -50.292284) (xy 42.71034 -50.313556) (xy 42.714164 -50.323496)
			(xy 42.732413 -50.366156) (xy 42.760957 -50.454449) (xy 42.780149 -50.545235) (xy 42.78978 -50.637526)
			(xy 42.790364 -50.683922) (xy 47.107348 -50.683922) (xy 47.107864 -50.655005) (xy 47.116591 -50.597833)
			(xy 47.133848 -50.542633) (xy 47.15924 -50.490671) (xy 47.192185 -50.443137) (xy 47.231928 -50.401121)
			(xy 47.254414 -50.382932) (xy 47.26316 -50.375354) (xy 47.273352 -50.354608) (xy 47.273972 -50.343054)
			(xy 47.273972 -50.26279) (xy 47.273417 -50.25122) (xy 47.263212 -50.230449) (xy 47.254414 -50.222912)
			(xy 47.231939 -50.204711) (xy 47.192203 -50.162693) (xy 47.159262 -50.115161) (xy 47.133872 -50.063202)
			(xy 47.116614 -50.008006) (xy 47.107884 -49.950837) (xy 47.107348 -49.921922) (xy 47.107834 -49.894671)
			(xy 47.11559 -49.840723) (xy 47.130945 -49.788428) (xy 47.153587 -49.738851) (xy 47.183053 -49.693001)
			(xy 47.218744 -49.65181) (xy 47.259935 -49.616119) (xy 47.305785 -49.586653) (xy 47.355362 -49.564011)
			(xy 47.407657 -49.548656) (xy 47.461605 -49.5409) (xy 47.516107 -49.5409) (xy 47.570055 -49.548656)
			(xy 47.62235 -49.564011) (xy 47.671927 -49.586653) (xy 47.717777 -49.616119) (xy 47.758968 -49.65181)
			(xy 47.794659 -49.693001) (xy 47.824125 -49.738851) (xy 47.846767 -49.788428) (xy 47.862122 -49.840723)
			(xy 47.869878 -49.894671) (xy 47.870364 -49.921922) (xy 47.869803 -49.950837) (xy 47.861085 -50.008007)
			(xy 47.843836 -50.063206) (xy 47.818453 -50.115168) (xy 47.785516 -50.162703) (xy 47.745781 -50.204721)
			(xy 47.723298 -50.222912) (xy 47.714535 -50.230473) (xy 47.704352 -50.251232) (xy 47.70374 -50.26279)
			(xy 47.70374 -50.343054) (xy 47.704323 -50.354621) (xy 47.714507 -50.375393) (xy 47.723298 -50.382932)
			(xy 47.745796 -50.401105) (xy 47.785531 -50.443129) (xy 47.818468 -50.490667) (xy 47.843854 -50.542632)
			(xy 47.861107 -50.597833) (xy 47.869831 -50.655005) (xy 47.870364 -50.683922) (xy 47.869878 -50.711173)
			(xy 47.862122 -50.765121) (xy 47.846767 -50.817416) (xy 47.824125 -50.866993) (xy 47.794659 -50.912843)
			(xy 47.758968 -50.954034) (xy 47.717777 -50.989725) (xy 47.671927 -51.019191) (xy 47.62235 -51.041833)
			(xy 47.570055 -51.057188) (xy 47.516107 -51.064944) (xy 47.461605 -51.064944) (xy 47.407657 -51.057188)
			(xy 47.355362 -51.041833) (xy 47.305785 -51.019191) (xy 47.259935 -50.989725) (xy 47.218744 -50.954034)
			(xy 47.183053 -50.912843) (xy 47.153587 -50.866993) (xy 47.130945 -50.817416) (xy 47.11559 -50.765121)
			(xy 47.107834 -50.711173) (xy 47.107348 -50.683922) (xy 42.790364 -50.683922) (xy 42.789832 -50.727128)
			(xy 42.781451 -50.813134) (xy 42.764769 -50.897921) (xy 42.739944 -50.980691) (xy 42.70721 -51.060664)
			(xy 42.666875 -51.137086) (xy 42.619319 -51.209236) (xy 42.564991 -51.276435) (xy 42.504404 -51.338049)
			(xy 42.471594 -51.366166) (xy 42.462704 -51.373532) (xy 42.45356 -51.39309) (xy 42.451782 -51.492404)
			(xy 42.460418 -51.51247) (xy 42.4688 -51.519836) (xy 42.499438 -51.547899) (xy 42.555904 -51.608856)
			(xy 42.606439 -51.674813) (xy 42.650602 -51.745196) (xy 42.688008 -51.819391) (xy 42.718331 -51.896751)
			(xy 42.741308 -51.976602) (xy 42.756737 -52.058248) (xy 42.764484 -52.140977) (xy 42.764964 -52.182522)
			(xy 42.764357 -52.228917) (xy 42.75472 -52.321205) (xy 42.735531 -52.411989) (xy 42.706999 -52.500283)
			(xy 42.688764 -52.542948) (xy 42.684932 -52.552884) (xy 42.68494 -52.574156) (xy 42.688764 -52.584096)
			(xy 42.707013 -52.626756) (xy 42.735557 -52.715049) (xy 42.754749 -52.805835) (xy 42.76438 -52.898126)
			(xy 42.764964 -52.944522) (xy 42.764408 -52.989616) (xy 42.761243 -53.020722) (xy 47.056548 -53.020722)
			(xy 47.057064 -52.991805) (xy 47.065791 -52.934633) (xy 47.083048 -52.879433) (xy 47.10844 -52.827471)
			(xy 47.141385 -52.779937) (xy 47.181128 -52.737921) (xy 47.203614 -52.719732) (xy 47.21236 -52.712154)
			(xy 47.222552 -52.691408) (xy 47.223172 -52.679854) (xy 47.223172 -52.59959) (xy 47.222617 -52.58802)
			(xy 47.212412 -52.567249) (xy 47.203614 -52.559712) (xy 47.181139 -52.541511) (xy 47.141403 -52.499493)
			(xy 47.108462 -52.451961) (xy 47.083072 -52.400002) (xy 47.065814 -52.344806) (xy 47.057084 -52.287637)
			(xy 47.056548 -52.258722) (xy 47.057034 -52.231471) (xy 47.06479 -52.177523) (xy 47.080145 -52.125228)
			(xy 47.102787 -52.075651) (xy 47.132253 -52.029801) (xy 47.167944 -51.98861) (xy 47.209135 -51.952919)
			(xy 47.254985 -51.923453) (xy 47.304562 -51.900811) (xy 47.356857 -51.885456) (xy 47.410805 -51.8777)
			(xy 47.465307 -51.8777) (xy 47.519255 -51.885456) (xy 47.57155 -51.900811) (xy 47.621127 -51.923453)
			(xy 47.666977 -51.952919) (xy 47.708168 -51.98861) (xy 47.743859 -52.029801) (xy 47.773325 -52.075651)
			(xy 47.795967 -52.125228) (xy 47.811322 -52.177523) (xy 47.819078 -52.231471) (xy 47.819564 -52.258722)
			(xy 47.819003 -52.287637) (xy 47.810285 -52.344807) (xy 47.793036 -52.400006) (xy 47.767653 -52.451968)
			(xy 47.734716 -52.499503) (xy 47.694981 -52.541521) (xy 47.672498 -52.559712) (xy 47.663735 -52.567273)
			(xy 47.653552 -52.588032) (xy 47.65294 -52.59959) (xy 47.65294 -52.679854) (xy 47.653523 -52.691421)
			(xy 47.663707 -52.712193) (xy 47.672498 -52.719732) (xy 47.694996 -52.737905) (xy 47.734731 -52.779929)
			(xy 47.767668 -52.827467) (xy 47.793054 -52.879432) (xy 47.810307 -52.934633) (xy 47.819031 -52.991805)
			(xy 47.819564 -53.020722) (xy 47.819078 -53.047973) (xy 47.811322 -53.101921) (xy 47.795967 -53.154216)
			(xy 47.773325 -53.203793) (xy 47.743859 -53.249643) (xy 47.708168 -53.290834) (xy 47.666977 -53.326525)
			(xy 47.621127 -53.355991) (xy 47.57155 -53.378633) (xy 47.519255 -53.393988) (xy 47.465307 -53.401744)
			(xy 47.410805 -53.401744) (xy 47.356857 -53.393988) (xy 47.304562 -53.378633) (xy 47.254985 -53.355991)
			(xy 47.209135 -53.326525) (xy 47.167944 -53.290834) (xy 47.132253 -53.249643) (xy 47.102787 -53.203793)
			(xy 47.080145 -53.154216) (xy 47.06479 -53.101921) (xy 47.057034 -53.047973) (xy 47.056548 -53.020722)
			(xy 42.761243 -53.020722) (xy 42.75528 -53.07934) (xy 42.737121 -53.167679) (xy 42.710115 -53.253728)
			(xy 42.674541 -53.336603) (xy 42.630764 -53.415453) (xy 42.605452 -53.452776) (xy 42.596562 -53.465476)
			(xy 42.5958 -53.495194) (xy 42.659808 -53.600604) (xy 42.686478 -53.613558) (xy 42.701718 -53.61178)
			(xy 42.729978 -53.608353) (xy 42.78679 -53.604666) (xy 42.815256 -53.604414) (xy 42.856359 -53.604894)
			(xy 42.938215 -53.612475) (xy 43.019022 -53.627578) (xy 43.098091 -53.650071) (xy 43.174747 -53.679765)
			(xy 43.248336 -53.716406) (xy 43.31823 -53.75968) (xy 43.383832 -53.809219) (xy 43.444584 -53.8646)
			(xy 43.499967 -53.925351) (xy 43.549508 -53.990952) (xy 43.592784 -54.060845) (xy 43.629426 -54.134433)
			(xy 43.659122 -54.211088) (xy 43.681617 -54.290157) (xy 43.696721 -54.370963) (xy 43.704305 -54.452819)
			(xy 43.704764 -54.493922) (xy 43.704157 -54.540317) (xy 43.69452 -54.632605) (xy 43.675331 -54.723389)
			(xy 43.646799 -54.811683) (xy 43.628564 -54.854348) (xy 43.624732 -54.864284) (xy 43.62474 -54.885556)
			(xy 43.628564 -54.895496) (xy 43.646813 -54.938156) (xy 43.675357 -55.026449) (xy 43.694549 -55.117235)
			(xy 43.700672 -55.175912) (xy 46.24832 -55.175912) (xy 46.248839 -55.146995) (xy 46.257567 -55.089824)
			(xy 46.274824 -55.034624) (xy 46.300216 -54.982663) (xy 46.333159 -54.935129) (xy 46.3729 -54.893112)
			(xy 46.395386 -54.874922) (xy 46.404131 -54.867344) (xy 46.414325 -54.846598) (xy 46.414944 -54.835044)
			(xy 46.414944 -54.75478) (xy 46.414347 -54.743215) (xy 46.404173 -54.722442) (xy 46.395386 -54.714902)
			(xy 46.372901 -54.696713) (xy 46.333166 -54.654693) (xy 46.300228 -54.607157) (xy 46.27484 -54.555196)
			(xy 46.257584 -54.499998) (xy 46.248855 -54.442828) (xy 46.24832 -54.413912) (xy 46.248806 -54.386661)
			(xy 46.256562 -54.332713) (xy 46.271917 -54.280418) (xy 46.294559 -54.230841) (xy 46.324025 -54.184991)
			(xy 46.359716 -54.1438) (xy 46.400907 -54.108109) (xy 46.446757 -54.078643) (xy 46.496334 -54.056001)
			(xy 46.548629 -54.040646) (xy 46.602577 -54.03289) (xy 46.657079 -54.03289) (xy 46.711027 -54.040646)
			(xy 46.763322 -54.056001) (xy 46.812899 -54.078643) (xy 46.858749 -54.108109) (xy 46.89994 -54.1438)
			(xy 46.935631 -54.184991) (xy 46.965097 -54.230841) (xy 46.987739 -54.280418) (xy 47.003094 -54.332713)
			(xy 47.01085 -54.386661) (xy 47.011336 -54.413912) (xy 47.010779 -54.442828) (xy 47.002061 -54.499998)
			(xy 46.984813 -54.555197) (xy 46.959428 -54.60716) (xy 46.92649 -54.654694) (xy 46.886754 -54.696712)
			(xy 46.86427 -54.714902) (xy 46.855507 -54.722462) (xy 46.845325 -54.743222) (xy 46.844712 -54.75478)
			(xy 46.844712 -54.835044) (xy 46.845311 -54.846608) (xy 46.855485 -54.86738) (xy 46.86427 -54.874922)
			(xy 46.886758 -54.893108) (xy 46.926494 -54.935128) (xy 46.959433 -54.982664) (xy 46.984821 -55.034626)
			(xy 47.002076 -55.089825) (xy 47.010803 -55.146996) (xy 47.011336 -55.175912) (xy 47.01085 -55.203163)
			(xy 47.003094 -55.257111) (xy 46.987739 -55.309406) (xy 46.965097 -55.358983) (xy 46.935631 -55.404833)
			(xy 46.89994 -55.446024) (xy 46.858749 -55.481715) (xy 46.812899 -55.511181) (xy 46.763322 -55.533823)
			(xy 46.711027 -55.549178) (xy 46.657079 -55.556934) (xy 46.602577 -55.556934) (xy 46.548629 -55.549178)
			(xy 46.496334 -55.533823) (xy 46.446757 -55.511181) (xy 46.400907 -55.481715) (xy 46.359716 -55.446024)
			(xy 46.324025 -55.404833) (xy 46.294559 -55.358983) (xy 46.271917 -55.309406) (xy 46.256562 -55.257111)
			(xy 46.248806 -55.203163) (xy 46.24832 -55.175912) (xy 43.700672 -55.175912) (xy 43.70418 -55.209526)
			(xy 43.704764 -55.255922) (xy 43.70426 -55.29827) (xy 43.696209 -55.382584) (xy 43.68018 -55.46575)
			(xy 43.656319 -55.547017) (xy 43.62484 -55.625647) (xy 43.586029 -55.700928) (xy 43.540239 -55.77218)
			(xy 43.487883 -55.838756) (xy 43.429435 -55.900054) (xy 43.365425 -55.955519) (xy 43.296433 -56.004648)
			(xy 43.223083 -56.046997) (xy 43.14604 -56.082181) (xy 43.066001 -56.109883) (xy 42.983692 -56.129851)
			(xy 42.899857 -56.141904) (xy 42.815256 -56.145935) (xy 42.730655 -56.141904) (xy 42.64682 -56.129851)
			(xy 42.564511 -56.109883) (xy 42.484472 -56.082181) (xy 42.407429 -56.046997) (xy 42.334079 -56.004648)
			(xy 42.265087 -55.955519) (xy 42.201077 -55.900054) (xy 42.142629 -55.838756) (xy 42.090273 -55.77218)
			(xy 42.044483 -55.700928) (xy 42.005672 -55.625647) (xy 41.974193 -55.547017) (xy 41.950332 -55.46575)
			(xy 41.934303 -55.382584) (xy 41.926252 -55.29827) (xy 41.925748 -55.255922) (xy 41.926334 -55.209526)
			(xy 41.935977 -55.117238) (xy 41.955172 -55.026454) (xy 41.98371 -54.938161) (xy 42.001948 -54.895496)
			(xy 42.005754 -54.885552) (xy 42.005762 -54.864288) (xy 42.001948 -54.854348) (xy 41.983714 -54.811681)
			(xy 41.955166 -54.723391) (xy 41.93597 -54.632607) (xy 41.926334 -54.540318) (xy 41.925748 -54.493922)
			(xy 41.926324 -54.448829) (xy 41.935448 -54.359106) (xy 41.953604 -54.270766) (xy 41.980605 -54.184717)
			(xy 42.016176 -54.101842) (xy 42.059949 -54.022992) (xy 42.08526 -53.985668) (xy 42.09415 -53.972968)
			(xy 42.094912 -53.94325) (xy 42.030904 -53.83784) (xy 42.004234 -53.824886) (xy 41.988994 -53.826664)
			(xy 41.960734 -53.83009) (xy 41.903922 -53.833777) (xy 41.875456 -53.83403) (xy 41.834353 -53.833575)
			(xy 41.752499 -53.825987) (xy 41.671694 -53.810878) (xy 41.592628 -53.788379) (xy 41.515975 -53.758681)
			(xy 41.442389 -53.722036) (xy 41.372498 -53.678759) (xy 41.306898 -53.629218) (xy 41.246148 -53.573836)
			(xy 41.190767 -53.513085) (xy 41.141228 -53.447484) (xy 41.097953 -53.377592) (xy 41.061311 -53.304005)
			(xy 41.031614 -53.227351) (xy 41.009117 -53.148284) (xy 40.99401 -53.067479) (xy 40.986424 -52.985625)
			(xy 40.985948 -52.944522) (xy 36.494027 -52.944522) (xy 34.687764 -57.305702) (xy 34.684466 -57.314915)
			(xy 34.684346 -57.334466) (xy 34.691531 -57.352648) (xy 34.697924 -57.360058) (xy 34.772346 -57.43829)
			(xy 34.801302 -57.445402) (xy 34.815526 -57.440322) (xy 34.851336 -57.428061) (xy 34.92458 -57.408949)
			(xy 34.999182 -57.396123) (xy 35.074604 -57.389677) (xy 35.112452 -57.389268) (xy 35.152021 -57.389689)
			(xy 35.230849 -57.396697) (xy 35.308743 -57.41068) (xy 35.385086 -57.431527) (xy 35.422332 -57.444894)
			(xy 35.430999 -57.447734) (xy 35.449225 -57.447734) (xy 35.457892 -57.444894) (xy 35.495137 -57.431525)
			(xy 35.571481 -57.410677) (xy 35.649374 -57.396694) (xy 35.728202 -57.389687) (xy 35.767772 -57.389268)
			(xy 35.806703 -57.389708) (xy 35.884265 -57.396558) (xy 35.960932 -57.410154) (xy 36.036118 -57.430394)
			(xy 36.072826 -57.44337) (xy 36.081375 -57.446134) (xy 36.099329 -57.446134) (xy 36.107878 -57.44337)
			(xy 36.144584 -57.430387) (xy 36.219768 -57.410136) (xy 36.296437 -57.396541) (xy 36.374 -57.389706)
			(xy 36.412932 -57.389268) (xy 36.454034 -57.389744) (xy 36.535887 -57.397332) (xy 36.616691 -57.412439)
			(xy 36.695756 -57.434937) (xy 36.772408 -57.464634) (xy 36.845994 -57.501277) (xy 36.915884 -57.544552)
			(xy 36.981484 -57.594092) (xy 37.042233 -57.649473) (xy 37.097613 -57.710222) (xy 37.147152 -57.775822)
			(xy 37.190427 -57.845713) (xy 37.227069 -57.919299) (xy 37.256766 -57.995952) (xy 37.279263 -58.075017)
			(xy 37.29437 -58.155821) (xy 37.301956 -58.237674) (xy 37.30244 -58.278776) (xy 37.30203 -58.317066)
			(xy 37.295424 -58.39336) (xy 37.282275 -58.468802) (xy 37.262681 -58.542832) (xy 37.250116 -58.579004)
			(xy 37.247469 -58.587442) (xy 37.247462 -58.605113) (xy 37.250116 -58.613548) (xy 37.257228 -58.633614)
			(xy 37.262054 -58.648092) (xy 37.285676 -58.666888) (xy 37.408612 -58.678064) (xy 37.435282 -58.66384)
			(xy 37.442648 -58.650632) (xy 37.463895 -58.612987) (xy 37.512646 -58.541596) (xy 37.568092 -58.475271)
			(xy 37.629712 -58.414638) (xy 37.696923 -58.360269) (xy 37.769092 -58.312678) (xy 37.845538 -58.272312)
			(xy 37.925539 -58.239554) (xy 38.008341 -58.214711) (xy 38.093163 -58.198019) (xy 38.179204 -58.189635)
			(xy 38.222428 -58.189114) (xy 38.261359 -58.189557) (xy 38.338919 -58.19641) (xy 38.415585 -58.210011)
			(xy 38.49077 -58.230254) (xy 38.527482 -58.243216) (xy 38.536031 -58.24598) (xy 38.553985 -58.24598)
			(xy 38.562534 -58.243216) (xy 38.599239 -58.23023) (xy 38.674424 -58.209975) (xy 38.751092 -58.196376)
			(xy 38.828656 -58.189536) (xy 38.867588 -58.189114) (xy 38.906519 -58.189555) (xy 38.98408 -58.196405)
			(xy 39.060747 -58.210002) (xy 39.135933 -58.230242) (xy 39.172642 -58.243216) (xy 39.181191 -58.24598)
			(xy 39.199145 -58.24598) (xy 39.207694 -58.243216) (xy 39.2444 -58.230233) (xy 39.319584 -58.209983)
			(xy 39.396253 -58.196388) (xy 39.473816 -58.189554) (xy 39.512748 -58.189114) (xy 39.553849 -58.189591)
			(xy 39.635699 -58.19718) (xy 39.7165 -58.212288) (xy 39.795562 -58.234788) (xy 39.872212 -58.264486)
			(xy 39.945794 -58.301129) (xy 40.015681 -58.344406) (xy 40.081277 -58.393946) (xy 40.142022 -58.449327)
			(xy 40.197399 -58.510077) (xy 40.2431 -58.5706) (xy 40.517609 -58.5706) (xy 40.521639 -58.486002)
			(xy 40.533693 -58.40217) (xy 40.55366 -58.319863) (xy 40.58136 -58.239827) (xy 40.616543 -58.162786)
			(xy 40.65889 -58.089438) (xy 40.708017 -58.020448) (xy 40.76348 -57.95644) (xy 40.824775 -57.897994)
			(xy 40.891349 -57.845639) (xy 40.962598 -57.79985) (xy 41.037877 -57.76104) (xy 41.116504 -57.729561)
			(xy 41.197767 -57.705699) (xy 41.28093 -57.68967) (xy 41.365241 -57.681618) (xy 41.407588 -57.681114)
			(xy 41.44652 -57.681543) (xy 41.524084 -57.688381) (xy 41.600752 -57.701978) (xy 41.675937 -57.722231)
			(xy 41.712642 -57.735216) (xy 41.721191 -57.73798) (xy 41.739145 -57.73798) (xy 41.747694 -57.735216)
			(xy 41.784399 -57.722232) (xy 41.859587 -57.701995) (xy 41.936255 -57.688401) (xy 42.013816 -57.681553)
			(xy 42.052748 -57.681114) (xy 42.095097 -57.681598) (xy 42.179413 -57.689649) (xy 42.262581 -57.705678)
			(xy 42.343849 -57.72954) (xy 42.422481 -57.76102) (xy 42.497764 -57.799831) (xy 42.569017 -57.845622)
			(xy 42.635595 -57.897979) (xy 42.696894 -57.956428) (xy 42.75236 -58.020439) (xy 42.80149 -58.089433)
			(xy 42.84384 -58.162784) (xy 42.879025 -58.239829) (xy 42.906727 -58.319869) (xy 42.926696 -58.40218)
			(xy 42.93875 -58.486017) (xy 42.939574 -58.503312) (xy 44.667424 -58.503312) (xy 44.668008 -58.456916)
			(xy 44.677653 -58.364628) (xy 44.696848 -58.273844) (xy 44.725386 -58.185551) (xy 44.743624 -58.142886)
			(xy 44.747436 -58.132944) (xy 44.747441 -58.111678) (xy 44.743624 -58.101738) (xy 44.725385 -58.059073)
			(xy 44.696839 -57.970782) (xy 44.677644 -57.879998) (xy 44.66801 -57.787708) (xy 44.667424 -57.741312)
			(xy 44.667864 -57.700208) (xy 44.675448 -57.618351) (xy 44.690553 -57.537543) (xy 44.71305 -57.458473)
			(xy 44.742747 -57.381816) (xy 44.77939 -57.308227) (xy 44.822667 -57.238333) (xy 44.872209 -57.17273)
			(xy 44.927592 -57.111978) (xy 44.988345 -57.056596) (xy 45.053949 -57.007056) (xy 45.123845 -56.96378)
			(xy 45.197435 -56.927138) (xy 45.274092 -56.897443) (xy 45.353162 -56.874948) (xy 45.433971 -56.859845)
			(xy 45.515828 -56.852263) (xy 45.556932 -56.851804) (xy 45.603327 -56.85241) (xy 45.695615 -56.862048)
			(xy 45.786399 -56.881237) (xy 45.874693 -56.909769) (xy 45.917358 -56.928004) (xy 45.927298 -56.931824)
			(xy 45.948566 -56.931824) (xy 45.958506 -56.928004) (xy 46.001164 -56.909749) (xy 46.089458 -56.881208)
			(xy 46.180244 -56.862017) (xy 46.272536 -56.852387) (xy 46.318932 -56.851804) (xy 46.365327 -56.85241)
			(xy 46.457615 -56.862048) (xy 46.548399 -56.881237) (xy 46.636693 -56.909769) (xy 46.679358 -56.928004)
			(xy 46.689298 -56.931824) (xy 46.710566 -56.931824) (xy 46.720506 -56.928004) (xy 46.763164 -56.909749)
			(xy 46.851458 -56.881208) (xy 46.942244 -56.862017) (xy 47.034536 -56.852387) (xy 47.080932 -56.851804)
			(xy 47.122035 -56.852236) (xy 47.203891 -56.859824) (xy 47.284698 -56.874932) (xy 47.363766 -56.897432)
			(xy 47.44042 -56.927131) (xy 47.514008 -56.963775) (xy 47.5839 -57.007054) (xy 47.649501 -57.056596)
			(xy 47.710251 -57.11198) (xy 47.765632 -57.172733) (xy 47.815171 -57.238336) (xy 47.858446 -57.308231)
			(xy 47.895087 -57.38182) (xy 47.924782 -57.458476) (xy 47.947278 -57.537545) (xy 47.962382 -57.618352)
			(xy 47.969966 -57.700209) (xy 47.97044 -57.741312) (xy 47.969867 -57.787708) (xy 47.96022 -57.879997)
			(xy 47.941021 -57.970781) (xy 47.91248 -58.059074) (xy 47.89424 -58.101738) (xy 47.890415 -58.111676)
			(xy 47.89042 -58.132946) (xy 47.89424 -58.142886) (xy 47.912491 -58.185546) (xy 47.941033 -58.273839)
			(xy 47.960224 -58.364625) (xy 47.969856 -58.456916) (xy 47.97044 -58.503312) (xy 47.969945 -58.544414)
			(xy 47.962359 -58.626267) (xy 47.947254 -58.70707) (xy 47.924757 -58.786136) (xy 47.895062 -58.862788)
			(xy 47.858421 -58.936374) (xy 47.815146 -59.006265) (xy 47.765608 -59.071865) (xy 47.710229 -59.132614)
			(xy 47.64948 -59.187995) (xy 47.583881 -59.237535) (xy 47.513991 -59.280811) (xy 47.440406 -59.317454)
			(xy 47.363755 -59.347151) (xy 47.28469 -59.369649) (xy 47.203886 -59.384756) (xy 47.122034 -59.392344)
			(xy 47.080932 -59.39282) (xy 47.034537 -59.392225) (xy 46.942249 -59.382583) (xy 46.851465 -59.363391)
			(xy 46.763171 -59.334856) (xy 46.720506 -59.31662) (xy 46.710566 -59.3128) (xy 46.689298 -59.3128)
			(xy 46.679358 -59.31662) (xy 46.636692 -59.334855) (xy 46.548401 -59.363401) (xy 46.457617 -59.382597)
			(xy 46.365328 -59.392233) (xy 46.318932 -59.39282) (xy 46.272537 -59.392225) (xy 46.180249 -59.382583)
			(xy 46.089465 -59.363391) (xy 46.001171 -59.334856) (xy 45.958506 -59.31662) (xy 45.948566 -59.3128)
			(xy 45.927298 -59.3128) (xy 45.917358 -59.31662) (xy 45.874692 -59.334855) (xy 45.786401 -59.363401)
			(xy 45.695617 -59.382597) (xy 45.603328 -59.392233) (xy 45.556932 -59.39282) (xy 45.51583 -59.392317)
			(xy 45.433976 -59.384735) (xy 45.35317 -59.369633) (xy 45.274103 -59.347139) (xy 45.197449 -59.317446)
			(xy 45.123861 -59.280806) (xy 45.053968 -59.237533) (xy 44.988366 -59.187996) (xy 44.927615 -59.132616)
			(xy 44.872233 -59.071868) (xy 44.822692 -59.006268) (xy 44.779415 -58.936377) (xy 44.742772 -58.862792)
			(xy 44.713075 -58.786139) (xy 44.690577 -58.707073) (xy 44.675471 -58.626268) (xy 44.667885 -58.544414)
			(xy 44.667424 -58.503312) (xy 42.939574 -58.503312) (xy 42.94278 -58.57062) (xy 42.93875 -58.655223)
			(xy 42.926696 -58.73906) (xy 42.906727 -58.821371) (xy 42.879025 -58.901411) (xy 42.84384 -58.978456)
			(xy 42.80149 -59.051807) (xy 42.75236 -59.120801) (xy 42.696894 -59.184812) (xy 42.635595 -59.243261)
			(xy 42.569017 -59.295618) (xy 42.497764 -59.341409) (xy 42.422481 -59.38022) (xy 42.343849 -59.4117)
			(xy 42.262581 -59.435562) (xy 42.179413 -59.451591) (xy 42.095097 -59.459642) (xy 42.052748 -59.46013)
			(xy 42.013816 -59.459687) (xy 41.936253 -59.452853) (xy 41.859585 -59.43926) (xy 41.7844 -59.419011)
			(xy 41.747694 -59.406028) (xy 41.739145 -59.403264) (xy 41.721191 -59.403264) (xy 41.712642 -59.406028)
			(xy 41.675933 -59.418999) (xy 41.600747 -59.43924) (xy 41.52408 -59.452838) (xy 41.446519 -59.459689)
			(xy 41.407588 -59.46013) (xy 41.365241 -59.459582) (xy 41.28093 -59.45153) (xy 41.197767 -59.435501)
			(xy 41.116504 -59.411639) (xy 41.037877 -59.38016) (xy 40.962598 -59.34135) (xy 40.891349 -59.295561)
			(xy 40.824775 -59.243206) (xy 40.76348 -59.18476) (xy 40.708017 -59.120752) (xy 40.65889 -59.051762)
			(xy 40.616543 -58.978414) (xy 40.58136 -58.901373) (xy 40.55366 -58.821337) (xy 40.533693 -58.73903)
			(xy 40.521639 -58.655198) (xy 40.517609 -58.5706) (xy 40.2431 -58.5706) (xy 40.246934 -58.575677)
			(xy 40.290205 -58.645568) (xy 40.326843 -58.719152) (xy 40.356535 -58.795804) (xy 40.379028 -58.874868)
			(xy 40.39413 -58.95567) (xy 40.401712 -59.037521) (xy 40.402256 -59.078622) (xy 40.401849 -59.116912)
			(xy 40.395247 -59.193207) (xy 40.382102 -59.268651) (xy 40.362513 -59.342683) (xy 40.349932 -59.37885)
			(xy 40.347293 -59.387288) (xy 40.3473 -59.404953) (xy 40.349932 -59.413394) (xy 40.362478 -59.449571)
			(xy 40.382059 -59.523603) (xy 40.395211 -59.599043) (xy 40.401836 -59.675333) (xy 40.402256 -59.713622)
			(xy 40.40178 -59.754725) (xy 40.394194 -59.836579) (xy 40.379087 -59.917384) (xy 40.35659 -59.996451)
			(xy 40.326893 -60.073105) (xy 40.290251 -60.146693) (xy 40.246976 -60.216585) (xy 40.197437 -60.282187)
			(xy 40.142056 -60.342938) (xy 40.081307 -60.39832) (xy 40.015706 -60.447861) (xy 39.945815 -60.491139)
			(xy 39.872229 -60.527783) (xy 39.795576 -60.557482) (xy 39.71651 -60.579981) (xy 39.635705 -60.59509)
			(xy 39.553851 -60.602679) (xy 39.512748 -60.60313) (xy 39.473179 -60.602709) (xy 39.394351 -60.595701)
			(xy 39.316457 -60.581718) (xy 39.240114 -60.560871) (xy 39.202868 -60.547504) (xy 39.194201 -60.544664)
			(xy 39.175975 -60.544664) (xy 39.167308 -60.547504) (xy 39.130063 -60.560873) (xy 39.053719 -60.581721)
			(xy 38.975826 -60.595703) (xy 38.896998 -60.60271) (xy 38.857428 -60.60313) (xy 38.819138 -60.60272)
			(xy 38.742844 -60.596114) (xy 38.667402 -60.582965) (xy 38.593372 -60.563371) (xy 38.5572 -60.550806)
			(xy 38.548762 -60.548164) (xy 38.531094 -60.548164) (xy 38.522656 -60.550806) (xy 38.486478 -60.563349)
			(xy 38.412446 -60.582924) (xy 38.337006 -60.59607) (xy 38.260716 -60.602691) (xy 38.222428 -60.60313)
			(xy 38.181324 -60.602671) (xy 38.099465 -60.595088) (xy 38.018656 -60.579985) (xy 37.939585 -60.55749)
			(xy 37.862927 -60.527795) (xy 37.789335 -60.491154) (xy 37.719439 -60.447878) (xy 37.653833 -60.398338)
			(xy 37.593079 -60.342957) (xy 37.537694 -60.282205) (xy 37.48815 -60.216602) (xy 37.444871 -60.146708)
			(xy 37.408225 -60.073119) (xy 37.378526 -59.996463) (xy 37.356026 -59.917393) (xy 37.340919 -59.836584)
			(xy 37.333331 -59.754726) (xy 37.33292 -59.713622) (xy 37.33333 -59.675332) (xy 37.339937 -59.599039)
			(xy 37.353087 -59.523597) (xy 37.372683 -59.449567) (xy 37.385244 -59.413394) (xy 37.387888 -59.404956)
			(xy 37.387895 -59.387285) (xy 37.385244 -59.37885) (xy 37.378132 -59.358784) (xy 37.373306 -59.344306)
			(xy 37.349684 -59.32551) (xy 37.226748 -59.314334) (xy 37.200078 -59.328558) (xy 37.192712 -59.341766)
			(xy 37.171465 -59.379413) (xy 37.122716 -59.450808) (xy 37.067271 -59.517137) (xy 37.005652 -59.577774)
			(xy 36.938441 -59.632147) (xy 36.866273 -59.679743) (xy 36.789827 -59.720114) (xy 36.709826 -59.752878)
			(xy 36.627023 -59.777726) (xy 36.5422 -59.794424) (xy 36.456157 -59.802814) (xy 36.412932 -59.803284)
			(xy 36.373363 -59.802863) (xy 36.294535 -59.795854) (xy 36.216642 -59.78187) (xy 36.140299 -59.761022)
			(xy 36.103052 -59.747658) (xy 36.094385 -59.744818) (xy 36.076159 -59.744818) (xy 36.067492 -59.747658)
			(xy 36.030247 -59.761026) (xy 35.953903 -59.781871) (xy 35.876009 -59.795851) (xy 35.797181 -59.802856)
			(xy 35.757612 -59.803284) (xy 35.718043 -59.802862) (xy 35.639216 -59.795851) (xy 35.561323 -59.781866)
			(xy 35.484981 -59.761017) (xy 35.447732 -59.747658) (xy 35.439065 -59.744818) (xy 35.420839 -59.744818)
			(xy 35.412172 -59.747658) (xy 35.374927 -59.761025) (xy 35.298583 -59.781868) (xy 35.220689 -59.795847)
			(xy 35.141861 -59.80285) (xy 35.102292 -59.803284) (xy 35.061189 -59.802823) (xy 34.979335 -59.795238)
			(xy 34.89853 -59.780132) (xy 34.819463 -59.757634) (xy 34.74281 -59.727937) (xy 34.669223 -59.691294)
			(xy 34.599332 -59.648018) (xy 34.533732 -59.598477) (xy 34.472982 -59.543095) (xy 34.417602 -59.482344)
			(xy 34.368064 -59.416742) (xy 34.32479 -59.346849) (xy 34.28815 -59.273261) (xy 34.258456 -59.196606)
			(xy 34.235961 -59.117539) (xy 34.220858 -59.036733) (xy 34.213275 -58.954879) (xy 34.212784 -58.913776)
			(xy 34.213227 -58.873696) (xy 34.220441 -58.79386) (xy 34.234811 -58.714998) (xy 34.256217 -58.637749)
			(xy 34.269934 -58.600086) (xy 34.272665 -58.591746) (xy 34.272934 -58.57421) (xy 34.270442 -58.565796)
			(xy 34.266886 -58.555128) (xy 34.263584 -58.544714) (xy 34.248344 -58.528458) (xy 34.238184 -58.52414)
			(xy 34.228766 -58.520805) (xy 34.208807 -58.52085) (xy 34.190367 -58.528487) (xy 34.176221 -58.542567)
			(xy 34.17189 -58.551572) (xy 32.666127 -62.18682) (xy 40.113202 -62.18682) (xy 40.117273 -62.131198)
			(xy 40.129399 -62.076761) (xy 40.149322 -62.02467) (xy 40.176618 -61.976035) (xy 40.210704 -61.931892)
			(xy 40.250853 -61.893183) (xy 40.296211 -61.860732) (xy 40.345811 -61.835231) (xy 40.398595 -61.817224)
			(xy 40.453438 -61.807094) (xy 40.509172 -61.805057) (xy 40.564609 -61.811157) (xy 40.618566 -61.825263)
			(xy 40.669895 -61.847075) (xy 40.717501 -61.876129) (xy 40.760369 -61.911804) (xy 40.797586 -61.953341)
			(xy 40.828359 -61.999854) (xy 40.852031 -62.050351) (xy 40.868099 -62.103758) (xy 40.876219 -62.158934)
			(xy 40.876728 -62.18682) (xy 40.876704 -62.188153) (xy 40.984867 -62.188153) (xy 40.984867 -62.133647)
			(xy 40.992625 -62.079695) (xy 41.007982 -62.027396) (xy 41.030626 -61.977815) (xy 41.060096 -61.931962)
			(xy 41.095792 -61.89077) (xy 41.136987 -61.855077) (xy 41.182843 -61.825611) (xy 41.232426 -61.802971)
			(xy 41.284726 -61.787618) (xy 41.338679 -61.779865) (xy 41.365932 -61.779404) (xy 41.394847 -61.77997)
			(xy 41.452016 -61.788689) (xy 41.507214 -61.805937) (xy 41.559176 -61.83132) (xy 41.606711 -61.864255)
			(xy 41.64873 -61.903988) (xy 41.666922 -61.92647) (xy 41.674467 -61.935249) (xy 41.695239 -61.94542)
			(xy 41.7068 -61.946028) (xy 41.787064 -61.946028) (xy 41.798633 -61.945462) (xy 41.819406 -61.935267)
			(xy 41.826942 -61.92647) (xy 41.845102 -61.90396) (xy 41.887129 -61.864228) (xy 41.934671 -61.831293)
			(xy 41.986638 -61.805909) (xy 42.041841 -61.788659) (xy 42.099014 -61.779936) (xy 42.127932 -61.779404)
			(xy 42.155183 -61.779868) (xy 42.209129 -61.787628) (xy 42.261421 -61.802987) (xy 42.310996 -61.825631)
			(xy 42.356844 -61.855099) (xy 42.357999 -61.8561) (xy 44.743084 -61.8561) (xy 44.747114 -61.771497)
			(xy 44.759168 -61.68766) (xy 44.779138 -61.605348) (xy 44.806841 -61.525307) (xy 44.842027 -61.448262)
			(xy 44.884377 -61.374911) (xy 44.933509 -61.305918) (xy 44.988976 -61.241907) (xy 45.050277 -61.183459)
			(xy 45.116856 -61.131103) (xy 45.18811 -61.085313) (xy 45.263395 -61.046503) (xy 45.342028 -61.015026)
			(xy 45.423297 -60.991166) (xy 45.506466 -60.975139) (xy 45.590782 -60.967091) (xy 45.633132 -60.966604)
			(xy 45.679527 -60.96721) (xy 45.771815 -60.976848) (xy 45.862599 -60.996037) (xy 45.950893 -61.024569)
			(xy 45.993558 -61.042804) (xy 46.003498 -61.046624) (xy 46.024766 -61.046624) (xy 46.034706 -61.042804)
			(xy 46.077364 -61.024549) (xy 46.165658 -60.996008) (xy 46.256444 -60.976817) (xy 46.348736 -60.967187)
			(xy 46.395132 -60.966604) (xy 46.441527 -60.96721) (xy 46.533815 -60.976848) (xy 46.624599 -60.996037)
			(xy 46.712893 -61.024569) (xy 46.755558 -61.042804) (xy 46.765498 -61.046624) (xy 46.786766 -61.046624)
			(xy 46.796706 -61.042804) (xy 46.839364 -61.024549) (xy 46.927658 -60.996008) (xy 47.018444 -60.976817)
			(xy 47.110736 -60.967187) (xy 47.157132 -60.966604) (xy 47.19948 -60.967085) (xy 47.283793 -60.975139)
			(xy 47.366958 -60.99117) (xy 47.448222 -61.015034) (xy 47.526851 -61.046515) (xy 47.602131 -61.085327)
			(xy 47.673381 -61.131119) (xy 47.739955 -61.183476) (xy 47.801252 -61.241924) (xy 47.856715 -61.305934)
			(xy 47.905843 -61.374926) (xy 47.94819 -61.448276) (xy 47.983373 -61.525319) (xy 48.011074 -61.605357)
			(xy 48.031041 -61.687666) (xy 48.043095 -61.7715) (xy 48.047125 -61.8561) (xy 48.043095 -61.9407)
			(xy 48.031041 -62.024534) (xy 48.011074 -62.106843) (xy 47.983373 -62.186881) (xy 47.94819 -62.263924)
			(xy 47.905843 -62.337274) (xy 47.856715 -62.406266) (xy 47.801252 -62.470276) (xy 47.739955 -62.528724)
			(xy 47.673381 -62.581081) (xy 47.602131 -62.626873) (xy 47.526851 -62.665685) (xy 47.448222 -62.697166)
			(xy 47.366958 -62.72103) (xy 47.283793 -62.737061) (xy 47.19948 -62.745115) (xy 47.157132 -62.74562)
			(xy 47.110737 -62.745025) (xy 47.018449 -62.735383) (xy 46.927665 -62.716191) (xy 46.839371 -62.687656)
			(xy 46.796706 -62.66942) (xy 46.786766 -62.6656) (xy 46.765498 -62.6656) (xy 46.755558 -62.66942)
			(xy 46.712892 -62.687655) (xy 46.624601 -62.716201) (xy 46.533817 -62.735397) (xy 46.441528 -62.745033)
			(xy 46.395132 -62.74562) (xy 46.348737 -62.745025) (xy 46.256449 -62.735383) (xy 46.165665 -62.716191)
			(xy 46.077371 -62.687656) (xy 46.034706 -62.66942) (xy 46.024766 -62.6656) (xy 46.003498 -62.6656)
			(xy 45.993558 -62.66942) (xy 45.950892 -62.687655) (xy 45.862601 -62.716201) (xy 45.771817 -62.735397)
			(xy 45.679528 -62.745033) (xy 45.633132 -62.74562) (xy 45.590782 -62.745109) (xy 45.506466 -62.737061)
			(xy 45.423297 -62.721034) (xy 45.342028 -62.697174) (xy 45.263395 -62.665697) (xy 45.18811 -62.626887)
			(xy 45.116856 -62.581097) (xy 45.050277 -62.528741) (xy 44.988976 -62.470293) (xy 44.933509 -62.406282)
			(xy 44.884377 -62.337289) (xy 44.842027 -62.263938) (xy 44.806841 -62.186893) (xy 44.779138 -62.106852)
			(xy 44.759168 -62.02454) (xy 44.747114 -61.940703) (xy 44.743084 -61.8561) (xy 42.357999 -61.8561)
			(xy 42.398031 -61.890791) (xy 42.433721 -61.931982) (xy 42.463185 -61.977832) (xy 42.485824 -62.027409)
			(xy 42.501178 -62.079703) (xy 42.508934 -62.133649) (xy 42.508934 -62.188151) (xy 42.501178 -62.242097)
			(xy 42.485824 -62.294391) (xy 42.463185 -62.343968) (xy 42.433721 -62.389818) (xy 42.398031 -62.431009)
			(xy 42.356844 -62.466701) (xy 42.310996 -62.496169) (xy 42.261421 -62.518813) (xy 42.209129 -62.534172)
			(xy 42.155183 -62.541932) (xy 42.127932 -62.54242) (xy 42.099014 -62.541909) (xy 42.041842 -62.533183)
			(xy 41.986641 -62.515926) (xy 41.934679 -62.490533) (xy 41.887145 -62.457586) (xy 41.84513 -62.417842)
			(xy 41.826942 -62.395354) (xy 41.819365 -62.386608) (xy 41.798617 -62.376418) (xy 41.787064 -62.375796)
			(xy 41.7068 -62.375796) (xy 41.695232 -62.376368) (xy 41.674462 -62.386562) (xy 41.666922 -62.395354)
			(xy 41.648732 -62.417838) (xy 41.606711 -62.457571) (xy 41.559175 -62.490508) (xy 41.507214 -62.515896)
			(xy 41.452017 -62.533153) (xy 41.394848 -62.541884) (xy 41.365932 -62.54242) (xy 41.338679 -62.541935)
			(xy 41.284726 -62.534182) (xy 41.232426 -62.518829) (xy 41.182843 -62.496189) (xy 41.136987 -62.466723)
			(xy 41.095792 -62.43103) (xy 41.060096 -62.389838) (xy 41.030626 -62.343985) (xy 41.007982 -62.294404)
			(xy 40.992625 -62.242105) (xy 40.984867 -62.188153) (xy 40.876704 -62.188153) (xy 40.876219 -62.214706)
			(xy 40.868099 -62.269882) (xy 40.852031 -62.323289) (xy 40.828359 -62.373786) (xy 40.797586 -62.420299)
			(xy 40.760369 -62.461836) (xy 40.717501 -62.497511) (xy 40.669895 -62.526565) (xy 40.618566 -62.548377)
			(xy 40.564609 -62.562483) (xy 40.509172 -62.568583) (xy 40.453438 -62.566546) (xy 40.398595 -62.556416)
			(xy 40.345811 -62.538409) (xy 40.296211 -62.512908) (xy 40.250853 -62.480457) (xy 40.210704 -62.441748)
			(xy 40.176618 -62.397605) (xy 40.149322 -62.34897) (xy 40.129399 -62.296879) (xy 40.117273 -62.242442)
			(xy 40.113202 -62.18682) (xy 32.666127 -62.18682) (xy 32.495582 -62.598554) (xy 35.658042 -62.598554)
			(xy 35.662113 -62.542932) (xy 35.674239 -62.488495) (xy 35.694162 -62.436404) (xy 35.721458 -62.387769)
			(xy 35.755544 -62.343626) (xy 35.795693 -62.304917) (xy 35.841051 -62.272466) (xy 35.890651 -62.246965)
			(xy 35.943435 -62.228958) (xy 35.998278 -62.218828) (xy 36.054012 -62.216791) (xy 36.109449 -62.222891)
			(xy 36.163406 -62.236997) (xy 36.214735 -62.258809) (xy 36.262341 -62.287863) (xy 36.305209 -62.323538)
			(xy 36.342426 -62.365075) (xy 36.373199 -62.411588) (xy 36.396871 -62.462085) (xy 36.412939 -62.515492)
			(xy 36.421059 -62.570668) (xy 36.421568 -62.598554) (xy 36.421059 -62.62644) (xy 36.412939 -62.681616)
			(xy 36.396871 -62.735023) (xy 36.373199 -62.78552) (xy 36.342426 -62.832033) (xy 36.305209 -62.87357)
			(xy 36.262341 -62.909245) (xy 36.214735 -62.938299) (xy 36.163406 -62.960111) (xy 36.109449 -62.974217)
			(xy 36.054012 -62.980317) (xy 35.998278 -62.97828) (xy 35.943435 -62.96815) (xy 35.890651 -62.950143)
			(xy 35.841051 -62.924642) (xy 35.795693 -62.892191) (xy 35.755544 -62.853482) (xy 35.721458 -62.809339)
			(xy 35.694162 -62.760704) (xy 35.674239 -62.708613) (xy 35.662113 -62.654176) (xy 35.658042 -62.598554)
			(xy 32.495582 -62.598554) (xy 32.240553 -63.21425) (xy 34.541712 -63.21425) (xy 34.545783 -63.158628)
			(xy 34.557909 -63.104191) (xy 34.577832 -63.0521) (xy 34.605128 -63.003465) (xy 34.639214 -62.959322)
			(xy 34.679363 -62.920613) (xy 34.724721 -62.888162) (xy 34.774321 -62.862661) (xy 34.827105 -62.844654)
			(xy 34.881948 -62.834524) (xy 34.937682 -62.832487) (xy 34.993119 -62.838587) (xy 35.047076 -62.852693)
			(xy 35.098405 -62.874505) (xy 35.146011 -62.903559) (xy 35.188879 -62.939234) (xy 35.226096 -62.980771)
			(xy 35.256869 -63.027284) (xy 35.280541 -63.077781) (xy 35.296609 -63.131188) (xy 35.304729 -63.186364)
			(xy 35.305238 -63.21425) (xy 35.304729 -63.242136) (xy 35.296609 -63.297312) (xy 35.280541 -63.350719)
			(xy 35.256869 -63.401216) (xy 35.226096 -63.447729) (xy 35.188879 -63.489266) (xy 35.146011 -63.524941)
			(xy 35.098405 -63.553995) (xy 35.047076 -63.575807) (xy 34.993119 -63.589913) (xy 34.937682 -63.596013)
			(xy 34.881948 -63.593976) (xy 34.827105 -63.583846) (xy 34.774321 -63.565839) (xy 34.724721 -63.540338)
			(xy 34.679363 -63.507887) (xy 34.639214 -63.469178) (xy 34.605128 -63.425035) (xy 34.577832 -63.3764)
			(xy 34.557909 -63.324309) (xy 34.545783 -63.269872) (xy 34.541712 -63.21425) (xy 32.240553 -63.21425)
			(xy 32.214566 -63.276988) (xy 32.211115 -63.286604) (xy 32.211321 -63.307014) (xy 32.219439 -63.325743)
			(xy 32.226504 -63.333122) (xy 32.30626 -63.409576) (xy 32.33674 -63.414656) (xy 32.351218 -63.408052)
			(xy 32.37652 -63.396828) (xy 32.429556 -63.380986) (xy 32.484325 -63.372982) (xy 32.512 -63.372492)
			(xy 32.539251 -63.372978) (xy 32.593199 -63.380734) (xy 32.645494 -63.396089) (xy 32.695071 -63.418731)
			(xy 32.740921 -63.448197) (xy 32.782112 -63.483888) (xy 32.817803 -63.525079) (xy 32.847269 -63.570929)
			(xy 32.869911 -63.620506) (xy 32.885266 -63.672801) (xy 32.893022 -63.726749) (xy 32.893022 -63.781251)
			(xy 32.885266 -63.835199) (xy 32.869911 -63.887494) (xy 32.847269 -63.937071) (xy 32.817803 -63.982921)
			(xy 32.782112 -64.024112) (xy 32.740921 -64.059803) (xy 32.695071 -64.089269) (xy 32.645494 -64.111911)
			(xy 32.593199 -64.127266) (xy 32.539251 -64.135022) (xy 32.512 -64.135508) (xy 32.482885 -64.134966)
			(xy 32.425328 -64.126135) (xy 32.36978 -64.108661) (xy 32.317533 -64.082952) (xy 32.269798 -64.049602)
			(xy 32.227683 -64.009388) (xy 32.192167 -63.963243) (xy 32.164074 -63.912237) (xy 32.153606 -63.885064)
			(xy 32.148272 -63.870078) (xy 32.122872 -63.852044) (xy 32.012382 -63.849758) (xy 32.002191 -63.850006)
			(xy 31.983261 -63.857522) (xy 31.968711 -63.871775) (xy 31.964376 -63.881) (xy 31.744158 -64.41313)
			(xy 31.742387 -64.417758) (xy 31.740472 -64.42748) (xy 31.740348 -64.432434) (xy 31.740348 -66.294)
			(xy 34.288982 -66.294) (xy 34.293053 -66.238378) (xy 34.305179 -66.183941) (xy 34.325102 -66.13185)
			(xy 34.352398 -66.083215) (xy 34.386484 -66.039072) (xy 34.426633 -66.000363) (xy 34.471991 -65.967912)
			(xy 34.521591 -65.942411) (xy 34.574375 -65.924404) (xy 34.629218 -65.914274) (xy 34.684952 -65.912237)
			(xy 34.740389 -65.918337) (xy 34.794346 -65.932443) (xy 34.845675 -65.954255) (xy 34.893281 -65.983309)
			(xy 34.936149 -66.018984) (xy 34.973366 -66.060521) (xy 35.004139 -66.107034) (xy 35.027811 -66.157531)
			(xy 35.043879 -66.210938) (xy 35.051999 -66.266114) (xy 35.052508 -66.294) (xy 35.051999 -66.321886)
			(xy 35.043879 -66.377062) (xy 35.027811 -66.430469) (xy 35.004139 -66.480966) (xy 34.973366 -66.527479)
			(xy 34.936149 -66.569016) (xy 34.893281 -66.604691) (xy 34.845675 -66.633745) (xy 34.794346 -66.655557)
			(xy 34.740389 -66.669663) (xy 34.684952 -66.675763) (xy 34.629218 -66.673726) (xy 34.574375 -66.663596)
			(xy 34.521591 -66.645589) (xy 34.471991 -66.620088) (xy 34.426633 -66.587637) (xy 34.386484 -66.548928)
			(xy 34.352398 -66.504785) (xy 34.325102 -66.45615) (xy 34.305179 -66.404059) (xy 34.293053 -66.349622)
			(xy 34.288982 -66.294) (xy 31.740348 -66.294) (xy 31.740348 -70.669912) (xy 37.082982 -70.669912)
			(xy 37.087053 -70.61429) (xy 37.099179 -70.559853) (xy 37.119102 -70.507762) (xy 37.146398 -70.459127)
			(xy 37.180484 -70.414984) (xy 37.220633 -70.376275) (xy 37.265991 -70.343824) (xy 37.315591 -70.318323)
			(xy 37.368375 -70.300316) (xy 37.423218 -70.290186) (xy 37.478952 -70.288149) (xy 37.534389 -70.294249)
			(xy 37.588346 -70.308355) (xy 37.639675 -70.330167) (xy 37.687281 -70.359221) (xy 37.730149 -70.394896)
			(xy 37.767366 -70.436433) (xy 37.798139 -70.482946) (xy 37.821811 -70.533443) (xy 37.837879 -70.58685)
			(xy 37.845999 -70.642026) (xy 37.846508 -70.669912) (xy 37.845999 -70.697798) (xy 37.837879 -70.752974)
			(xy 37.821811 -70.806381) (xy 37.798139 -70.856878) (xy 37.767366 -70.903391) (xy 37.730149 -70.944928)
			(xy 37.687281 -70.980603) (xy 37.639675 -71.009657) (xy 37.588346 -71.031469) (xy 37.534389 -71.045575)
			(xy 37.478952 -71.051675) (xy 37.423218 -71.049638) (xy 37.368375 -71.039508) (xy 37.315591 -71.021501)
			(xy 37.265991 -70.996) (xy 37.220633 -70.963549) (xy 37.180484 -70.92484) (xy 37.146398 -70.880697)
			(xy 37.119102 -70.832062) (xy 37.099179 -70.779971) (xy 37.087053 -70.725534) (xy 37.082982 -70.669912)
			(xy 31.740348 -70.669912) (xy 31.740348 -73.463912) (xy 31.99892 -73.463912) (xy 31.999439 -73.434995)
			(xy 32.008167 -73.377824) (xy 32.025424 -73.322624) (xy 32.050816 -73.270663) (xy 32.083759 -73.223129)
			(xy 32.1235 -73.181112) (xy 32.145986 -73.162922) (xy 32.154731 -73.155344) (xy 32.164925 -73.134598)
			(xy 32.165544 -73.123044) (xy 32.165544 -73.04278) (xy 32.164947 -73.031215) (xy 32.154773 -73.010442)
			(xy 32.145986 -73.002902) (xy 32.123501 -72.984713) (xy 32.083766 -72.942693) (xy 32.050828 -72.895157)
			(xy 32.02544 -72.843196) (xy 32.008184 -72.787998) (xy 31.999455 -72.730828) (xy 31.99892 -72.701912)
			(xy 31.999367 -72.674658) (xy 32.007123 -72.620705) (xy 32.022479 -72.568405) (xy 32.045122 -72.518823)
			(xy 32.074591 -72.472969) (xy 32.110287 -72.431775) (xy 32.151482 -72.396081) (xy 32.197337 -72.366614)
			(xy 32.24692 -72.343973) (xy 32.299221 -72.328619) (xy 32.353174 -72.320865) (xy 32.380428 -72.320404)
			(xy 32.409343 -72.320972) (xy 32.466512 -72.329691) (xy 32.52171 -72.346939) (xy 32.573672 -72.372321)
			(xy 32.621207 -72.405256) (xy 32.663226 -72.444988) (xy 32.681418 -72.46747) (xy 32.688964 -72.476247)
			(xy 32.709735 -72.486419) (xy 32.721296 -72.487028) (xy 32.80156 -72.487028) (xy 32.813129 -72.486459)
			(xy 32.833901 -72.476266) (xy 32.841438 -72.46747) (xy 32.858191 -72.446687) (xy 32.896545 -72.409557)
			(xy 32.939699 -72.378135) (xy 32.986813 -72.353036) (xy 33.036965 -72.33475) (xy 33.089176 -72.323633)
			(xy 33.142428 -72.319903) (xy 33.19568 -72.323633) (xy 33.247891 -72.33475) (xy 33.298043 -72.353036)
			(xy 33.345157 -72.378135) (xy 33.388311 -72.409557) (xy 33.426665 -72.446687) (xy 33.443418 -72.46747)
			(xy 33.450964 -72.476247) (xy 33.471735 -72.486419) (xy 33.483296 -72.487028) (xy 33.56356 -72.487028)
			(xy 33.575129 -72.486459) (xy 33.595901 -72.476266) (xy 33.603438 -72.46747) (xy 33.620191 -72.446687)
			(xy 33.658545 -72.409557) (xy 33.701699 -72.378135) (xy 33.748813 -72.353036) (xy 33.798965 -72.33475)
			(xy 33.851176 -72.323633) (xy 33.904428 -72.319903) (xy 33.95768 -72.323633) (xy 34.009891 -72.33475)
			(xy 34.060043 -72.353036) (xy 34.107157 -72.378135) (xy 34.150311 -72.409557) (xy 34.188665 -72.446687)
			(xy 34.205418 -72.46747) (xy 34.212964 -72.476247) (xy 34.233735 -72.486419) (xy 34.245296 -72.487028)
			(xy 34.32556 -72.487028) (xy 34.337129 -72.486459) (xy 34.357901 -72.476266) (xy 34.365438 -72.46747)
			(xy 34.3836 -72.444962) (xy 34.425627 -72.40523) (xy 34.473168 -72.372295) (xy 34.525135 -72.346911)
			(xy 34.580337 -72.329659) (xy 34.63751 -72.320936) (xy 34.666428 -72.320404) (xy 34.69368 -72.320852)
			(xy 34.74763 -72.328612) (xy 34.799926 -72.343972) (xy 34.849505 -72.366617) (xy 34.895355 -72.396087)
			(xy 34.936546 -72.431783) (xy 34.972237 -72.472977) (xy 35.001702 -72.518831) (xy 35.024342 -72.568411)
			(xy 35.039696 -72.620709) (xy 35.047451 -72.674659) (xy 35.047936 -72.701912) (xy 35.047379 -72.730828)
			(xy 35.038661 -72.787998) (xy 35.021413 -72.843197) (xy 34.996028 -72.89516) (xy 34.96309 -72.942694)
			(xy 34.923354 -72.984712) (xy 34.90087 -73.002902) (xy 34.892107 -73.010462) (xy 34.881925 -73.031222)
			(xy 34.881312 -73.04278) (xy 34.881312 -73.123044) (xy 34.881911 -73.134608) (xy 34.892085 -73.15538)
			(xy 34.90087 -73.162922) (xy 34.923358 -73.181108) (xy 34.963094 -73.223128) (xy 34.996033 -73.270664)
			(xy 35.021421 -73.322626) (xy 35.038676 -73.377825) (xy 35.047403 -73.434996) (xy 35.047936 -73.463912)
			(xy 35.047433 -73.491162) (xy 35.039676 -73.545108) (xy 35.024321 -73.597401) (xy 35.00168 -73.646976)
			(xy 34.972215 -73.692825) (xy 34.936526 -73.734014) (xy 34.895338 -73.769706) (xy 34.84949 -73.799173)
			(xy 34.799916 -73.821815) (xy 34.747624 -73.837173) (xy 34.693678 -73.844932) (xy 34.666428 -73.84542)
			(xy 34.63751 -73.844912) (xy 34.580337 -73.836185) (xy 34.525137 -73.818927) (xy 34.473175 -73.793534)
			(xy 34.425641 -73.760587) (xy 34.383626 -73.720842) (xy 34.365438 -73.698354) (xy 34.357863 -73.689606)
			(xy 34.337114 -73.679417) (xy 34.32556 -73.678796) (xy 34.245296 -73.678796) (xy 34.233728 -73.679366)
			(xy 34.212957 -73.689561) (xy 34.205418 -73.698354) (xy 34.188665 -73.719137) (xy 34.150311 -73.756267)
			(xy 34.107157 -73.787689) (xy 34.060043 -73.812788) (xy 34.009891 -73.831074) (xy 33.95768 -73.842191)
			(xy 33.904428 -73.845921) (xy 33.851176 -73.842191) (xy 33.798965 -73.831074) (xy 33.748813 -73.812788)
			(xy 33.701699 -73.787689) (xy 33.658545 -73.756267) (xy 33.620191 -73.719137) (xy 33.603438 -73.698354)
			(xy 33.595863 -73.689606) (xy 33.575114 -73.679417) (xy 33.56356 -73.678796) (xy 33.483296 -73.678796)
			(xy 33.471728 -73.679366) (xy 33.450957 -73.689561) (xy 33.443418 -73.698354) (xy 33.426665 -73.719137)
			(xy 33.388311 -73.756267) (xy 33.345157 -73.787689) (xy 33.298043 -73.812788) (xy 33.247891 -73.831074)
			(xy 33.19568 -73.842191) (xy 33.142428 -73.845921) (xy 33.089176 -73.842191) (xy 33.036965 -73.831074)
			(xy 32.986813 -73.812788) (xy 32.939699 -73.787689) (xy 32.896545 -73.756267) (xy 32.858191 -73.719137)
			(xy 32.841438 -73.698354) (xy 32.833863 -73.689606) (xy 32.813114 -73.679417) (xy 32.80156 -73.678796)
			(xy 32.721296 -73.678796) (xy 32.709728 -73.679366) (xy 32.688957 -73.689561) (xy 32.681418 -73.698354)
			(xy 32.66323 -73.72084) (xy 32.621208 -73.760573) (xy 32.573672 -73.79351) (xy 32.521711 -73.818897)
			(xy 32.466513 -73.836154) (xy 32.409344 -73.844884) (xy 32.380428 -73.84542) (xy 32.353176 -73.844919)
			(xy 32.299227 -73.837166) (xy 32.246931 -73.821814) (xy 32.197352 -73.799176) (xy 32.151499 -73.769712)
			(xy 32.110306 -73.734022) (xy 32.074612 -73.692833) (xy 32.045144 -73.646983) (xy 32.0225 -73.597406)
			(xy 32.007143 -73.545112) (xy 31.999384 -73.491164) (xy 31.99892 -73.463912) (xy 31.740348 -73.463912)
			(xy 31.740348 -76.666153) (xy 36.825367 -76.666153) (xy 36.825367 -76.611647) (xy 36.833125 -76.557695)
			(xy 36.848482 -76.505397) (xy 36.871126 -76.455816) (xy 36.900595 -76.409963) (xy 36.936291 -76.368771)
			(xy 36.977486 -76.333079) (xy 37.023341 -76.303612) (xy 37.072923 -76.280972) (xy 37.125222 -76.265619)
			(xy 37.179175 -76.257865) (xy 37.206428 -76.257404) (xy 37.235343 -76.257972) (xy 37.292512 -76.266691)
			(xy 37.34771 -76.283939) (xy 37.399672 -76.309321) (xy 37.447207 -76.342256) (xy 37.489226 -76.381988)
			(xy 37.507418 -76.40447) (xy 37.514964 -76.413247) (xy 37.535735 -76.423419) (xy 37.547296 -76.424028)
			(xy 37.62756 -76.424028) (xy 37.639129 -76.423459) (xy 37.659901 -76.413266) (xy 37.667438 -76.40447)
			(xy 37.6856 -76.381962) (xy 37.727627 -76.34223) (xy 37.775168 -76.309295) (xy 37.827135 -76.283911)
			(xy 37.882337 -76.266659) (xy 37.93951 -76.257936) (xy 37.968428 -76.257404) (xy 37.995679 -76.257868)
			(xy 38.049625 -76.265628) (xy 38.101918 -76.280986) (xy 38.151493 -76.303629) (xy 38.197342 -76.333097)
			(xy 38.23853 -76.36879) (xy 38.27422 -76.409981) (xy 38.303684 -76.455831) (xy 38.326324 -76.505408)
			(xy 38.341678 -76.557702) (xy 38.349434 -76.611649) (xy 38.349434 -76.666151) (xy 38.341678 -76.720098)
			(xy 38.326324 -76.772392) (xy 38.303684 -76.821969) (xy 38.27422 -76.867819) (xy 38.23853 -76.90901)
			(xy 38.197342 -76.944703) (xy 38.151493 -76.974171) (xy 38.101918 -76.996814) (xy 38.049625 -77.012172)
			(xy 37.995679 -77.019932) (xy 37.968428 -77.02042) (xy 37.93951 -77.019912) (xy 37.882337 -77.011185)
			(xy 37.827137 -76.993927) (xy 37.775175 -76.968534) (xy 37.727641 -76.935587) (xy 37.685626 -76.895842)
			(xy 37.667438 -76.873354) (xy 37.659863 -76.864606) (xy 37.639114 -76.854417) (xy 37.62756 -76.853796)
			(xy 37.547296 -76.853796) (xy 37.535728 -76.854366) (xy 37.514957 -76.864561) (xy 37.507418 -76.873354)
			(xy 37.48923 -76.89584) (xy 37.447208 -76.935573) (xy 37.399672 -76.96851) (xy 37.347711 -76.993897)
			(xy 37.292513 -77.011154) (xy 37.235344 -77.019884) (xy 37.206428 -77.02042) (xy 37.179175 -77.019935)
			(xy 37.125222 -77.012181) (xy 37.072923 -76.996828) (xy 37.023341 -76.974188) (xy 36.977486 -76.944721)
			(xy 36.936291 -76.909029) (xy 36.900595 -76.867837) (xy 36.871126 -76.821984) (xy 36.848482 -76.772403)
			(xy 36.833125 -76.720105) (xy 36.825367 -76.666153) (xy 31.740348 -76.666153) (xy 31.740348 -78.474062)
			(xy 31.740703 -78.483145) (xy 31.747035 -78.500168) (xy 31.758943 -78.513884) (xy 31.766764 -78.518512)
			(xy 31.857696 -78.568042) (xy 31.885128 -78.567026) (xy 31.897066 -78.559152) (xy 31.933095 -78.536431)
			(xy 32.008706 -78.497198) (xy 32.087721 -78.46537) (xy 32.169416 -78.441239) (xy 32.253042 -78.425025)
			(xy 32.337836 -78.416877) (xy 32.380428 -78.416404) (xy 32.426824 -78.41699) (xy 32.519113 -78.426626)
			(xy 32.609897 -78.445822) (xy 32.698188 -78.474369) (xy 32.740854 -78.492604) (xy 32.750794 -78.496424)
			(xy 32.772062 -78.496424) (xy 32.782002 -78.492604) (xy 32.824667 -78.474367) (xy 32.912961 -78.445831)
			(xy 33.003744 -78.426638) (xy 33.096033 -78.416996) (xy 33.142428 -78.416404) (xy 33.188824 -78.41699)
			(xy 33.281113 -78.426626) (xy 33.371897 -78.445822) (xy 33.460188 -78.474369) (xy 33.502854 -78.492604)
			(xy 33.512794 -78.496424) (xy 33.534062 -78.496424) (xy 33.544002 -78.492604) (xy 33.586667 -78.474367)
			(xy 33.674961 -78.445831) (xy 33.765744 -78.426638) (xy 33.858033 -78.416996) (xy 33.904428 -78.416404)
			(xy 33.945529 -78.41688) (xy 34.027381 -78.424467) (xy 34.108184 -78.439574) (xy 34.187249 -78.462072)
			(xy 34.2639 -78.49177) (xy 34.337484 -78.528413) (xy 34.407373 -78.571689) (xy 34.472971 -78.621228)
			(xy 34.533719 -78.67661) (xy 34.589097 -78.73736) (xy 34.638634 -78.80296) (xy 34.681907 -78.872851)
			(xy 34.718547 -78.946437) (xy 34.74824 -79.023089) (xy 34.770735 -79.102155) (xy 34.785838 -79.182958)
			(xy 34.793422 -79.264811) (xy 34.793936 -79.305912) (xy 34.793351 -79.352308) (xy 34.783716 -79.444598)
			(xy 34.764523 -79.535383) (xy 34.735979 -79.623675) (xy 34.717736 -79.666338) (xy 34.713921 -79.676278)
			(xy 34.713926 -79.697544) (xy 34.717736 -79.707486) (xy 34.735973 -79.750151) (xy 34.764509 -79.838445)
			(xy 34.783703 -79.929228) (xy 34.793347 -80.021517) (xy 34.793936 -80.067912) (xy 34.793461 -80.109015)
			(xy 34.785875 -80.190869) (xy 34.770769 -80.271674) (xy 34.756478 -80.3219) (xy 36.316384 -80.3219)
			(xy 36.320414 -80.237297) (xy 36.332468 -80.15346) (xy 36.352437 -80.071149) (xy 36.38014 -79.991108)
			(xy 36.415326 -79.914064) (xy 36.457676 -79.840712) (xy 36.506808 -79.771719) (xy 36.562275 -79.707709)
			(xy 36.623575 -79.649261) (xy 36.690154 -79.596905) (xy 36.761408 -79.551114) (xy 36.836693 -79.512305)
			(xy 36.915325 -79.480827) (xy 36.996594 -79.456967) (xy 37.079763 -79.440939) (xy 37.164078 -79.432891)
			(xy 37.206428 -79.432404) (xy 37.252823 -79.433011) (xy 37.345111 -79.442649) (xy 37.435894 -79.461838)
			(xy 37.524189 -79.490369) (xy 37.566854 -79.508604) (xy 37.576794 -79.512424) (xy 37.598062 -79.512424)
			(xy 37.608002 -79.508604) (xy 37.650661 -79.490351) (xy 37.738954 -79.461809) (xy 37.82974 -79.442618)
			(xy 37.922032 -79.432987) (xy 37.968428 -79.432404) (xy 38.010776 -79.432885) (xy 38.095089 -79.440938)
			(xy 38.178254 -79.456969) (xy 38.259519 -79.480833) (xy 38.338148 -79.512314) (xy 38.413428 -79.551126)
			(xy 38.484679 -79.596917) (xy 38.551254 -79.649274) (xy 38.61255 -79.707723) (xy 38.624229 -79.721202)
			(xy 38.932104 -79.721202) (xy 38.93255 -79.682914) (xy 38.939168 -79.606624) (xy 38.952312 -79.531184)
			(xy 38.971886 -79.457152) (xy 38.984428 -79.420974) (xy 38.987068 -79.412536) (xy 38.987068 -79.394868)
			(xy 38.984428 -79.38643) (xy 38.971873 -79.350255) (xy 38.952276 -79.276226) (xy 38.939124 -79.200785)
			(xy 38.932515 -79.124491) (xy 38.932104 -79.086202) (xy 38.932554 -79.045099) (xy 38.940139 -78.963242)
			(xy 38.955245 -78.882435) (xy 38.977742 -78.803366) (xy 39.007438 -78.726711) (xy 39.044081 -78.653122)
			(xy 39.087358 -78.583228) (xy 39.136899 -78.517626) (xy 39.192282 -78.456875) (xy 39.253034 -78.401493)
			(xy 39.318637 -78.351952) (xy 39.388531 -78.308676) (xy 39.46212 -78.272034) (xy 39.538776 -78.242338)
			(xy 39.617845 -78.219842) (xy 39.698652 -78.204738) (xy 39.780509 -78.197154) (xy 39.821612 -78.196694)
			(xy 39.861181 -78.197117) (xy 39.940009 -78.204123) (xy 40.017903 -78.218105) (xy 40.094247 -78.238951)
			(xy 40.131492 -78.25232) (xy 40.140159 -78.25516) (xy 40.158385 -78.25516) (xy 40.167052 -78.25232)
			(xy 40.204298 -78.238955) (xy 40.280642 -78.218108) (xy 40.358535 -78.204124) (xy 40.437363 -78.197115)
			(xy 40.476932 -78.196694) (xy 40.51522 -78.197131) (xy 40.59151 -78.203752) (xy 40.66695 -78.216898)
			(xy 40.740982 -78.236474) (xy 40.77716 -78.249018) (xy 40.785598 -78.25166) (xy 40.803266 -78.25166)
			(xy 40.811704 -78.249018) (xy 40.847876 -78.236453) (xy 40.921906 -78.216859) (xy 40.997348 -78.20371)
			(xy 41.073642 -78.197103) (xy 41.111932 -78.196694) (xy 41.153035 -78.197136) (xy 41.23489 -78.204724)
			(xy 41.315696 -78.219832) (xy 41.394764 -78.242331) (xy 41.471418 -78.272029) (xy 41.545005 -78.308674)
			(xy 41.614897 -78.351951) (xy 41.680498 -78.401493) (xy 41.741248 -78.456876) (xy 41.796629 -78.517628)
			(xy 41.846168 -78.583231) (xy 41.889443 -78.653125) (xy 41.926084 -78.726713) (xy 41.95578 -78.803369)
			(xy 41.978276 -78.882437) (xy 41.993381 -78.963243) (xy 42.000965 -79.045099) (xy 42.00144 -79.086202)
			(xy 42.000992 -79.12449) (xy 41.994374 -79.20078) (xy 41.981231 -79.276219) (xy 41.961658 -79.350252)
			(xy 41.949116 -79.38643) (xy 41.946473 -79.394868) (xy 41.946473 -79.412536) (xy 41.949116 -79.420974)
			(xy 41.956228 -79.44104) (xy 41.961054 -79.455518) (xy 41.984676 -79.474314) (xy 42.107612 -79.48549)
			(xy 42.134282 -79.471266) (xy 42.141648 -79.458058) (xy 42.162857 -79.420391) (xy 42.211614 -79.349001)
			(xy 42.267066 -79.282678) (xy 42.32869 -79.222047) (xy 42.395906 -79.16768) (xy 42.468078 -79.12009)
			(xy 42.544527 -79.079726) (xy 42.624531 -79.046969) (xy 42.707336 -79.022128) (xy 42.79216 -79.005436)
			(xy 42.878203 -78.997052) (xy 42.921428 -78.99654) (xy 42.960998 -78.996961) (xy 43.039826 -79.003968)
			(xy 43.117719 -79.01795) (xy 43.194063 -79.038797) (xy 43.231308 -79.052166) (xy 43.239975 -79.055006)
			(xy 43.258201 -79.055006) (xy 43.266868 -79.052166) (xy 43.304113 -79.038798) (xy 43.380457 -79.017951)
			(xy 43.458351 -79.003969) (xy 43.537179 -78.996961) (xy 43.576748 -78.99654) (xy 43.615036 -78.996969)
			(xy 43.691327 -79.003592) (xy 43.766766 -79.016741) (xy 43.840799 -79.036319) (xy 43.876976 -79.048864)
			(xy 43.885414 -79.051506) (xy 43.903082 -79.051506) (xy 43.91152 -79.048864) (xy 43.947689 -79.036292)
			(xy 44.021721 -79.0167) (xy 44.097164 -79.003553) (xy 44.173458 -78.996949) (xy 44.211748 -78.99654)
			(xy 44.252853 -78.996921) (xy 44.334711 -79.004511) (xy 44.41552 -79.019621) (xy 44.49459 -79.042123)
			(xy 44.571246 -79.071824) (xy 44.644835 -79.108472) (xy 44.714729 -79.151754) (xy 44.78033 -79.2013)
			(xy 44.841081 -79.256687) (xy 44.896462 -79.317443) (xy 44.946 -79.383051) (xy 44.989274 -79.452949)
			(xy 45.025914 -79.526542) (xy 45.055608 -79.603201) (xy 45.078101 -79.682274) (xy 45.093203 -79.763084)
			(xy 45.100784 -79.844943) (xy 45.101256 -79.886048) (xy 45.100827 -79.924336) (xy 45.094204 -80.000627)
			(xy 45.081055 -80.076066) (xy 45.061477 -80.150099) (xy 45.048932 -80.186276) (xy 45.046265 -80.194708)
			(xy 45.046281 -80.212382) (xy 45.048932 -80.22082) (xy 45.061504 -80.256989) (xy 45.081096 -80.331021)
			(xy 45.094243 -80.406464) (xy 45.100847 -80.482758) (xy 45.101256 -80.521048) (xy 45.100779 -80.56215)
			(xy 45.093191 -80.644003) (xy 45.078082 -80.724806) (xy 45.055583 -80.803871) (xy 45.025886 -80.880523)
			(xy 44.989243 -80.954108) (xy 44.945967 -81.023998) (xy 44.896427 -81.089598) (xy 44.841047 -81.150347)
			(xy 44.780298 -81.205727) (xy 44.714698 -81.255267) (xy 44.644808 -81.298543) (xy 44.571223 -81.335186)
			(xy 44.494571 -81.364883) (xy 44.415506 -81.387382) (xy 44.334703 -81.402491) (xy 44.25285 -81.410079)
			(xy 44.211748 -81.410556) (xy 44.172816 -81.410118) (xy 44.095252 -81.403283) (xy 44.018584 -81.389688)
			(xy 43.9434 -81.369438) (xy 43.906694 -81.356454) (xy 43.898145 -81.35369) (xy 43.880191 -81.35369)
			(xy 43.871642 -81.356454) (xy 43.834933 -81.369427) (xy 43.759747 -81.389667) (xy 43.68308 -81.403265)
			(xy 43.605519 -81.410115) (xy 43.566588 -81.410556) (xy 43.527656 -81.410136) (xy 43.450092 -81.403296)
			(xy 43.373423 -81.389696) (xy 43.298239 -81.36944) (xy 43.261534 -81.356454) (xy 43.252985 -81.35369)
			(xy 43.235031 -81.35369) (xy 43.226482 -81.356454) (xy 43.189769 -81.369415) (xy 43.114584 -81.389659)
			(xy 43.037919 -81.403259) (xy 42.960359 -81.410113) (xy 42.921428 -81.410556) (xy 42.880327 -81.410007)
			(xy 42.798477 -81.402425) (xy 42.717674 -81.387323) (xy 42.63861 -81.364831) (xy 42.561959 -81.335139)
			(xy 42.488374 -81.298501) (xy 42.418483 -81.255231) (xy 42.352883 -81.205696) (xy 42.292134 -81.15032)
			(xy 42.236752 -81.089575) (xy 42.187212 -81.023979) (xy 42.143936 -80.954092) (xy 42.107292 -80.880511)
			(xy 42.077594 -80.803862) (xy 42.055094 -80.7248) (xy 42.039986 -80.643999) (xy 42.032397 -80.562149)
			(xy 42.03192 -80.521048) (xy 42.032349 -80.48276) (xy 42.038972 -80.406469) (xy 42.052121 -80.33103)
			(xy 42.071699 -80.256997) (xy 42.084244 -80.22082) (xy 42.08686 -80.212376) (xy 42.086876 -80.194714)
			(xy 42.084244 -80.186276) (xy 42.077132 -80.16621) (xy 42.072306 -80.151732) (xy 42.048684 -80.132936)
			(xy 41.925748 -80.12176) (xy 41.899078 -80.135984) (xy 41.891712 -80.149192) (xy 41.870438 -80.186821)
			(xy 41.821689 -80.258212) (xy 41.766245 -80.324537) (xy 41.704628 -80.38517) (xy 41.637419 -80.43954)
			(xy 41.565253 -80.487133) (xy 41.488811 -80.527501) (xy 41.408812 -80.560262) (xy 41.326013 -80.585109)
			(xy 41.241194 -80.601805) (xy 41.155155 -80.610195) (xy 41.111932 -80.61071) (xy 41.073 -80.610273)
			(xy 40.995436 -80.603438) (xy 40.918768 -80.589842) (xy 40.843584 -80.569592) (xy 40.806878 -80.556608)
			(xy 40.798329 -80.553844) (xy 40.780375 -80.553844) (xy 40.771826 -80.556608) (xy 40.735118 -80.569583)
			(xy 40.659931 -80.589823) (xy 40.583265 -80.60342) (xy 40.505703 -80.61027) (xy 40.466772 -80.61071)
			(xy 40.42784 -80.610291) (xy 40.350276 -80.603451) (xy 40.273608 -80.58985) (xy 40.198423 -80.569594)
			(xy 40.161718 -80.556608) (xy 40.153169 -80.553844) (xy 40.135215 -80.553844) (xy 40.126666 -80.556608)
			(xy 40.089954 -80.569572) (xy 40.014769 -80.589815) (xy 39.938103 -80.603415) (xy 39.860543 -80.610268)
			(xy 39.821612 -80.61071) (xy 39.780509 -80.610236) (xy 39.698654 -80.602652) (xy 39.617848 -80.587548)
			(xy 39.53878 -80.565052) (xy 39.462125 -80.535357) (xy 39.388537 -80.498716) (xy 39.318644 -80.45544)
			(xy 39.253041 -80.405901) (xy 39.19229 -80.35052) (xy 39.136908 -80.289769) (xy 39.087368 -80.224168)
			(xy 39.044091 -80.154276) (xy 39.007449 -80.080688) (xy 38.977752 -80.004034) (xy 38.955255 -79.924966)
			(xy 38.940149 -79.84416) (xy 38.932564 -79.762305) (xy 38.932104 -79.721202) (xy 38.624229 -79.721202)
			(xy 38.668014 -79.771733) (xy 38.717142 -79.840725) (xy 38.759489 -79.914075) (xy 38.794673 -79.991118)
			(xy 38.822374 -80.071156) (xy 38.842341 -80.153465) (xy 38.854395 -80.237299) (xy 38.858425 -80.3219)
			(xy 38.854395 -80.406501) (xy 38.842341 -80.490335) (xy 38.822374 -80.572644) (xy 38.794673 -80.652682)
			(xy 38.759489 -80.729725) (xy 38.717142 -80.803075) (xy 38.668014 -80.872067) (xy 38.61255 -80.936077)
			(xy 38.551254 -80.994526) (xy 38.484679 -81.046883) (xy 38.413428 -81.092674) (xy 38.338148 -81.131486)
			(xy 38.259519 -81.162967) (xy 38.178254 -81.186831) (xy 38.095089 -81.202862) (xy 38.010776 -81.210915)
			(xy 37.968428 -81.21142) (xy 37.922033 -81.210826) (xy 37.829745 -81.201184) (xy 37.738961 -81.181991)
			(xy 37.650667 -81.153456) (xy 37.608002 -81.13522) (xy 37.598062 -81.1314) (xy 37.576794 -81.1314)
			(xy 37.566854 -81.13522) (xy 37.524188 -81.153456) (xy 37.435897 -81.182002) (xy 37.345113 -81.201198)
			(xy 37.252824 -81.210834) (xy 37.206428 -81.21142) (xy 37.164078 -81.210909) (xy 37.079763 -81.202861)
			(xy 36.996594 -81.186833) (xy 36.915325 -81.162973) (xy 36.836693 -81.131495) (xy 36.761408 -81.092686)
			(xy 36.690154 -81.046895) (xy 36.623575 -80.994539) (xy 36.562274 -80.936091) (xy 36.506808 -80.872081)
			(xy 36.457676 -80.803088) (xy 36.415326 -80.729736) (xy 36.38014 -80.652692) (xy 36.352437 -80.572651)
			(xy 36.332468 -80.49034) (xy 36.320414 -80.406503) (xy 36.316384 -80.3219) (xy 34.756478 -80.3219)
			(xy 34.748272 -80.350741) (xy 34.718576 -80.427395) (xy 34.681934 -80.500983) (xy 34.638659 -80.570875)
			(xy 34.589119 -80.636476) (xy 34.533738 -80.697227) (xy 34.472989 -80.752609) (xy 34.407388 -80.80215)
			(xy 34.337497 -80.845426) (xy 34.26391 -80.88207) (xy 34.187257 -80.911767) (xy 34.10819 -80.934266)
			(xy 34.027385 -80.949373) (xy 33.945531 -80.95696) (xy 33.904428 -80.95742) (xy 33.858032 -80.956837)
			(xy 33.76574 -80.947206) (xy 33.674954 -80.928016) (xy 33.58666 -80.899475) (xy 33.544002 -80.88122)
			(xy 33.534062 -80.8774) (xy 33.512794 -80.8774) (xy 33.502854 -80.88122) (xy 33.460188 -80.899454)
			(xy 33.371894 -80.927985) (xy 33.28111 -80.947173) (xy 33.188823 -80.956811) (xy 33.142428 -80.95742)
			(xy 33.096032 -80.956837) (xy 33.00374 -80.947206) (xy 32.912954 -80.928016) (xy 32.82466 -80.899475)
			(xy 32.782002 -80.88122) (xy 32.772062 -80.8774) (xy 32.750794 -80.8774) (xy 32.740854 -80.88122)
			(xy 32.698188 -80.899454) (xy 32.609894 -80.927985) (xy 32.51911 -80.947173) (xy 32.426823 -80.956811)
			(xy 32.380428 -80.95742) (xy 32.330593 -80.956697) (xy 32.231553 -80.945495) (xy 32.182816 -80.935068)
			(xy 32.169862 -80.932274) (xy 32.145478 -80.939132) (xy 32.065468 -81.01711) (xy 32.057848 -81.041494)
			(xy 32.060642 -81.054448) (xy 32.064092 -81.072539) (xy 32.067786 -81.109184) (xy 32.068008 -81.1276)
			(xy 32.068008 -84.385912) (xy 39.460424 -84.385912) (xy 39.461008 -84.339516) (xy 39.470653 -84.247228)
			(xy 39.489848 -84.156444) (xy 39.518386 -84.068151) (xy 39.536624 -84.025486) (xy 39.540436 -84.015544)
			(xy 39.540441 -83.994278) (xy 39.536624 -83.984338) (xy 39.518385 -83.941673) (xy 39.489839 -83.853382)
			(xy 39.470644 -83.762598) (xy 39.46101 -83.670308) (xy 39.460424 -83.623912) (xy 39.460928 -83.581564)
			(xy 39.468979 -83.49725) (xy 39.485008 -83.414084) (xy 39.508869 -83.332817) (xy 39.540348 -83.254187)
			(xy 39.579159 -83.178906) (xy 39.624949 -83.107654) (xy 39.677305 -83.041078) (xy 39.735753 -82.97978)
			(xy 39.799763 -82.924315) (xy 39.868755 -82.875186) (xy 39.942105 -82.832837) (xy 40.019148 -82.797653)
			(xy 40.099187 -82.769951) (xy 40.181496 -82.749983) (xy 40.265331 -82.73793) (xy 40.349932 -82.7339)
			(xy 40.434533 -82.73793) (xy 40.518368 -82.749983) (xy 40.600677 -82.769951) (xy 40.680716 -82.797653)
			(xy 40.757759 -82.832837) (xy 40.831109 -82.875186) (xy 40.900101 -82.924315) (xy 40.964111 -82.97978)
			(xy 41.022559 -83.041078) (xy 41.074915 -83.107654) (xy 41.120705 -83.178906) (xy 41.159516 -83.254187)
			(xy 41.190995 -83.332817) (xy 41.214856 -83.414084) (xy 41.230885 -83.49725) (xy 41.238936 -83.581564)
			(xy 41.23944 -83.623912) (xy 41.238867 -83.670308) (xy 41.22922 -83.762597) (xy 41.210021 -83.853381)
			(xy 41.18148 -83.941674) (xy 41.16324 -83.984338) (xy 41.159415 -83.994276) (xy 41.15942 -84.015546)
			(xy 41.16324 -84.025486) (xy 41.181491 -84.068146) (xy 41.210033 -84.156439) (xy 41.229224 -84.247225)
			(xy 41.238856 -84.339516) (xy 41.23944 -84.385912) (xy 41.238936 -84.42826) (xy 41.230885 -84.512574)
			(xy 41.214856 -84.59574) (xy 41.190995 -84.677007) (xy 41.159516 -84.755637) (xy 41.120705 -84.830918)
			(xy 41.074915 -84.90217) (xy 41.022559 -84.968746) (xy 40.964111 -85.030044) (xy 40.900101 -85.085509)
			(xy 40.831109 -85.134638) (xy 40.757759 -85.176987) (xy 40.680716 -85.212171) (xy 40.600677 -85.239873)
			(xy 40.518368 -85.259841) (xy 40.434533 -85.271894) (xy 40.349932 -85.275925) (xy 40.265331 -85.271894)
			(xy 40.181496 -85.259841) (xy 40.099187 -85.239873) (xy 40.019148 -85.212171) (xy 39.942105 -85.176987)
			(xy 39.868755 -85.134638) (xy 39.799763 -85.085509) (xy 39.735753 -85.030044) (xy 39.677305 -84.968746)
			(xy 39.624949 -84.90217) (xy 39.579159 -84.830918) (xy 39.540348 -84.755637) (xy 39.508869 -84.677007)
			(xy 39.485008 -84.59574) (xy 39.468979 -84.512574) (xy 39.460928 -84.42826) (xy 39.460424 -84.385912)
			(xy 32.068008 -84.385912) (xy 32.068008 -86.3346) (xy 32.689292 -86.3346) (xy 32.68976 -86.30723)
			(xy 32.697578 -86.253051) (xy 32.713066 -86.200548) (xy 32.735908 -86.150801) (xy 32.765631 -86.104834)
			(xy 32.783272 -86.083902) (xy 32.789368 -86.07679) (xy 32.795718 -86.059772) (xy 32.795718 -85.974428)
			(xy 32.789368 -85.95741) (xy 32.783272 -85.950298) (xy 32.765614 -85.929381) (xy 32.735906 -85.883404)
			(xy 32.713074 -85.833652) (xy 32.697587 -85.781148) (xy 32.689764 -85.72697) (xy 32.689292 -85.6996)
			(xy 32.689778 -85.672349) (xy 32.697534 -85.618401) (xy 32.712889 -85.566106) (xy 32.735531 -85.516529)
			(xy 32.764997 -85.470679) (xy 32.800688 -85.429488) (xy 32.841879 -85.393797) (xy 32.887729 -85.364331)
			(xy 32.937306 -85.341689) (xy 32.989601 -85.326334) (xy 33.043549 -85.318578) (xy 33.098051 -85.318578)
			(xy 33.151999 -85.326334) (xy 33.204294 -85.341689) (xy 33.253871 -85.364331) (xy 33.299721 -85.393797)
			(xy 33.340912 -85.429488) (xy 33.376603 -85.470679) (xy 33.406069 -85.516529) (xy 33.428711 -85.566106)
			(xy 33.444066 -85.618401) (xy 33.451822 -85.672349) (xy 33.452308 -85.6996) (xy 33.45184 -85.72697)
			(xy 33.444022 -85.781149) (xy 33.428534 -85.833652) (xy 33.405692 -85.883399) (xy 33.375969 -85.929366)
			(xy 33.358328 -85.950298) (xy 33.352232 -85.95741) (xy 33.345882 -85.974428) (xy 33.345882 -86.059772)
			(xy 33.352232 -86.07679) (xy 33.358328 -86.083902) (xy 33.375986 -86.104819) (xy 33.405694 -86.150796)
			(xy 33.428526 -86.200548) (xy 33.444013 -86.253052) (xy 33.451836 -86.30723) (xy 33.451993 -86.316312)
			(xy 35.838892 -86.316312) (xy 35.839383 -86.274361) (xy 35.847275 -86.19083) (xy 35.86299 -86.108412)
			(xy 35.886388 -86.027838) (xy 35.901376 -85.988652) (xy 35.904581 -85.979525) (xy 35.904565 -85.960194)
			(xy 35.901376 -85.95106) (xy 35.886389 -85.911873) (xy 35.862968 -85.831304) (xy 35.847246 -85.748886)
			(xy 35.839364 -85.665352) (xy 35.838892 -85.6234) (xy 35.839396 -85.581052) (xy 35.847447 -85.496738)
			(xy 35.863476 -85.413572) (xy 35.887337 -85.332305) (xy 35.918816 -85.253675) (xy 35.957627 -85.178394)
			(xy 36.003417 -85.107142) (xy 36.055773 -85.040566) (xy 36.114221 -84.979268) (xy 36.178231 -84.923803)
			(xy 36.247223 -84.874674) (xy 36.320573 -84.832325) (xy 36.397616 -84.797141) (xy 36.477655 -84.769439)
			(xy 36.559964 -84.749471) (xy 36.643799 -84.737418) (xy 36.7284 -84.733388) (xy 36.813001 -84.737418)
			(xy 36.896836 -84.749471) (xy 36.979145 -84.769439) (xy 37.059184 -84.797141) (xy 37.136227 -84.832325)
			(xy 37.209577 -84.874674) (xy 37.278569 -84.923803) (xy 37.342579 -84.979268) (xy 37.401027 -85.040566)
			(xy 37.453383 -85.107142) (xy 37.499173 -85.178394) (xy 37.537984 -85.253675) (xy 37.567561 -85.327553)
			(xy 44.693267 -85.327553) (xy 44.693267 -85.273047) (xy 44.701025 -85.219095) (xy 44.716382 -85.166796)
			(xy 44.739026 -85.117215) (xy 44.768496 -85.071362) (xy 44.804192 -85.03017) (xy 44.845387 -84.994477)
			(xy 44.891243 -84.965011) (xy 44.940826 -84.942371) (xy 44.993126 -84.927018) (xy 45.047079 -84.919265)
			(xy 45.074332 -84.918804) (xy 45.103247 -84.91937) (xy 45.160416 -84.928089) (xy 45.215614 -84.945337)
			(xy 45.267576 -84.97072) (xy 45.315111 -85.003655) (xy 45.35713 -85.043388) (xy 45.375322 -85.06587)
			(xy 45.382867 -85.074649) (xy 45.403639 -85.08482) (xy 45.4152 -85.085428) (xy 45.495464 -85.085428)
			(xy 45.507033 -85.084862) (xy 45.527806 -85.074667) (xy 45.535342 -85.06587) (xy 45.552095 -85.045087)
			(xy 45.590449 -85.007957) (xy 45.633603 -84.976535) (xy 45.680717 -84.951436) (xy 45.730869 -84.93315)
			(xy 45.78308 -84.922033) (xy 45.836332 -84.918303) (xy 45.889584 -84.922033) (xy 45.941795 -84.93315)
			(xy 45.991947 -84.951436) (xy 46.039061 -84.976535) (xy 46.082215 -85.007957) (xy 46.120569 -85.045087)
			(xy 46.137322 -85.06587) (xy 46.144867 -85.074649) (xy 46.165639 -85.08482) (xy 46.1772 -85.085428)
			(xy 46.257464 -85.085428) (xy 46.269033 -85.084862) (xy 46.289806 -85.074667) (xy 46.297342 -85.06587)
			(xy 46.314095 -85.045087) (xy 46.352449 -85.007957) (xy 46.395603 -84.976535) (xy 46.442717 -84.951436)
			(xy 46.492869 -84.93315) (xy 46.54508 -84.922033) (xy 46.598332 -84.918303) (xy 46.651584 -84.922033)
			(xy 46.703795 -84.93315) (xy 46.753947 -84.951436) (xy 46.801061 -84.976535) (xy 46.844215 -85.007957)
			(xy 46.882569 -85.045087) (xy 46.899322 -85.06587) (xy 46.906867 -85.074649) (xy 46.927639 -85.08482)
			(xy 46.9392 -85.085428) (xy 47.019464 -85.085428) (xy 47.031033 -85.084862) (xy 47.051806 -85.074667)
			(xy 47.059342 -85.06587) (xy 47.077502 -85.04336) (xy 47.119529 -85.003628) (xy 47.167071 -84.970693)
			(xy 47.219038 -84.945309) (xy 47.274241 -84.928059) (xy 47.331414 -84.919336) (xy 47.360332 -84.918804)
			(xy 47.387583 -84.919268) (xy 47.441529 -84.927028) (xy 47.493821 -84.942387) (xy 47.543396 -84.965031)
			(xy 47.589244 -84.994499) (xy 47.630431 -85.030191) (xy 47.666121 -85.071382) (xy 47.695585 -85.117232)
			(xy 47.718224 -85.166809) (xy 47.733578 -85.219103) (xy 47.741334 -85.273049) (xy 47.741334 -85.327551)
			(xy 47.733578 -85.381497) (xy 47.718224 -85.433791) (xy 47.695585 -85.483368) (xy 47.666121 -85.529218)
			(xy 47.630431 -85.570409) (xy 47.589244 -85.606101) (xy 47.543396 -85.635569) (xy 47.493821 -85.658213)
			(xy 47.441529 -85.673572) (xy 47.387583 -85.681332) (xy 47.360332 -85.68182) (xy 47.331414 -85.681309)
			(xy 47.274242 -85.672583) (xy 47.219041 -85.655326) (xy 47.167079 -85.629933) (xy 47.119545 -85.596986)
			(xy 47.07753 -85.557242) (xy 47.059342 -85.534754) (xy 47.051765 -85.526008) (xy 47.031017 -85.515818)
			(xy 47.019464 -85.515196) (xy 46.9392 -85.515196) (xy 46.927632 -85.515768) (xy 46.906862 -85.525962)
			(xy 46.899322 -85.534754) (xy 46.882569 -85.555537) (xy 46.844215 -85.592667) (xy 46.801061 -85.624089)
			(xy 46.753947 -85.649188) (xy 46.703795 -85.667474) (xy 46.651584 -85.678591) (xy 46.598332 -85.682321)
			(xy 46.54508 -85.678591) (xy 46.492869 -85.667474) (xy 46.442717 -85.649188) (xy 46.395603 -85.624089)
			(xy 46.352449 -85.592667) (xy 46.314095 -85.555537) (xy 46.297342 -85.534754) (xy 46.289765 -85.526008)
			(xy 46.269017 -85.515818) (xy 46.257464 -85.515196) (xy 46.1772 -85.515196) (xy 46.165632 -85.515768)
			(xy 46.144862 -85.525962) (xy 46.137322 -85.534754) (xy 46.120569 -85.555537) (xy 46.082215 -85.592667)
			(xy 46.039061 -85.624089) (xy 45.991947 -85.649188) (xy 45.941795 -85.667474) (xy 45.889584 -85.678591)
			(xy 45.836332 -85.682321) (xy 45.78308 -85.678591) (xy 45.730869 -85.667474) (xy 45.680717 -85.649188)
			(xy 45.633603 -85.624089) (xy 45.590449 -85.592667) (xy 45.552095 -85.555537) (xy 45.535342 -85.534754)
			(xy 45.527765 -85.526008) (xy 45.507017 -85.515818) (xy 45.495464 -85.515196) (xy 45.4152 -85.515196)
			(xy 45.403632 -85.515768) (xy 45.382862 -85.525962) (xy 45.375322 -85.534754) (xy 45.357132 -85.557238)
			(xy 45.315111 -85.596971) (xy 45.267575 -85.629908) (xy 45.215614 -85.655296) (xy 45.160417 -85.672553)
			(xy 45.103248 -85.681284) (xy 45.074332 -85.68182) (xy 45.047079 -85.681335) (xy 44.993126 -85.673582)
			(xy 44.940826 -85.658229) (xy 44.891243 -85.635589) (xy 44.845387 -85.606123) (xy 44.804192 -85.57043)
			(xy 44.768496 -85.529238) (xy 44.739026 -85.483385) (xy 44.716382 -85.433804) (xy 44.701025 -85.381505)
			(xy 44.693267 -85.327553) (xy 37.567561 -85.327553) (xy 37.569463 -85.332305) (xy 37.593324 -85.413572)
			(xy 37.609353 -85.496738) (xy 37.617404 -85.581052) (xy 37.617908 -85.6234) (xy 37.617421 -85.665351)
			(xy 37.609528 -85.748882) (xy 37.593812 -85.8313) (xy 37.570412 -85.911874) (xy 37.555424 -85.95106)
			(xy 37.552267 -85.9602) (xy 37.552252 -85.979519) (xy 37.555424 -85.988652) (xy 37.570414 -86.027838)
			(xy 37.593835 -86.108407) (xy 37.609556 -86.190826) (xy 37.617436 -86.27436) (xy 37.617908 -86.316312)
			(xy 37.617404 -86.35866) (xy 37.609353 -86.442974) (xy 37.593324 -86.52614) (xy 37.569463 -86.607407)
			(xy 37.537984 -86.686037) (xy 37.499173 -86.761318) (xy 37.453383 -86.83257) (xy 37.401027 -86.899146)
			(xy 37.342579 -86.960444) (xy 37.278569 -87.015909) (xy 37.209577 -87.065038) (xy 37.136227 -87.107387)
			(xy 37.059184 -87.142571) (xy 36.979145 -87.170273) (xy 36.896836 -87.190241) (xy 36.813001 -87.202294)
			(xy 36.7284 -87.206325) (xy 36.643799 -87.202294) (xy 36.559964 -87.190241) (xy 36.477655 -87.170273)
			(xy 36.397616 -87.142571) (xy 36.320573 -87.107387) (xy 36.247223 -87.065038) (xy 36.178231 -87.015909)
			(xy 36.114221 -86.960444) (xy 36.055773 -86.899146) (xy 36.003417 -86.83257) (xy 35.957627 -86.761318)
			(xy 35.918816 -86.686037) (xy 35.887337 -86.607407) (xy 35.863476 -86.52614) (xy 35.847447 -86.442974)
			(xy 35.839396 -86.35866) (xy 35.838892 -86.316312) (xy 33.451993 -86.316312) (xy 33.452308 -86.3346)
			(xy 33.451822 -86.361851) (xy 33.444066 -86.415799) (xy 33.428711 -86.468094) (xy 33.406069 -86.517671)
			(xy 33.376603 -86.563521) (xy 33.340912 -86.604712) (xy 33.299721 -86.640403) (xy 33.253871 -86.669869)
			(xy 33.204294 -86.692511) (xy 33.151999 -86.707866) (xy 33.098051 -86.715622) (xy 33.043549 -86.715622)
			(xy 32.989601 -86.707866) (xy 32.937306 -86.692511) (xy 32.887729 -86.669869) (xy 32.841879 -86.640403)
			(xy 32.800688 -86.604712) (xy 32.764997 -86.563521) (xy 32.735531 -86.517671) (xy 32.712889 -86.468094)
			(xy 32.697534 -86.415799) (xy 32.689778 -86.361851) (xy 32.689292 -86.3346) (xy 32.068008 -86.3346)
			(xy 32.068008 -87.29091) (xy 32.06844 -87.300621) (xy 32.075666 -87.31865) (xy 32.089077 -87.332699)
			(xy 32.097726 -87.337138) (xy 32.195516 -87.381842) (xy 32.224726 -87.377524) (xy 32.236156 -87.367618)
			(xy 32.257085 -87.350032) (xy 32.303025 -87.320405) (xy 32.352723 -87.297638) (xy 32.405162 -87.282196)
			(xy 32.459268 -87.274395) (xy 32.4866 -87.273892) (xy 32.513851 -87.274378) (xy 32.567799 -87.282134)
			(xy 32.620094 -87.297489) (xy 32.669671 -87.320131) (xy 32.715521 -87.349597) (xy 32.756712 -87.385288)
			(xy 32.792403 -87.426479) (xy 32.821869 -87.472329) (xy 32.844511 -87.521906) (xy 32.859866 -87.574201)
			(xy 32.867622 -87.628149) (xy 32.868108 -87.6554) (xy 32.867659 -87.681819) (xy 32.860365 -87.734152)
			(xy 32.845917 -87.784977) (xy 32.824592 -87.833322) (xy 32.796798 -87.878259) (xy 32.763067 -87.918931)
			(xy 32.724045 -87.954556) (xy 32.7025 -87.969852) (xy 32.691832 -87.977218) (xy 32.680148 -88.000332)
			(xy 32.683704 -88.111838) (xy 32.696658 -88.13419) (xy 32.707834 -88.140794) (xy 32.731717 -88.155664)
			(xy 32.775233 -88.19132) (xy 32.813042 -88.232981) (xy 32.844322 -88.279742) (xy 32.868395 -88.33059)
			(xy 32.88474 -88.384422) (xy 32.893002 -88.440071) (xy 32.893508 -88.4682) (xy 32.893022 -88.495451)
			(xy 32.885266 -88.549399) (xy 32.869911 -88.601694) (xy 32.847269 -88.651271) (xy 32.817803 -88.697121)
			(xy 32.782112 -88.738312) (xy 32.740921 -88.774003) (xy 32.695071 -88.803469) (xy 32.645494 -88.826111)
			(xy 32.593199 -88.841466) (xy 32.539251 -88.849222) (xy 32.512 -88.849708) (xy 32.481913 -88.849141)
			(xy 32.422485 -88.83969) (xy 32.365279 -88.821021) (xy 32.311715 -88.7936) (xy 32.263123 -88.758105)
			(xy 32.24149 -88.737186) (xy 32.230568 -88.726264) (xy 32.200342 -88.720168) (xy 32.09925 -88.761824)
			(xy 32.090149 -88.76605) (xy 32.075987 -88.780243) (xy 32.068364 -88.798787) (xy 32.068008 -88.808814)
			(xy 32.068008 -88.99271) (xy 32.06844 -89.002421) (xy 32.075666 -89.02045) (xy 32.089077 -89.034499)
			(xy 32.097726 -89.038938) (xy 32.195516 -89.083642) (xy 32.224726 -89.079324) (xy 32.236156 -89.069418)
			(xy 32.257085 -89.051832) (xy 32.303025 -89.022205) (xy 32.352723 -88.999438) (xy 32.405162 -88.983996)
			(xy 32.459268 -88.976195) (xy 32.4866 -88.975692) (xy 32.513851 -88.976178) (xy 32.567799 -88.983934)
			(xy 32.620094 -88.999289) (xy 32.669671 -89.021931) (xy 32.715521 -89.051397) (xy 32.756712 -89.087088)
			(xy 32.792403 -89.128279) (xy 32.821869 -89.174129) (xy 32.844511 -89.223706) (xy 32.859866 -89.276001)
			(xy 32.867622 -89.329949) (xy 32.867622 -89.3572) (xy 37.185092 -89.3572) (xy 37.185584 -89.314525)
			(xy 37.193782 -89.22957) (xy 37.210083 -89.145791) (xy 37.234337 -89.06396) (xy 37.249862 -89.024206)
			(xy 37.253139 -89.01496) (xy 37.253123 -88.995359) (xy 37.249862 -88.986106) (xy 37.23435 -88.946348)
			(xy 37.210108 -88.864516) (xy 37.193811 -88.780738) (xy 37.18561 -88.695786) (xy 37.185092 -88.653112)
			(xy 37.185583 -88.611161) (xy 37.193475 -88.52763) (xy 37.20919 -88.445212) (xy 37.232588 -88.364638)
			(xy 37.247576 -88.325452) (xy 37.250781 -88.316325) (xy 37.250765 -88.296994) (xy 37.247576 -88.28786)
			(xy 37.232589 -88.248673) (xy 37.209168 -88.168104) (xy 37.193446 -88.085686) (xy 37.185564 -88.002152)
			(xy 37.185092 -87.9602) (xy 37.185596 -87.917852) (xy 37.193647 -87.833538) (xy 37.209676 -87.750372)
			(xy 37.233537 -87.669105) (xy 37.265016 -87.590475) (xy 37.303827 -87.515194) (xy 37.349617 -87.443942)
			(xy 37.401973 -87.377366) (xy 37.460421 -87.316068) (xy 37.524431 -87.260603) (xy 37.593423 -87.211474)
			(xy 37.666773 -87.169125) (xy 37.743816 -87.133941) (xy 37.823855 -87.106239) (xy 37.906164 -87.086271)
			(xy 37.989999 -87.074218) (xy 38.0746 -87.070188) (xy 38.159201 -87.074218) (xy 38.243036 -87.086271)
			(xy 38.325345 -87.106239) (xy 38.405384 -87.133941) (xy 38.482427 -87.169125) (xy 38.555777 -87.211474)
			(xy 38.624769 -87.260603) (xy 38.688779 -87.316068) (xy 38.747227 -87.377366) (xy 38.799583 -87.443942)
			(xy 38.845373 -87.515194) (xy 38.884184 -87.590475) (xy 38.915663 -87.669105) (xy 38.939524 -87.750372)
			(xy 38.955553 -87.833538) (xy 38.963604 -87.917852) (xy 38.964108 -87.9602) (xy 38.963621 -88.002151)
			(xy 38.955728 -88.085682) (xy 38.940012 -88.1681) (xy 38.916612 -88.248674) (xy 38.901624 -88.28786)
			(xy 38.898467 -88.297) (xy 38.898452 -88.316319) (xy 38.901624 -88.325452) (xy 38.916614 -88.364638)
			(xy 38.940035 -88.445207) (xy 38.955756 -88.527626) (xy 38.963636 -88.61116) (xy 38.964108 -88.653112)
			(xy 38.963587 -88.695786) (xy 38.955397 -88.780741) (xy 38.939104 -88.864519) (xy 38.914858 -88.946351)
			(xy 38.899338 -88.986106) (xy 38.89611 -88.995365) (xy 38.896094 -89.014954) (xy 38.899338 -89.024206)
			(xy 38.914853 -89.063963) (xy 38.939095 -89.145795) (xy 38.955391 -89.229573) (xy 38.96359 -89.314526)
			(xy 38.964108 -89.3572) (xy 38.963604 -89.399548) (xy 38.955553 -89.483862) (xy 38.939524 -89.567028)
			(xy 38.915663 -89.648295) (xy 38.884184 -89.726925) (xy 38.845373 -89.802206) (xy 38.799583 -89.873458)
			(xy 38.747227 -89.940034) (xy 38.688779 -90.001332) (xy 38.624769 -90.056797) (xy 38.555777 -90.105926)
			(xy 38.482427 -90.148275) (xy 38.405384 -90.183459) (xy 38.325345 -90.211161) (xy 38.243036 -90.231129)
			(xy 38.159201 -90.243182) (xy 38.0746 -90.247213) (xy 37.989999 -90.243182) (xy 37.906164 -90.231129)
			(xy 37.823855 -90.211161) (xy 37.743816 -90.183459) (xy 37.666773 -90.148275) (xy 37.593423 -90.105926)
			(xy 37.524431 -90.056797) (xy 37.460421 -90.001332) (xy 37.401973 -89.940034) (xy 37.349617 -89.873458)
			(xy 37.303827 -89.802206) (xy 37.265016 -89.726925) (xy 37.233537 -89.648295) (xy 37.209676 -89.567028)
			(xy 37.193647 -89.483862) (xy 37.185596 -89.399548) (xy 37.185092 -89.3572) (xy 32.867622 -89.3572)
			(xy 32.867622 -89.384451) (xy 32.859866 -89.438399) (xy 32.844511 -89.490694) (xy 32.821869 -89.540271)
			(xy 32.792403 -89.586121) (xy 32.756712 -89.627312) (xy 32.715521 -89.663003) (xy 32.669671 -89.692469)
			(xy 32.620094 -89.715111) (xy 32.567799 -89.730466) (xy 32.513851 -89.738222) (xy 32.4866 -89.738708)
			(xy 32.459266 -89.738239) (xy 32.405159 -89.730434) (xy 32.35272 -89.714984) (xy 32.303024 -89.692205)
			(xy 32.25709 -89.662565) (xy 32.236156 -89.644982) (xy 32.224726 -89.635076) (xy 32.195516 -89.630758)
			(xy 32.097726 -89.675462) (xy 32.089064 -89.679883) (xy 32.075647 -89.693938) (xy 32.068418 -89.711975)
			(xy 32.068008 -89.72169) (xy 32.068008 -92.16771) (xy 32.06844 -92.177421) (xy 32.075666 -92.19545)
			(xy 32.089077 -92.209499) (xy 32.097726 -92.213938) (xy 32.195516 -92.258642) (xy 32.224726 -92.254324)
			(xy 32.236156 -92.244418) (xy 32.257085 -92.226832) (xy 32.303025 -92.197205) (xy 32.352723 -92.174438)
			(xy 32.405162 -92.158996) (xy 32.459268 -92.151195) (xy 32.4866 -92.150692) (xy 32.513851 -92.151178)
			(xy 32.567799 -92.158934) (xy 32.620094 -92.174289) (xy 32.669671 -92.196931) (xy 32.715521 -92.226397)
			(xy 32.756712 -92.262088) (xy 32.792403 -92.303279) (xy 32.821869 -92.349129) (xy 32.844511 -92.398706)
			(xy 32.859866 -92.451001) (xy 32.867622 -92.504949) (xy 32.867622 -92.559451) (xy 32.859866 -92.613399)
			(xy 32.844511 -92.665694) (xy 32.821869 -92.715271) (xy 32.792403 -92.761121) (xy 32.756712 -92.802312)
			(xy 32.715521 -92.838003) (xy 32.669671 -92.867469) (xy 32.620094 -92.890111) (xy 32.567799 -92.905466)
			(xy 32.513851 -92.913222) (xy 32.4866 -92.913708) (xy 32.459266 -92.913239) (xy 32.405159 -92.905434)
			(xy 32.35272 -92.889984) (xy 32.303024 -92.867205) (xy 32.25709 -92.837565) (xy 32.236156 -92.819982)
			(xy 32.224726 -92.810076) (xy 32.195516 -92.805758) (xy 32.097726 -92.850462) (xy 32.089064 -92.854883)
			(xy 32.075647 -92.868938) (xy 32.068418 -92.886975) (xy 32.068008 -92.89669) (xy 32.068008 -93.08211)
			(xy 32.06844 -93.091821) (xy 32.075666 -93.10985) (xy 32.089077 -93.123899) (xy 32.097726 -93.128338)
			(xy 32.195516 -93.173042) (xy 32.224726 -93.168724) (xy 32.236156 -93.158818) (xy 32.257085 -93.141232)
			(xy 32.303025 -93.111605) (xy 32.352723 -93.088838) (xy 32.405162 -93.073396) (xy 32.459268 -93.065595)
			(xy 32.4866 -93.065092) (xy 32.513851 -93.065578) (xy 32.567799 -93.073334) (xy 32.620094 -93.088689)
			(xy 32.669671 -93.111331) (xy 32.715521 -93.140797) (xy 32.756712 -93.176488) (xy 32.792403 -93.217679)
			(xy 32.821869 -93.263529) (xy 32.844511 -93.313106) (xy 32.859866 -93.365401) (xy 32.867622 -93.419349)
			(xy 32.868108 -93.4466) (xy 32.867689 -93.47229) (xy 32.860793 -93.523205) (xy 32.847126 -93.572734)
			(xy 32.826935 -93.61998) (xy 32.800585 -93.664089) (xy 32.768554 -93.704263) (xy 32.731421 -93.739774)
			(xy 32.710882 -93.75521) (xy 32.70123 -93.762322) (xy 32.690308 -93.782896) (xy 32.686752 -93.886782)
			(xy 32.696404 -93.907864) (xy 32.705548 -93.915484) (xy 32.726618 -93.933722) (xy 32.763762 -93.975263)
			(xy 32.794471 -94.021764) (xy 32.810588 -94.0562) (xy 37.185092 -94.0562) (xy 37.185584 -94.013525)
			(xy 37.193782 -93.92857) (xy 37.210083 -93.844791) (xy 37.234337 -93.76296) (xy 37.249862 -93.723206)
			(xy 37.253139 -93.71396) (xy 37.253123 -93.694359) (xy 37.249862 -93.685106) (xy 37.23435 -93.645348)
			(xy 37.210108 -93.563516) (xy 37.193811 -93.479738) (xy 37.18561 -93.394786) (xy 37.185092 -93.352112)
			(xy 37.185526 -93.311974) (xy 37.19274 -93.232022) (xy 37.207128 -93.153046) (xy 37.228573 -93.075687)
			(xy 37.256901 -93.000575) (xy 37.273992 -92.964254) (xy 37.278542 -92.95367) (xy 37.278524 -92.930651)
			(xy 37.273992 -92.920058) (xy 37.256885 -92.883745) (xy 37.228557 -92.808631) (xy 37.207114 -92.731271)
			(xy 37.19273 -92.652292) (xy 37.185523 -92.572339) (xy 37.185092 -92.5322) (xy 37.185596 -92.489852)
			(xy 37.193647 -92.405538) (xy 37.209676 -92.322372) (xy 37.233537 -92.241105) (xy 37.265016 -92.162475)
			(xy 37.303827 -92.087194) (xy 37.349617 -92.015942) (xy 37.401973 -91.949366) (xy 37.460421 -91.888068)
			(xy 37.524431 -91.832603) (xy 37.593423 -91.783474) (xy 37.666773 -91.741125) (xy 37.743816 -91.705941)
			(xy 37.823855 -91.678239) (xy 37.906164 -91.658271) (xy 37.989999 -91.646218) (xy 38.0746 -91.642188)
			(xy 38.159201 -91.646218) (xy 38.243036 -91.658271) (xy 38.325345 -91.678239) (xy 38.405384 -91.705941)
			(xy 38.482427 -91.741125) (xy 38.555777 -91.783474) (xy 38.624769 -91.832603) (xy 38.688779 -91.888068)
			(xy 38.747227 -91.949366) (xy 38.799583 -92.015942) (xy 38.803258 -92.02166) (xy 44.032424 -92.02166)
			(xy 44.032857 -91.983372) (xy 44.039478 -91.907082) (xy 44.052626 -91.831642) (xy 44.072204 -91.75761)
			(xy 44.084748 -91.721432) (xy 44.087408 -91.712999) (xy 44.087395 -91.695326) (xy 44.084748 -91.686888)
			(xy 44.072177 -91.650718) (xy 44.052585 -91.576687) (xy 44.039438 -91.501244) (xy 44.032833 -91.42495)
			(xy 44.032424 -91.38666) (xy 44.032829 -91.345556) (xy 44.040417 -91.263699) (xy 44.055527 -91.182891)
			(xy 44.078027 -91.103822) (xy 44.107728 -91.027166) (xy 44.144374 -90.953578) (xy 44.187654 -90.883685)
			(xy 44.237198 -90.818084) (xy 44.292584 -90.757333) (xy 44.353339 -90.701952) (xy 44.418945 -90.652413)
			(xy 44.488841 -90.609139) (xy 44.562432 -90.572499) (xy 44.63909 -90.542805) (xy 44.718161 -90.52031)
			(xy 44.79897 -90.505207) (xy 44.880828 -90.497625) (xy 44.921932 -90.497152) (xy 44.968327 -90.497754)
			(xy 45.060615 -90.507393) (xy 45.151399 -90.526583) (xy 45.239693 -90.555116) (xy 45.282358 -90.573352)
			(xy 45.292298 -90.577172) (xy 45.313566 -90.577172) (xy 45.323506 -90.573352) (xy 45.366163 -90.555094)
			(xy 45.454457 -90.526554) (xy 45.545244 -90.507365) (xy 45.637536 -90.497735) (xy 45.683932 -90.497152)
			(xy 45.730327 -90.497754) (xy 45.822615 -90.507393) (xy 45.913399 -90.526583) (xy 46.001693 -90.555116)
			(xy 46.044358 -90.573352) (xy 46.054298 -90.577172) (xy 46.075566 -90.577172) (xy 46.085506 -90.573352)
			(xy 46.128163 -90.555094) (xy 46.216457 -90.526554) (xy 46.307244 -90.507365) (xy 46.399536 -90.497735)
			(xy 46.445932 -90.497152) (xy 46.492327 -90.497754) (xy 46.584615 -90.507393) (xy 46.675399 -90.526583)
			(xy 46.763693 -90.555116) (xy 46.806358 -90.573352) (xy 46.816298 -90.577172) (xy 46.837566 -90.577172)
			(xy 46.847506 -90.573352) (xy 46.890163 -90.555094) (xy 46.978457 -90.526554) (xy 47.069244 -90.507365)
			(xy 47.161536 -90.497735) (xy 47.207932 -90.497152) (xy 47.249034 -90.497636) (xy 47.330887 -90.505223)
			(xy 47.41169 -90.52033) (xy 47.490755 -90.542828) (xy 47.567408 -90.572525) (xy 47.640993 -90.609167)
			(xy 47.710884 -90.652442) (xy 47.776483 -90.701981) (xy 47.837233 -90.757362) (xy 47.892614 -90.81811)
			(xy 47.942153 -90.88371) (xy 47.985429 -90.9536) (xy 48.022072 -91.027185) (xy 48.051769 -91.103837)
			(xy 48.074268 -91.182902) (xy 48.089375 -91.263705) (xy 48.096964 -91.345558) (xy 48.09744 -91.38666)
			(xy 48.097009 -91.424948) (xy 48.090387 -91.501238) (xy 48.077238 -91.576678) (xy 48.05766 -91.65071)
			(xy 48.045116 -91.686888) (xy 48.042493 -91.695331) (xy 48.04248 -91.712994) (xy 48.045116 -91.721432)
			(xy 48.057691 -91.7576) (xy 48.077282 -91.831632) (xy 48.090428 -91.907075) (xy 48.097032 -91.98337)
			(xy 48.09744 -92.02166) (xy 48.09691 -92.062762) (xy 48.089329 -92.144614) (xy 48.074227 -92.225418)
			(xy 48.051735 -92.304484) (xy 48.022043 -92.381138) (xy 47.985405 -92.454725) (xy 47.942134 -92.524617)
			(xy 47.892598 -92.590218) (xy 47.83722 -92.65097) (xy 47.776474 -92.706352) (xy 47.710876 -92.755893)
			(xy 47.640988 -92.79917) (xy 47.567404 -92.835814) (xy 47.490753 -92.865512) (xy 47.411689 -92.888011)
			(xy 47.330886 -92.903119) (xy 47.249034 -92.910706) (xy 47.207932 -92.911168) (xy 47.161537 -92.910577)
			(xy 47.069248 -92.900935) (xy 46.978465 -92.881741) (xy 46.890171 -92.853205) (xy 46.847506 -92.834968)
			(xy 46.837566 -92.831148) (xy 46.816298 -92.831148) (xy 46.806358 -92.834968) (xy 46.76369 -92.8532)
			(xy 46.6754 -92.881748) (xy 46.584617 -92.900945) (xy 46.492328 -92.910581) (xy 46.445932 -92.911168)
			(xy 46.399537 -92.910577) (xy 46.307248 -92.900935) (xy 46.216465 -92.881741) (xy 46.128171 -92.853205)
			(xy 46.085506 -92.834968) (xy 46.075566 -92.831148) (xy 46.054298 -92.831148) (xy 46.044358 -92.834968)
			(xy 46.00169 -92.8532) (xy 45.9134 -92.881748) (xy 45.822617 -92.900945) (xy 45.730328 -92.910581)
			(xy 45.683932 -92.911168) (xy 45.637537 -92.910577) (xy 45.545248 -92.900935) (xy 45.454465 -92.881741)
			(xy 45.366171 -92.853205) (xy 45.323506 -92.834968) (xy 45.313566 -92.831148) (xy 45.292298 -92.831148)
			(xy 45.282358 -92.834968) (xy 45.23969 -92.8532) (xy 45.1514 -92.881748) (xy 45.060617 -92.900945)
			(xy 44.968328 -92.910581) (xy 44.921932 -92.911168) (xy 44.880828 -92.910717) (xy 44.798971 -92.903135)
			(xy 44.718163 -92.888031) (xy 44.639093 -92.865536) (xy 44.562436 -92.83584) (xy 44.488846 -92.799198)
			(xy 44.418952 -92.755922) (xy 44.353349 -92.706381) (xy 44.292597 -92.650998) (xy 44.237214 -92.590245)
			(xy 44.187674 -92.524642) (xy 44.144398 -92.454747) (xy 44.107757 -92.381157) (xy 44.078062 -92.3045)
			(xy 44.055567 -92.225429) (xy 44.040464 -92.144621) (xy 44.032882 -92.062764) (xy 44.032424 -92.02166)
			(xy 38.803258 -92.02166) (xy 38.845373 -92.087194) (xy 38.884184 -92.162475) (xy 38.915663 -92.241105)
			(xy 38.939524 -92.322372) (xy 38.955553 -92.405538) (xy 38.963604 -92.489852) (xy 38.964108 -92.5322)
			(xy 38.963678 -92.572338) (xy 38.956464 -92.65229) (xy 38.942074 -92.731267) (xy 38.920628 -92.808626)
			(xy 38.892299 -92.883738) (xy 38.875208 -92.920058) (xy 38.870715 -92.93066) (xy 38.870697 -92.953661)
			(xy 38.875208 -92.964254) (xy 38.89232 -93.000565) (xy 38.920646 -93.075679) (xy 38.942088 -93.15304)
			(xy 38.956471 -93.232019) (xy 38.963678 -93.311973) (xy 38.964108 -93.352112) (xy 38.963587 -93.394786)
			(xy 38.955397 -93.479741) (xy 38.939104 -93.563519) (xy 38.914858 -93.645351) (xy 38.899338 -93.685106)
			(xy 38.89611 -93.694365) (xy 38.896094 -93.713954) (xy 38.899338 -93.723206) (xy 38.914853 -93.762963)
			(xy 38.939095 -93.844795) (xy 38.955391 -93.928573) (xy 38.96359 -94.013526) (xy 38.964108 -94.0562)
			(xy 38.963604 -94.098548) (xy 38.955553 -94.182862) (xy 38.939524 -94.266028) (xy 38.915663 -94.347295)
			(xy 38.884184 -94.425925) (xy 38.845373 -94.501206) (xy 38.799583 -94.572458) (xy 38.747227 -94.639034)
			(xy 38.688779 -94.700332) (xy 38.624769 -94.755797) (xy 38.555777 -94.804926) (xy 38.482427 -94.847275)
			(xy 38.405384 -94.882459) (xy 38.325345 -94.910161) (xy 38.243036 -94.930129) (xy 38.159201 -94.942182)
			(xy 38.0746 -94.946213) (xy 37.989999 -94.942182) (xy 37.906164 -94.930129) (xy 37.823855 -94.910161)
			(xy 37.743816 -94.882459) (xy 37.666773 -94.847275) (xy 37.593423 -94.804926) (xy 37.524431 -94.755797)
			(xy 37.460421 -94.700332) (xy 37.401973 -94.639034) (xy 37.349617 -94.572458) (xy 37.303827 -94.501206)
			(xy 37.265016 -94.425925) (xy 37.233537 -94.347295) (xy 37.209676 -94.266028) (xy 37.193647 -94.182862)
			(xy 37.185596 -94.098548) (xy 37.185092 -94.0562) (xy 32.810588 -94.0562) (xy 32.818093 -94.072235)
			(xy 32.834125 -94.125604) (xy 32.842227 -94.180737) (xy 32.842708 -94.2086) (xy 32.842222 -94.235851)
			(xy 32.834466 -94.289799) (xy 32.819111 -94.342094) (xy 32.796469 -94.391671) (xy 32.767003 -94.437521)
			(xy 32.731312 -94.478712) (xy 32.690121 -94.514403) (xy 32.644271 -94.543869) (xy 32.594694 -94.566511)
			(xy 32.542399 -94.581866) (xy 32.488451 -94.589622) (xy 32.4612 -94.590108) (xy 32.430259 -94.589506)
			(xy 32.369191 -94.579514) (xy 32.310536 -94.559792) (xy 32.255837 -94.530857) (xy 32.230822 -94.512638)
			(xy 32.219138 -94.503748) (xy 32.19069 -94.501208) (xy 32.095948 -94.548198) (xy 32.08771 -94.552749)
			(xy 32.075087 -94.566691) (xy 32.068369 -94.584258) (xy 32.068008 -94.593664) (xy 32.068008 -94.847664)
			(xy 32.068494 -94.857626) (xy 32.076082 -94.87605) (xy 32.08274 -94.883478) (xy 36.002722 -98.80346)
			(xy 36.010092 -98.810203) (xy 36.028554 -98.817794) (xy 36.038536 -98.818192) (xy 36.957254 -98.818192)
			(xy 36.986227 -98.818751) (xy 37.043454 -98.82786) (xy 37.09855 -98.845813) (xy 37.150157 -98.872168)
			(xy 37.197004 -98.906274) (xy 37.217858 -98.926396) (xy 39.570914 -101.279198) (xy 39.57826 -101.286006)
			(xy 39.596722 -101.293734) (xy 39.606728 -101.294184) (xy 46.020482 -101.294184) (xy 46.030982 -101.294227)
			(xy 46.05195 -101.29537) (xy 46.062392 -101.29647) (xy 46.077886 -101.298248) (xy 46.103538 -101.301624)
			(xy 46.153613 -101.314639) (xy 46.201374 -101.334532) (xy 46.245883 -101.360911) (xy 46.266354 -101.376734)
			(xy 46.279054 -101.386894) (xy 46.286937 -101.393317) (xy 46.30206 -101.406913) (xy 46.30928 -101.414072)
			(xy 47.877476 -102.982014) (xy 47.884874 -102.988858) (xy 47.903474 -102.996578) (xy 47.913544 -102.997)
			(xy 48.111918 -102.997) (xy 48.121987 -102.996573) (xy 48.140586 -102.988854) (xy 48.147986 -102.982014)
			(xy 48.306736 -102.823264) (xy 48.313411 -102.815851) (xy 48.320974 -102.797415) (xy 48.321468 -102.78745)
			(xy 48.321468 -72.867012) (xy 48.320977 -72.857052) (xy 48.31338 -72.838636) (xy 48.306736 -72.831198)
			(xy 46.572678 -71.09714) (xy 46.565308 -71.090397) (xy 46.546846 -71.082806) (xy 46.536864 -71.082408)
			(xy 45.789342 -71.082408) (xy 45.760369 -71.081848) (xy 45.703142 -71.072739) (xy 45.648047 -71.054786)
			(xy 45.59644 -71.028431) (xy 45.549594 -70.994324) (xy 45.528738 -70.974204) (xy 44.47667 -69.92239)
			(xy 44.471336 -69.919088) (xy 44.44755 -69.904195) (xy 44.404221 -69.86853) (xy 44.366583 -69.826904)
			(xy 44.335446 -69.780215) (xy 44.311483 -69.72947) (xy 44.29521 -69.675762) (xy 44.286979 -69.620249)
			(xy 44.286424 -69.59219) (xy 44.286888 -69.564938) (xy 44.294646 -69.51099) (xy 44.310004 -69.458696)
			(xy 44.332647 -69.409119) (xy 44.362116 -69.363269) (xy 44.39781 -69.32208) (xy 44.439003 -69.286391)
			(xy 44.484856 -69.256927) (xy 44.534435 -69.234289) (xy 44.586731 -69.218937) (xy 44.64068 -69.211185)
			(xy 44.667932 -69.210682) (xy 44.695996 -69.211175) (xy 44.75152 -69.219393) (xy 44.80524 -69.235662)
			(xy 44.855994 -69.25963) (xy 44.902686 -69.290779) (xy 44.944307 -69.328437) (xy 44.979959 -69.371789)
			(xy 44.99483 -69.395594) (xy 44.998132 -69.400928) (xy 45.927264 -70.33006) (xy 45.93467 -70.336754)
			(xy 45.953106 -70.344356) (xy 45.963078 -70.344792) (xy 46.7106 -70.344792) (xy 46.739575 -70.345347)
			(xy 46.796806 -70.354449) (xy 46.851907 -70.372395) (xy 46.903521 -70.398745) (xy 46.950374 -70.432849)
			(xy 46.971204 -70.452996) (xy 48.258476 -71.740014) (xy 48.265874 -71.746858) (xy 48.284474 -71.754578)
			(xy 48.294544 -71.755) (xy 48.569118 -71.755) (xy 48.579187 -71.754573) (xy 48.597786 -71.746854)
			(xy 48.605186 -71.740014) (xy 48.702214 -71.642986) (xy 48.709068 -71.635591) (xy 48.71681 -71.616992)
			(xy 48.7172 -71.606918) (xy 48.7172 -68.911724) (xy 48.716763 -68.90166) (xy 48.709029 -68.883076)
			(xy 48.702214 -68.875656) (xy 47.799498 -67.97294) (xy 47.792129 -67.966194) (xy 47.773667 -67.958596)
			(xy 47.763684 -67.958208) (xy 44.217336 -67.958208) (xy 44.207374 -67.958694) (xy 44.18895 -67.966282)
			(xy 44.181522 -67.97294) (xy 43.667109 -68.487353) (xy 44.896467 -68.487353) (xy 44.896467 -68.432847)
			(xy 44.904225 -68.378895) (xy 44.919582 -68.326596) (xy 44.942226 -68.277015) (xy 44.971696 -68.231162)
			(xy 45.007392 -68.18997) (xy 45.048587 -68.154277) (xy 45.094443 -68.124811) (xy 45.144026 -68.102171)
			(xy 45.196326 -68.086818) (xy 45.250279 -68.079065) (xy 45.277532 -68.078604) (xy 45.306447 -68.07917)
			(xy 45.363616 -68.087889) (xy 45.418814 -68.105137) (xy 45.470776 -68.13052) (xy 45.518311 -68.163455)
			(xy 45.56033 -68.203188) (xy 45.578522 -68.22567) (xy 45.586067 -68.234449) (xy 45.606839 -68.24462)
			(xy 45.6184 -68.245228) (xy 45.698664 -68.245228) (xy 45.710233 -68.244662) (xy 45.731006 -68.234467)
			(xy 45.738542 -68.22567) (xy 45.755295 -68.204887) (xy 45.793649 -68.167757) (xy 45.836803 -68.136335)
			(xy 45.883917 -68.111236) (xy 45.934069 -68.09295) (xy 45.98628 -68.081833) (xy 46.039532 -68.078103)
			(xy 46.092784 -68.081833) (xy 46.144995 -68.09295) (xy 46.195147 -68.111236) (xy 46.242261 -68.136335)
			(xy 46.285415 -68.167757) (xy 46.323769 -68.204887) (xy 46.340522 -68.22567) (xy 46.348067 -68.234449)
			(xy 46.368839 -68.24462) (xy 46.3804 -68.245228) (xy 46.460664 -68.245228) (xy 46.472233 -68.244662)
			(xy 46.493006 -68.234467) (xy 46.500542 -68.22567) (xy 46.517295 -68.204887) (xy 46.555649 -68.167757)
			(xy 46.598803 -68.136335) (xy 46.645917 -68.111236) (xy 46.696069 -68.09295) (xy 46.74828 -68.081833)
			(xy 46.801532 -68.078103) (xy 46.854784 -68.081833) (xy 46.906995 -68.09295) (xy 46.957147 -68.111236)
			(xy 47.004261 -68.136335) (xy 47.047415 -68.167757) (xy 47.085769 -68.204887) (xy 47.102522 -68.22567)
			(xy 47.110067 -68.234449) (xy 47.130839 -68.24462) (xy 47.1424 -68.245228) (xy 47.222664 -68.245228)
			(xy 47.234233 -68.244662) (xy 47.255006 -68.234467) (xy 47.262542 -68.22567) (xy 47.280702 -68.20316)
			(xy 47.322729 -68.163428) (xy 47.370271 -68.130493) (xy 47.422238 -68.105109) (xy 47.477441 -68.087859)
			(xy 47.534614 -68.079136) (xy 47.563532 -68.078604) (xy 47.590783 -68.079068) (xy 47.644729 -68.086828)
			(xy 47.697021 -68.102187) (xy 47.746596 -68.124831) (xy 47.792444 -68.154299) (xy 47.833631 -68.189991)
			(xy 47.869321 -68.231182) (xy 47.898785 -68.277032) (xy 47.921424 -68.326609) (xy 47.936778 -68.378903)
			(xy 47.944534 -68.432849) (xy 47.944534 -68.487351) (xy 47.936778 -68.541297) (xy 47.921424 -68.593591)
			(xy 47.898785 -68.643168) (xy 47.869321 -68.689018) (xy 47.833631 -68.730209) (xy 47.792444 -68.765901)
			(xy 47.746596 -68.795369) (xy 47.697021 -68.818013) (xy 47.644729 -68.833372) (xy 47.590783 -68.841132)
			(xy 47.563532 -68.84162) (xy 47.534614 -68.841109) (xy 47.477442 -68.832383) (xy 47.422241 -68.815126)
			(xy 47.370279 -68.789733) (xy 47.322745 -68.756786) (xy 47.28073 -68.717042) (xy 47.262542 -68.694554)
			(xy 47.254965 -68.685808) (xy 47.234217 -68.675618) (xy 47.222664 -68.674996) (xy 47.1424 -68.674996)
			(xy 47.130832 -68.675568) (xy 47.110062 -68.685762) (xy 47.102522 -68.694554) (xy 47.085769 -68.715337)
			(xy 47.047415 -68.752467) (xy 47.004261 -68.783889) (xy 46.957147 -68.808988) (xy 46.906995 -68.827274)
			(xy 46.854784 -68.838391) (xy 46.801532 -68.842121) (xy 46.74828 -68.838391) (xy 46.696069 -68.827274)
			(xy 46.645917 -68.808988) (xy 46.598803 -68.783889) (xy 46.555649 -68.752467) (xy 46.517295 -68.715337)
			(xy 46.500542 -68.694554) (xy 46.492965 -68.685808) (xy 46.472217 -68.675618) (xy 46.460664 -68.674996)
			(xy 46.3804 -68.674996) (xy 46.368832 -68.675568) (xy 46.348062 -68.685762) (xy 46.340522 -68.694554)
			(xy 46.323769 -68.715337) (xy 46.285415 -68.752467) (xy 46.242261 -68.783889) (xy 46.195147 -68.808988)
			(xy 46.144995 -68.827274) (xy 46.092784 -68.838391) (xy 46.039532 -68.842121) (xy 45.98628 -68.838391)
			(xy 45.934069 -68.827274) (xy 45.883917 -68.808988) (xy 45.836803 -68.783889) (xy 45.793649 -68.752467)
			(xy 45.755295 -68.715337) (xy 45.738542 -68.694554) (xy 45.730965 -68.685808) (xy 45.710217 -68.675618)
			(xy 45.698664 -68.674996) (xy 45.6184 -68.674996) (xy 45.606832 -68.675568) (xy 45.586062 -68.685762)
			(xy 45.578522 -68.694554) (xy 45.560332 -68.717038) (xy 45.518311 -68.756771) (xy 45.470775 -68.789708)
			(xy 45.418814 -68.815096) (xy 45.363617 -68.832353) (xy 45.306448 -68.841084) (xy 45.277532 -68.84162)
			(xy 45.250279 -68.841135) (xy 45.196326 -68.833382) (xy 45.144026 -68.818029) (xy 45.094443 -68.795389)
			(xy 45.048587 -68.765923) (xy 45.007392 -68.73023) (xy 44.971696 -68.689038) (xy 44.942226 -68.643185)
			(xy 44.919582 -68.593604) (xy 44.904225 -68.541305) (xy 44.896467 -68.487353) (xy 43.667109 -68.487353)
			(xy 42.432732 -69.72173) (xy 42.424593 -69.730756) (xy 42.417147 -69.753851) (xy 42.418508 -69.765926)
			(xy 42.434002 -69.859398) (xy 42.44848 -69.87921) (xy 42.459656 -69.884544) (xy 42.483247 -69.896697)
			(xy 42.527119 -69.926553) (xy 42.566427 -69.962203) (xy 42.600412 -70.00296) (xy 42.628417 -70.048035)
			(xy 42.649902 -70.096558) (xy 42.664452 -70.147591) (xy 42.671785 -70.200148) (xy 42.672254 -70.226682)
			(xy 42.671835 -70.251554) (xy 42.665337 -70.300874) (xy 42.652488 -70.348931) (xy 42.633505 -70.394912)
			(xy 42.621454 -70.416674) (xy 42.615104 -70.42785) (xy 42.614342 -70.452488) (xy 42.661586 -70.55104)
			(xy 42.681398 -70.565772) (xy 42.694098 -70.567804) (xy 42.720768 -70.572375) (xy 42.772553 -70.588064)
			(xy 42.821598 -70.610919) (xy 42.866917 -70.640482) (xy 42.9076 -70.676157) (xy 42.942827 -70.717228)
			(xy 42.971891 -70.762869) (xy 42.994208 -70.812161) (xy 43.009328 -70.864115) (xy 43.016947 -70.917685)
			(xy 43.01744 -70.94474) (xy 43.016952 -70.97199) (xy 43.009191 -71.025935) (xy 43.001855 -71.050912)
			(xy 43.535852 -71.050912) (xy 43.539923 -70.99529) (xy 43.552049 -70.940853) (xy 43.571972 -70.888762)
			(xy 43.599268 -70.840127) (xy 43.633354 -70.795984) (xy 43.673503 -70.757275) (xy 43.718861 -70.724824)
			(xy 43.768461 -70.699323) (xy 43.821245 -70.681316) (xy 43.876088 -70.671186) (xy 43.931822 -70.669149)
			(xy 43.987259 -70.675249) (xy 44.041216 -70.689355) (xy 44.092545 -70.711167) (xy 44.140151 -70.740221)
			(xy 44.183019 -70.775896) (xy 44.220236 -70.817433) (xy 44.251009 -70.863946) (xy 44.274681 -70.914443)
			(xy 44.290749 -70.96785) (xy 44.298869 -71.023026) (xy 44.299378 -71.050912) (xy 44.298869 -71.078798)
			(xy 44.290749 -71.133974) (xy 44.274681 -71.187381) (xy 44.251009 -71.237878) (xy 44.220236 -71.284391)
			(xy 44.183019 -71.325928) (xy 44.140151 -71.361603) (xy 44.092545 -71.390657) (xy 44.041216 -71.412469)
			(xy 43.987259 -71.426575) (xy 43.931822 -71.432675) (xy 43.876088 -71.430638) (xy 43.821245 -71.420508)
			(xy 43.768461 -71.402501) (xy 43.718861 -71.377) (xy 43.673503 -71.344549) (xy 43.633354 -71.30584)
			(xy 43.599268 -71.261697) (xy 43.571972 -71.213062) (xy 43.552049 -71.160971) (xy 43.539923 -71.106534)
			(xy 43.535852 -71.050912) (xy 43.001855 -71.050912) (xy 42.993832 -71.078227) (xy 42.971189 -71.127801)
			(xy 42.941722 -71.173649) (xy 42.906031 -71.214837) (xy 42.864843 -71.250527) (xy 42.818994 -71.279993)
			(xy 42.76942 -71.302635) (xy 42.717127 -71.317992) (xy 42.663182 -71.325752) (xy 42.635932 -71.326248)
			(xy 42.608987 -71.325782) (xy 42.555631 -71.318206) (xy 42.503868 -71.303212) (xy 42.454723 -71.281098)
			(xy 42.431716 -71.267066) (xy 42.420286 -71.2597) (xy 42.394124 -71.25843) (xy 42.292524 -71.30796)
			(xy 42.277538 -71.329296) (xy 42.276268 -71.342758) (xy 42.272991 -71.37066) (xy 42.25929 -71.425143)
			(xy 42.237747 -71.477027) (xy 42.208826 -71.525189) (xy 42.173154 -71.568589) (xy 42.131501 -71.606288)
			(xy 42.08477 -71.637469) (xy 42.033971 -71.661458) (xy 41.980202 -71.677738) (xy 41.924628 -71.685954)
			(xy 41.896538 -71.68642) (xy 41.868475 -71.685925) (xy 41.812953 -71.677703) (xy 41.759237 -71.661431)
			(xy 41.708486 -71.637461) (xy 41.661798 -71.60631) (xy 41.620179 -71.568652) (xy 41.584531 -71.5253)
			(xy 41.56964 -71.501508) (xy 41.566338 -71.496174) (xy 41.344596 -71.274178) (xy 41.324471 -71.253328)
			(xy 41.29037 -71.206478) (xy 41.264019 -71.154869) (xy 41.246068 -71.099773) (xy 41.236959 -71.042547)
			(xy 41.236392 -71.013574) (xy 41.236392 -70.405244) (xy 41.236024 -70.395776) (xy 41.229153 -70.378134)
			(xy 41.216308 -70.364225) (xy 41.207944 -70.359778) (xy 41.112694 -70.313296) (xy 41.083992 -70.316344)
			(xy 41.072308 -70.325234) (xy 41.052107 -70.340511) (xy 41.008436 -70.366162) (xy 40.961754 -70.385808)
			(xy 40.912883 -70.399103) (xy 40.862682 -70.405813) (xy 40.837358 -70.40626) (xy 40.814066 -70.40588)
			(xy 40.767836 -70.400149) (xy 40.745156 -70.39483) (xy 40.73906 -70.39356) (xy 40.432228 -70.39356)
			(xy 40.422265 -70.394046) (xy 40.403839 -70.401631) (xy 40.396414 -70.408292) (xy 40.074088 -70.730618)
			(xy 40.066852 -70.73852) (xy 40.059207 -70.758514) (xy 40.059356 -70.769226) (xy 40.063674 -70.855586)
			(xy 40.07358 -70.874382) (xy 40.081962 -70.881494) (xy 40.103648 -70.8997) (xy 40.141919 -70.941429)
			(xy 40.173598 -70.988359) (xy 40.197987 -71.039458) (xy 40.214549 -71.093603) (xy 40.222922 -71.149601)
			(xy 40.22344 -71.177912) (xy 40.222953 -71.205164) (xy 40.215196 -71.259112) (xy 40.19984 -71.311407)
			(xy 40.177198 -71.360985) (xy 40.147732 -71.406836) (xy 40.112041 -71.448027) (xy 40.070852 -71.48372)
			(xy 40.025002 -71.513189) (xy 39.975426 -71.535833) (xy 39.923131 -71.551191) (xy 39.869183 -71.558952)
			(xy 39.841932 -71.55942) (xy 39.83156 -71.559342) (xy 39.810848 -71.558196) (xy 39.80053 -71.557134)
			(xy 39.789608 -71.555864) (xy 39.769288 -71.562468) (xy 39.704772 -71.62038) (xy 39.697218 -71.627974)
			(xy 39.688543 -71.64753) (xy 39.688008 -71.658226) (xy 39.688008 -72.701912) (xy 42.634914 -72.701912)
			(xy 42.638985 -72.64629) (xy 42.651111 -72.591853) (xy 42.671034 -72.539762) (xy 42.69833 -72.491127)
			(xy 42.732416 -72.446984) (xy 42.772565 -72.408275) (xy 42.817923 -72.375824) (xy 42.867523 -72.350323)
			(xy 42.920307 -72.332316) (xy 42.97515 -72.322186) (xy 43.030884 -72.320149) (xy 43.086321 -72.326249)
			(xy 43.140278 -72.340355) (xy 43.191607 -72.362167) (xy 43.239213 -72.391221) (xy 43.282081 -72.426896)
			(xy 43.319298 -72.468433) (xy 43.350071 -72.514946) (xy 43.373743 -72.565443) (xy 43.389811 -72.61885)
			(xy 43.397931 -72.674026) (xy 43.39844 -72.701912) (xy 43.397931 -72.729798) (xy 43.389811 -72.784974)
			(xy 43.373743 -72.838381) (xy 43.350071 -72.888878) (xy 43.319298 -72.935391) (xy 43.282081 -72.976928)
			(xy 43.239213 -73.012603) (xy 43.191607 -73.041657) (xy 43.140278 -73.063469) (xy 43.086321 -73.077575)
			(xy 43.030884 -73.083675) (xy 42.97515 -73.081638) (xy 42.920307 -73.071508) (xy 42.867523 -73.053501)
			(xy 42.817923 -73.028) (xy 42.772565 -72.995549) (xy 42.732416 -72.95684) (xy 42.69833 -72.912697)
			(xy 42.671034 -72.864062) (xy 42.651111 -72.811971) (xy 42.638985 -72.757534) (xy 42.634914 -72.701912)
			(xy 39.688008 -72.701912) (xy 39.688008 -75.467464) (xy 39.688494 -75.477426) (xy 39.696082 -75.49585)
			(xy 39.70274 -75.503278) (xy 40.08501 -75.885802) (xy 40.092411 -75.892484) (xy 40.110824 -75.900082)
			(xy 40.130743 -75.900089) (xy 40.140128 -75.896724) (xy 40.24122 -75.855576) (xy 40.258238 -75.83043)
			(xy 40.258492 -75.814936) (xy 40.259253 -75.787874) (xy 40.267476 -75.734366) (xy 40.28318 -75.682557)
			(xy 40.30605 -75.633488) (xy 40.335627 -75.588145) (xy 40.371316 -75.547438) (xy 40.4124 -75.512185)
			(xy 40.458056 -75.483093) (xy 40.507366 -75.460747) (xy 40.559339 -75.445596) (xy 40.612932 -75.437943)
			(xy 40.64 -75.437492) (xy 40.667251 -75.437978) (xy 40.721199 -75.445734) (xy 40.773494 -75.461089)
			(xy 40.823071 -75.483731) (xy 40.868921 -75.513197) (xy 40.910112 -75.548888) (xy 40.945803 -75.590079)
			(xy 40.975269 -75.635929) (xy 40.981169 -75.648847) (xy 41.35022 -75.648847) (xy 41.35022 -75.594353)
			(xy 41.357975 -75.540412) (xy 41.373328 -75.488125) (xy 41.395965 -75.438554) (xy 41.425427 -75.392709)
			(xy 41.461113 -75.351524) (xy 41.502297 -75.315837) (xy 41.54814 -75.286373) (xy 41.59771 -75.263734)
			(xy 41.649997 -75.248379) (xy 41.703937 -75.240621) (xy 41.731184 -75.240134) (xy 41.759752 -75.24065)
			(xy 41.816247 -75.249173) (xy 41.870839 -75.266031) (xy 41.896792 -75.27798) (xy 41.909143 -75.283555)
			(xy 41.935776 -75.288521) (xy 41.962778 -75.286304) (xy 41.988245 -75.27706) (xy 42.010382 -75.261441)
			(xy 42.027629 -75.240548) (xy 42.038772 -75.215854) (xy 42.041318 -75.202542) (xy 42.046091 -75.176013)
			(xy 42.061988 -75.124511) (xy 42.084977 -75.07576) (xy 42.114602 -75.030732) (xy 42.150271 -74.990324)
			(xy 42.191274 -74.95534) (xy 42.236795 -74.926478) (xy 42.285926 -74.904313) (xy 42.337688 -74.889286)
			(xy 42.39105 -74.881697) (xy 42.418 -74.881232) (xy 42.445254 -74.881638) (xy 42.499207 -74.889395)
			(xy 42.551508 -74.904752) (xy 42.60109 -74.927395) (xy 42.646945 -74.956865) (xy 42.68814 -74.99256)
			(xy 42.723835 -75.033755) (xy 42.753305 -75.07961) (xy 42.775948 -75.129192) (xy 42.791305 -75.181493)
			(xy 42.799062 -75.235446) (xy 42.799062 -75.289954) (xy 42.791305 -75.343907) (xy 42.775948 -75.396208)
			(xy 42.753305 -75.44579) (xy 42.723835 -75.491645) (xy 42.68814 -75.53284) (xy 42.646945 -75.568535)
			(xy 42.60109 -75.598005) (xy 42.551508 -75.620648) (xy 42.499207 -75.636005) (xy 42.445254 -75.643762)
			(xy 42.418 -75.644248) (xy 42.389432 -75.64374) (xy 42.332936 -75.635214) (xy 42.278345 -75.618353)
			(xy 42.252392 -75.606402) (xy 42.240044 -75.600821) (xy 42.21341 -75.59586) (xy 42.186409 -75.59808)
			(xy 42.160944 -75.607325) (xy 42.138807 -75.622944) (xy 42.121559 -75.643836) (xy 42.110414 -75.668529)
			(xy 42.107866 -75.68184) (xy 42.10317 -75.708384) (xy 42.087262 -75.759887) (xy 42.064262 -75.808638)
			(xy 42.034627 -75.853665) (xy 41.998949 -75.894072) (xy 41.980355 -75.909932) (xy 42.888914 -75.909932)
			(xy 42.892985 -75.85431) (xy 42.905111 -75.799873) (xy 42.925034 -75.747782) (xy 42.95233 -75.699147)
			(xy 42.986416 -75.655004) (xy 43.026565 -75.616295) (xy 43.071923 -75.583844) (xy 43.121523 -75.558343)
			(xy 43.174307 -75.540336) (xy 43.22915 -75.530206) (xy 43.284884 -75.528169) (xy 43.340321 -75.534269)
			(xy 43.394278 -75.548375) (xy 43.445607 -75.570187) (xy 43.493213 -75.599241) (xy 43.536081 -75.634916)
			(xy 43.573298 -75.676453) (xy 43.604071 -75.722966) (xy 43.627743 -75.773463) (xy 43.641443 -75.819)
			(xy 43.777914 -75.819) (xy 43.781985 -75.763378) (xy 43.794111 -75.708941) (xy 43.814034 -75.65685)
			(xy 43.84133 -75.608215) (xy 43.875416 -75.564072) (xy 43.915565 -75.525363) (xy 43.960923 -75.492912)
			(xy 44.010523 -75.467411) (xy 44.063307 -75.449404) (xy 44.11815 -75.439274) (xy 44.173884 -75.437237)
			(xy 44.229321 -75.443337) (xy 44.283278 -75.457443) (xy 44.334607 -75.479255) (xy 44.382213 -75.508309)
			(xy 44.425081 -75.543984) (xy 44.462298 -75.585521) (xy 44.493071 -75.632034) (xy 44.516743 -75.682531)
			(xy 44.532811 -75.735938) (xy 44.540931 -75.791114) (xy 44.54144 -75.819) (xy 44.540931 -75.846886)
			(xy 44.532811 -75.902062) (xy 44.516743 -75.955469) (xy 44.493071 -76.005966) (xy 44.462298 -76.052479)
			(xy 44.443911 -76.073) (xy 46.226982 -76.073) (xy 46.231053 -76.017378) (xy 46.243179 -75.962941)
			(xy 46.263102 -75.91085) (xy 46.290398 -75.862215) (xy 46.324484 -75.818072) (xy 46.364633 -75.779363)
			(xy 46.409991 -75.746912) (xy 46.459591 -75.721411) (xy 46.512375 -75.703404) (xy 46.567218 -75.693274)
			(xy 46.622952 -75.691237) (xy 46.678389 -75.697337) (xy 46.732346 -75.711443) (xy 46.783675 -75.733255)
			(xy 46.831281 -75.762309) (xy 46.874149 -75.797984) (xy 46.911366 -75.839521) (xy 46.942139 -75.886034)
			(xy 46.965811 -75.936531) (xy 46.981879 -75.989938) (xy 46.989999 -76.045114) (xy 46.990508 -76.073)
			(xy 46.989999 -76.100886) (xy 46.981879 -76.156062) (xy 46.965811 -76.209469) (xy 46.942139 -76.259966)
			(xy 46.911366 -76.306479) (xy 46.874149 -76.348016) (xy 46.831281 -76.383691) (xy 46.783675 -76.412745)
			(xy 46.732346 -76.434557) (xy 46.678389 -76.448663) (xy 46.622952 -76.454763) (xy 46.567218 -76.452726)
			(xy 46.512375 -76.442596) (xy 46.459591 -76.424589) (xy 46.409991 -76.399088) (xy 46.364633 -76.366637)
			(xy 46.324484 -76.327928) (xy 46.290398 -76.283785) (xy 46.263102 -76.23515) (xy 46.243179 -76.183059)
			(xy 46.231053 -76.128622) (xy 46.226982 -76.073) (xy 44.443911 -76.073) (xy 44.425081 -76.094016)
			(xy 44.382213 -76.129691) (xy 44.334607 -76.158745) (xy 44.283278 -76.180557) (xy 44.229321 -76.194663)
			(xy 44.173884 -76.200763) (xy 44.11815 -76.198726) (xy 44.063307 -76.188596) (xy 44.010523 -76.170589)
			(xy 43.960923 -76.145088) (xy 43.915565 -76.112637) (xy 43.875416 -76.073928) (xy 43.84133 -76.029785)
			(xy 43.814034 -75.98115) (xy 43.794111 -75.929059) (xy 43.781985 -75.874622) (xy 43.777914 -75.819)
			(xy 43.641443 -75.819) (xy 43.643811 -75.82687) (xy 43.651931 -75.882046) (xy 43.65244 -75.909932)
			(xy 43.651931 -75.937818) (xy 43.643811 -75.992994) (xy 43.627743 -76.046401) (xy 43.604071 -76.096898)
			(xy 43.573298 -76.143411) (xy 43.536081 -76.184948) (xy 43.493213 -76.220623) (xy 43.445607 -76.249677)
			(xy 43.394278 -76.271489) (xy 43.340321 -76.285595) (xy 43.284884 -76.291695) (xy 43.22915 -76.289658)
			(xy 43.174307 -76.279528) (xy 43.121523 -76.261521) (xy 43.071923 -76.23602) (xy 43.026565 -76.203569)
			(xy 42.986416 -76.16486) (xy 42.95233 -76.120717) (xy 42.925034 -76.072082) (xy 42.905111 -76.019991)
			(xy 42.892985 -75.965554) (xy 42.888914 -75.909932) (xy 41.980355 -75.909932) (xy 41.957937 -75.929053)
			(xy 41.912409 -75.957913) (xy 41.863272 -75.980075) (xy 41.811504 -75.995099) (xy 41.758136 -76.002686)
			(xy 41.731184 -76.00315) (xy 41.703937 -76.002579) (xy 41.649997 -75.994821) (xy 41.59771 -75.979466)
			(xy 41.54814 -75.956827) (xy 41.502297 -75.927363) (xy 41.461113 -75.891676) (xy 41.425427 -75.850491)
			(xy 41.395965 -75.804646) (xy 41.373328 -75.755075) (xy 41.357975 -75.702788) (xy 41.35022 -75.648847)
			(xy 40.981169 -75.648847) (xy 40.997911 -75.685506) (xy 41.013266 -75.737801) (xy 41.021022 -75.791749)
			(xy 41.021022 -75.846251) (xy 41.013266 -75.900199) (xy 40.997911 -75.952494) (xy 40.975269 -76.002071)
			(xy 40.945803 -76.047921) (xy 40.910112 -76.089112) (xy 40.868921 -76.124803) (xy 40.823071 -76.154269)
			(xy 40.773494 -76.176911) (xy 40.721199 -76.192266) (xy 40.667251 -76.200022) (xy 40.64 -76.200508)
			(xy 40.608287 -76.199879) (xy 40.545729 -76.189414) (xy 40.51554 -76.17968) (xy 40.50157 -76.174854)
			(xy 40.473376 -76.181204) (xy 40.462962 -76.191618) (xy 40.456117 -76.198985) (xy 40.448364 -76.217524)
			(xy 40.448353 -76.237619) (xy 40.456084 -76.256166) (xy 40.462962 -76.2635) (xy 40.523922 -76.32446)
			(xy 40.531292 -76.331203) (xy 40.549754 -76.338794) (xy 40.559736 -76.339192) (xy 41.020238 -76.339192)
			(xy 41.031171 -76.33868) (xy 41.051063 -76.329608) (xy 41.058592 -76.321666) (xy 41.076788 -76.301381)
			(xy 41.117979 -76.265706) (xy 41.163829 -76.236257) (xy 41.213404 -76.213637) (xy 41.265695 -76.198304)
			(xy 41.319636 -76.190572) (xy 41.346882 -76.190094) (xy 41.374136 -76.190556) (xy 41.428088 -76.198311)
			(xy 41.480388 -76.213666) (xy 41.529971 -76.236307) (xy 41.575826 -76.265775) (xy 41.61702 -76.301468)
			(xy 41.652716 -76.342661) (xy 41.682185 -76.388515) (xy 41.704829 -76.438097) (xy 41.720186 -76.490396)
			(xy 41.727943 -76.544348) (xy 41.72839 -76.571602) (xy 41.727899 -76.599667) (xy 41.719684 -76.655193)
			(xy 41.703418 -76.708914) (xy 41.679451 -76.75967) (xy 41.648302 -76.806364) (xy 41.610644 -76.847987)
			(xy 41.56729 -76.883639) (xy 41.543478 -76.8985) (xy 41.538144 -76.901802) (xy 41.471088 -76.968604)
			(xy 41.450238 -76.98873) (xy 41.403388 -77.022832) (xy 41.35178 -77.049184) (xy 41.296684 -77.067137)
			(xy 41.239457 -77.076248) (xy 41.210484 -77.076808) (xy 40.386 -77.076808) (xy 40.357025 -77.076253)
			(xy 40.299794 -77.067151) (xy 40.244693 -77.049205) (xy 40.193079 -77.022855) (xy 40.146226 -76.988751)
			(xy 40.125396 -76.968604) (xy 39.058596 -75.901804) (xy 39.036946 -75.879213) (xy 39.000811 -75.828135)
			(xy 38.97381 -75.771694) (xy 38.964616 -75.741784) (xy 38.961568 -75.731624) (xy 38.948614 -75.715622)
			(xy 38.865302 -75.671426) (xy 38.844728 -75.669902) (xy 38.834822 -75.673204) (xy 38.805613 -75.68224)
			(xy 38.74525 -75.691944) (xy 38.71468 -75.692508) (xy 38.687619 -75.69204) (xy 38.63404 -75.684399)
			(xy 38.58208 -75.669258) (xy 38.532782 -75.646923) (xy 38.487138 -75.617841) (xy 38.446065 -75.582597)
			(xy 38.410388 -75.5419) (xy 38.380824 -75.496567) (xy 38.357967 -75.447509) (xy 38.349682 -75.421744)
			(xy 38.346126 -75.409806) (xy 38.329108 -75.39228) (xy 38.227762 -75.357736) (xy 38.203632 -75.361038)
			(xy 38.193726 -75.36815) (xy 38.169398 -75.384736) (xy 38.116713 -75.41102) (xy 38.060616 -75.428902)
			(xy 38.002439 -75.437958) (xy 37.973 -75.438508) (xy 37.945749 -75.438022) (xy 37.891801 -75.430266)
			(xy 37.839506 -75.414911) (xy 37.789929 -75.392269) (xy 37.744079 -75.362803) (xy 37.702888 -75.327112)
			(xy 37.667197 -75.285921) (xy 37.637731 -75.240071) (xy 37.615089 -75.190494) (xy 37.599734 -75.138199)
			(xy 37.591978 -75.084251) (xy 37.591978 -75.029749) (xy 37.599734 -74.975801) (xy 37.615089 -74.923506)
			(xy 37.637731 -74.873929) (xy 37.667197 -74.828079) (xy 37.702888 -74.786888) (xy 37.744079 -74.751197)
			(xy 37.789929 -74.721731) (xy 37.839506 -74.699089) (xy 37.891801 -74.683734) (xy 37.945749 -74.675978)
			(xy 37.973 -74.675492) (xy 38.000062 -74.675958) (xy 38.053643 -74.683597) (xy 38.105605 -74.698736)
			(xy 38.154905 -74.72107) (xy 38.200551 -74.750151) (xy 38.241627 -74.785395) (xy 38.277306 -74.826092)
			(xy 38.306872 -74.871426) (xy 38.329731 -74.920485) (xy 38.337998 -74.946256) (xy 38.341554 -74.958194)
			(xy 38.358572 -74.97572) (xy 38.459918 -75.010264) (xy 38.484048 -75.006962) (xy 38.493954 -74.99985)
			(xy 38.518281 -74.983262) (xy 38.570967 -74.956976) (xy 38.627063 -74.939091) (xy 38.685241 -74.930032)
			(xy 38.71468 -74.929492) (xy 38.741524 -74.929947) (xy 38.794683 -74.937465) (xy 38.820598 -74.944478)
			(xy 38.832282 -74.94778) (xy 38.85565 -74.943716) (xy 38.930326 -74.887582) (xy 38.939359 -74.879941)
			(xy 38.949834 -74.858758) (xy 38.950392 -74.846942) (xy 38.950392 -70.964044) (xy 38.950952 -70.935071)
			(xy 38.96006 -70.877844) (xy 38.978014 -70.822748) (xy 39.004368 -70.771141) (xy 39.038475 -70.724295)
			(xy 39.058596 -70.70344) (xy 39.997888 -69.764148) (xy 40.009572 -69.752718) (xy 40.021256 -69.74205)
			(xy 40.028368 -69.711824) (xy 39.988236 -69.6087) (xy 39.984152 -69.599337) (xy 39.969981 -69.584652)
			(xy 39.951196 -69.576676) (xy 39.940992 -69.576188) (xy 34.764726 -69.576188) (xy 34.75863 -69.577712)
			(xy 34.735951 -69.583034) (xy 34.68972 -69.588763) (xy 34.666428 -69.589142) (xy 34.639171 -69.588681)
			(xy 34.585213 -69.580927) (xy 34.532907 -69.565572) (xy 34.483319 -69.542929) (xy 34.437458 -69.513459)
			(xy 34.396258 -69.477762) (xy 34.360558 -69.436565) (xy 34.331085 -69.390706) (xy 34.308438 -69.34112)
			(xy 34.293079 -69.288815) (xy 34.285321 -69.234857) (xy 34.285321 -69.180343) (xy 34.293079 -69.126385)
			(xy 34.308438 -69.07408) (xy 34.331085 -69.024494) (xy 34.360558 -68.978635) (xy 34.396258 -68.937438)
			(xy 34.437458 -68.901741) (xy 34.483319 -68.872271) (xy 34.532907 -68.849628) (xy 34.585213 -68.834273)
			(xy 34.639171 -68.826519) (xy 34.666428 -68.826126) (xy 34.68972 -68.826505) (xy 34.735951 -68.832235)
			(xy 34.75863 -68.837556) (xy 34.764726 -68.83908) (xy 35.733736 -68.83908) (xy 35.7423 -68.838702)
			(xy 35.758451 -68.832984) (xy 35.771838 -68.822289) (xy 35.776662 -68.815204) (xy 35.829494 -68.731384)
			(xy 35.831018 -68.705476) (xy 35.82543 -68.693538) (xy 35.813672 -68.667753) (xy 35.797052 -68.613575)
			(xy 35.788628 -68.557535) (xy 35.788092 -68.5292) (xy 35.78847 -68.505908) (xy 35.794197 -68.459676)
			(xy 35.799522 -68.436998) (xy 35.800792 -68.430902) (xy 35.800792 -68.14058) (xy 35.800439 -68.131268)
			(xy 35.793867 -68.11385) (xy 35.781463 -68.099966) (xy 35.77336 -68.095368) (xy 35.679888 -68.047616)
			(xy 35.65144 -68.049902) (xy 35.639756 -68.058284) (xy 35.615231 -68.075268) (xy 35.562011 -68.102215)
			(xy 35.505245 -68.120547) (xy 35.446317 -68.129818) (xy 35.41649 -68.13042) (xy 35.389238 -68.129934)
			(xy 35.33529 -68.122176) (xy 35.282995 -68.106819) (xy 35.233417 -68.084177) (xy 35.187567 -68.054709)
			(xy 35.146376 -68.019017) (xy 35.110685 -67.977825) (xy 35.081219 -67.931974) (xy 35.058577 -67.882396)
			(xy 35.043222 -67.8301) (xy 35.035466 -67.776152) (xy 35.035466 -67.721648) (xy 35.043222 -67.6677)
			(xy 35.058577 -67.615404) (xy 35.081219 -67.565826) (xy 35.110685 -67.519975) (xy 35.146376 -67.478783)
			(xy 35.187567 -67.443091) (xy 35.233417 -67.413623) (xy 35.282995 -67.390981) (xy 35.33529 -67.375624)
			(xy 35.389238 -67.367866) (xy 35.41649 -67.367404) (xy 35.446318 -67.367979) (xy 35.505248 -67.377258)
			(xy 35.562017 -67.395593) (xy 35.615243 -67.422536) (xy 35.639756 -67.43954) (xy 35.65144 -67.447922)
			(xy 35.679888 -67.450208) (xy 35.77336 -67.402456) (xy 35.781407 -67.397795) (xy 35.793749 -67.383902)
			(xy 35.800357 -67.366535) (xy 35.800792 -67.357244) (xy 35.800792 -67.128136) (xy 35.800306 -67.118174)
			(xy 35.792718 -67.09975) (xy 35.78606 -67.092322) (xy 35.477196 -66.783204) (xy 35.457069 -66.762354)
			(xy 35.422965 -66.715505) (xy 35.396611 -66.663897) (xy 35.378656 -66.608801) (xy 35.369542 -66.551574)
			(xy 35.368992 -66.5226) (xy 35.368992 -64.3382) (xy 35.369547 -64.309225) (xy 35.378649 -64.251994)
			(xy 35.396595 -64.196893) (xy 35.422945 -64.145279) (xy 35.457049 -64.098426) (xy 35.477196 -64.077596)
			(xy 37.077396 -62.477396) (xy 37.098246 -62.457269) (xy 37.145095 -62.423165) (xy 37.196703 -62.396811)
			(xy 37.251799 -62.378856) (xy 37.309026 -62.369742) (xy 37.338 -62.369192) (xy 38.128702 -62.369192)
			(xy 38.134798 -62.367922) (xy 38.157477 -62.362602) (xy 38.203708 -62.356875) (xy 38.227 -62.356492)
			(xy 38.254251 -62.356978) (xy 38.308199 -62.364734) (xy 38.360494 -62.380089) (xy 38.410071 -62.402731)
			(xy 38.455921 -62.432197) (xy 38.497112 -62.467888) (xy 38.532803 -62.509079) (xy 38.562269 -62.554929)
			(xy 38.584911 -62.604506) (xy 38.600266 -62.656801) (xy 38.608022 -62.710749) (xy 38.608508 -62.738)
			(xy 38.60789 -62.769108) (xy 38.597802 -62.830501) (xy 38.588442 -62.860174) (xy 38.584124 -62.87262)
			(xy 38.588696 -62.89802) (xy 38.658292 -62.985142) (xy 38.682168 -62.995302) (xy 38.695122 -62.993778)
			(xy 38.705063 -62.992811) (xy 38.725012 -62.991793) (xy 38.735 -62.991746) (xy 38.762257 -62.992209)
			(xy 38.816216 -62.999967) (xy 38.868521 -63.015326) (xy 38.918108 -63.037972) (xy 38.963968 -63.067445)
			(xy 39.005166 -63.103145) (xy 39.040864 -63.144345) (xy 39.070335 -63.190205) (xy 39.092979 -63.239793)
			(xy 39.108336 -63.292099) (xy 39.116092 -63.346058) (xy 39.11609 -63.400572) (xy 39.108329 -63.454531)
			(xy 39.092969 -63.506836) (xy 39.07032 -63.556422) (xy 39.040845 -63.60228) (xy 39.005144 -63.643477)
			(xy 38.963943 -63.679173) (xy 38.918081 -63.708642) (xy 38.868492 -63.731285) (xy 38.816186 -63.746639)
			(xy 38.762226 -63.754393) (xy 38.707713 -63.754389) (xy 38.653754 -63.746626) (xy 38.60145 -63.731263)
			(xy 38.551865 -63.708613) (xy 38.506008 -63.679136) (xy 38.464812 -63.643433) (xy 38.429118 -63.602231)
			(xy 38.39965 -63.556368) (xy 38.37701 -63.506778) (xy 38.361658 -63.454471) (xy 38.353906 -63.400511)
			(xy 38.353492 -63.373254) (xy 38.354106 -63.342145) (xy 38.364185 -63.280749) (xy 38.373558 -63.25108)
			(xy 38.377876 -63.238634) (xy 38.373304 -63.213234) (xy 38.303708 -63.126112) (xy 38.279832 -63.115952)
			(xy 38.266878 -63.117476) (xy 38.256937 -63.118443) (xy 38.236988 -63.119461) (xy 38.227 -63.119508)
			(xy 38.203708 -63.11913) (xy 38.157476 -63.113403) (xy 38.134798 -63.108078) (xy 38.128702 -63.106808)
			(xy 38.109652 -63.106808) (xy 38.099651 -63.107304) (xy 38.081177 -63.114973) (xy 38.067041 -63.129124)
			(xy 38.059393 -63.147607) (xy 38.058852 -63.157608) (xy 38.058852 -63.169546) (xy 38.069266 -63.190374)
			(xy 38.078664 -63.19774) (xy 38.101398 -63.215909) (xy 38.141608 -63.257976) (xy 38.174956 -63.305668)
			(xy 38.200665 -63.357874) (xy 38.218139 -63.413383) (xy 38.226971 -63.470903) (xy 38.227508 -63.5)
			(xy 38.227022 -63.527251) (xy 38.219266 -63.581199) (xy 38.203911 -63.633494) (xy 38.181269 -63.683071)
			(xy 38.151803 -63.728921) (xy 38.116112 -63.770112) (xy 38.076079 -63.8048) (xy 40.562782 -63.8048)
			(xy 40.566853 -63.749178) (xy 40.578979 -63.694741) (xy 40.598902 -63.64265) (xy 40.626198 -63.594015)
			(xy 40.660284 -63.549872) (xy 40.700433 -63.511163) (xy 40.745791 -63.478712) (xy 40.795391 -63.453211)
			(xy 40.848175 -63.435204) (xy 40.903018 -63.425074) (xy 40.958752 -63.423037) (xy 41.014189 -63.429137)
			(xy 41.068146 -63.443243) (xy 41.119475 -63.465055) (xy 41.167081 -63.494109) (xy 41.209949 -63.529784)
			(xy 41.247166 -63.571321) (xy 41.277939 -63.617834) (xy 41.301611 -63.668331) (xy 41.317679 -63.721738)
			(xy 41.325799 -63.776914) (xy 41.326308 -63.8048) (xy 41.325799 -63.832686) (xy 41.317679 -63.887862)
			(xy 41.301611 -63.941269) (xy 41.277939 -63.991766) (xy 41.247166 -64.038279) (xy 41.209949 -64.079816)
			(xy 41.167081 -64.115491) (xy 41.119475 -64.144545) (xy 41.068146 -64.166357) (xy 41.014189 -64.180463)
			(xy 40.958752 -64.186563) (xy 40.903018 -64.184526) (xy 40.848175 -64.174396) (xy 40.795391 -64.156389)
			(xy 40.745791 -64.130888) (xy 40.700433 -64.098437) (xy 40.660284 -64.059728) (xy 40.626198 -64.015585)
			(xy 40.598902 -63.96695) (xy 40.578979 -63.914859) (xy 40.566853 -63.860422) (xy 40.562782 -63.8048)
			(xy 38.076079 -63.8048) (xy 38.074921 -63.805803) (xy 38.029071 -63.835269) (xy 37.979494 -63.857911)
			(xy 37.927199 -63.873266) (xy 37.873251 -63.881022) (xy 37.818749 -63.881022) (xy 37.764801 -63.873266)
			(xy 37.712506 -63.857911) (xy 37.662929 -63.835269) (xy 37.617079 -63.805803) (xy 37.575888 -63.770112)
			(xy 37.540197 -63.728921) (xy 37.510731 -63.683071) (xy 37.488089 -63.633494) (xy 37.472734 -63.581199)
			(xy 37.464978 -63.527251) (xy 37.464492 -63.5) (xy 37.465041 -63.470904) (xy 37.473881 -63.413386)
			(xy 37.491355 -63.357879) (xy 37.517059 -63.305671) (xy 37.550395 -63.257973) (xy 37.59059 -63.215892)
			(xy 37.613336 -63.19774) (xy 37.622734 -63.190374) (xy 37.633148 -63.169546) (xy 37.633148 -63.157608)
			(xy 37.632662 -63.147596) (xy 37.625006 -63.129093) (xy 37.610854 -63.114926) (xy 37.59236 -63.107249)
			(xy 37.582348 -63.106808) (xy 37.511736 -63.106808) (xy 37.501774 -63.107294) (xy 37.48335 -63.114882)
			(xy 37.475922 -63.12154) (xy 36.15055 -64.446912) (xy 44.82211 -64.446912) (xy 44.822567 -64.419659)
			(xy 44.830322 -64.365707) (xy 44.845678 -64.313407) (xy 44.86832 -64.263826) (xy 44.897789 -64.217972)
			(xy 44.933483 -64.176779) (xy 44.974677 -64.141085) (xy 45.020531 -64.111617) (xy 45.070113 -64.088976)
			(xy 45.122412 -64.073621) (xy 45.176365 -64.065866) (xy 45.203618 -64.065404) (xy 45.232533 -64.06598)
			(xy 45.289701 -64.074696) (xy 45.344899 -64.091943) (xy 45.396861 -64.117324) (xy 45.444397 -64.150257)
			(xy 45.486416 -64.189989) (xy 45.504608 -64.21247) (xy 45.512159 -64.221243) (xy 45.532926 -64.231417)
			(xy 45.544486 -64.232028) (xy 45.62475 -64.232028) (xy 45.636318 -64.231454) (xy 45.657091 -64.221264)
			(xy 45.664628 -64.21247) (xy 45.681381 -64.191687) (xy 45.719735 -64.154557) (xy 45.762889 -64.123135)
			(xy 45.810003 -64.098036) (xy 45.860155 -64.07975) (xy 45.912366 -64.068633) (xy 45.965618 -64.064903)
			(xy 46.01887 -64.068633) (xy 46.071081 -64.07975) (xy 46.121233 -64.098036) (xy 46.168347 -64.123135)
			(xy 46.211501 -64.154557) (xy 46.249855 -64.191687) (xy 46.266608 -64.21247) (xy 46.274159 -64.221243)
			(xy 46.294926 -64.231417) (xy 46.306486 -64.232028) (xy 46.38675 -64.232028) (xy 46.398318 -64.231454)
			(xy 46.419091 -64.221264) (xy 46.426628 -64.21247) (xy 46.443381 -64.191687) (xy 46.481735 -64.154557)
			(xy 46.524889 -64.123135) (xy 46.572003 -64.098036) (xy 46.622155 -64.07975) (xy 46.674366 -64.068633)
			(xy 46.727618 -64.064903) (xy 46.78087 -64.068633) (xy 46.833081 -64.07975) (xy 46.883233 -64.098036)
			(xy 46.930347 -64.123135) (xy 46.973501 -64.154557) (xy 47.011855 -64.191687) (xy 47.028608 -64.21247)
			(xy 47.036159 -64.221243) (xy 47.056926 -64.231417) (xy 47.068486 -64.232028) (xy 47.14875 -64.232028)
			(xy 47.160318 -64.231454) (xy 47.181091 -64.221264) (xy 47.188628 -64.21247) (xy 47.206796 -64.189967)
			(xy 47.248821 -64.150234) (xy 47.296361 -64.117298) (xy 47.348327 -64.091914) (xy 47.403528 -64.074661)
			(xy 47.460701 -64.065937) (xy 47.489618 -64.065404) (xy 47.51687 -64.065861) (xy 47.57082 -64.07362)
			(xy 47.623116 -64.088978) (xy 47.672694 -64.111622) (xy 47.718545 -64.141092) (xy 47.759735 -64.176786)
			(xy 47.795426 -64.217979) (xy 47.824892 -64.263833) (xy 47.847532 -64.313413) (xy 47.862886 -64.36571)
			(xy 47.870641 -64.41966) (xy 47.871126 -64.446912) (xy 47.870567 -64.477144) (xy 47.861016 -64.53685)
			(xy 47.84217 -64.594302) (xy 47.814501 -64.648064) (xy 47.778701 -64.696791) (xy 47.757588 -64.718438)
			(xy 47.749714 -64.726058) (xy 47.742094 -64.745616) (xy 47.745396 -64.842136) (xy 47.75454 -64.860932)
			(xy 47.762922 -64.868044) (xy 47.783482 -64.886269) (xy 47.819687 -64.927594) (xy 47.849592 -64.973684)
			(xy 47.872579 -65.023585) (xy 47.888172 -65.076268) (xy 47.896049 -65.130641) (xy 47.896526 -65.158112)
			(xy 47.896033 -65.185363) (xy 47.888276 -65.239309) (xy 47.87292 -65.291603) (xy 47.850279 -65.341179)
			(xy 47.820813 -65.387028) (xy 47.785122 -65.428218) (xy 47.743933 -65.463909) (xy 47.698084 -65.493376)
			(xy 47.648508 -65.516018) (xy 47.596215 -65.531374) (xy 47.542269 -65.539133) (xy 47.515018 -65.53962)
			(xy 47.4861 -65.539119) (xy 47.428927 -65.530391) (xy 47.373726 -65.513131) (xy 47.321764 -65.487737)
			(xy 47.274231 -65.454789) (xy 47.232216 -65.415042) (xy 47.214028 -65.392554) (xy 47.206457 -65.383802)
			(xy 47.185705 -65.373615) (xy 47.17415 -65.372996) (xy 47.093886 -65.372996) (xy 47.082317 -65.37356)
			(xy 47.061547 -65.383759) (xy 47.054008 -65.392554) (xy 47.037255 -65.413337) (xy 46.998901 -65.450467)
			(xy 46.955747 -65.481889) (xy 46.908633 -65.506988) (xy 46.858481 -65.525274) (xy 46.80627 -65.536391)
			(xy 46.753018 -65.540121) (xy 46.699766 -65.536391) (xy 46.647555 -65.525274) (xy 46.597403 -65.506988)
			(xy 46.550289 -65.481889) (xy 46.507135 -65.450467) (xy 46.468781 -65.413337) (xy 46.452028 -65.392554)
			(xy 46.444457 -65.383802) (xy 46.423705 -65.373615) (xy 46.41215 -65.372996) (xy 46.331886 -65.372996)
			(xy 46.320317 -65.37356) (xy 46.299547 -65.383759) (xy 46.292008 -65.392554) (xy 46.275255 -65.413337)
			(xy 46.236901 -65.450467) (xy 46.193747 -65.481889) (xy 46.146633 -65.506988) (xy 46.096481 -65.525274)
			(xy 46.04427 -65.536391) (xy 45.991018 -65.540121) (xy 45.937766 -65.536391) (xy 45.885555 -65.525274)
			(xy 45.835403 -65.506988) (xy 45.788289 -65.481889) (xy 45.745135 -65.450467) (xy 45.706781 -65.413337)
			(xy 45.690028 -65.392554) (xy 45.682457 -65.383802) (xy 45.661705 -65.373615) (xy 45.65015 -65.372996)
			(xy 45.569886 -65.372996) (xy 45.558317 -65.37356) (xy 45.537547 -65.383759) (xy 45.530008 -65.392554)
			(xy 45.511826 -65.415045) (xy 45.469803 -65.454777) (xy 45.422266 -65.487714) (xy 45.370303 -65.5131)
			(xy 45.315104 -65.530356) (xy 45.257934 -65.539085) (xy 45.229018 -65.53962) (xy 45.201766 -65.539128)
			(xy 45.147817 -65.531374) (xy 45.09552 -65.516021) (xy 45.045941 -65.493381) (xy 45.000088 -65.463916)
			(xy 44.958896 -65.428225) (xy 44.923202 -65.387036) (xy 44.893733 -65.341185) (xy 44.87109 -65.291608)
			(xy 44.855733 -65.239312) (xy 44.847974 -65.185364) (xy 44.84751 -65.158112) (xy 44.848074 -65.12788)
			(xy 44.857623 -65.068174) (xy 44.876467 -65.010722) (xy 44.904135 -64.956959) (xy 44.939935 -64.908232)
			(xy 44.961048 -64.886586) (xy 44.968922 -64.878966) (xy 44.976542 -64.859408) (xy 44.97324 -64.762888)
			(xy 44.964096 -64.744092) (xy 44.955714 -64.73698) (xy 44.935173 -64.718734) (xy 44.898964 -64.677415)
			(xy 44.869056 -64.63133) (xy 44.846066 -64.581432) (xy 44.83047 -64.528753) (xy 44.822589 -64.474382)
			(xy 44.82211 -64.446912) (xy 36.15055 -64.446912) (xy 36.12134 -64.476122) (xy 36.114597 -64.483492)
			(xy 36.107006 -64.501954) (xy 36.106608 -64.511936) (xy 36.106608 -66.348864) (xy 36.107094 -66.358826)
			(xy 36.114682 -66.37725) (xy 36.12134 -66.384678) (xy 36.430204 -66.693796) (xy 36.450331 -66.714646)
			(xy 36.484435 -66.761495) (xy 36.510789 -66.813103) (xy 36.528744 -66.868199) (xy 36.537858 -66.925426)
			(xy 36.538408 -66.9544) (xy 36.538408 -67.01536) (xy 36.538845 -67.026174) (xy 36.547664 -67.045917)
			(xy 36.555426 -67.05346) (xy 36.62045 -67.111118) (xy 36.641278 -67.117468) (xy 36.6522 -67.116198)
			(xy 36.663712 -67.114892) (xy 36.686842 -67.113495) (xy 36.698428 -67.113404) (xy 36.726136 -67.113903)
			(xy 36.780969 -67.121927) (xy 36.834063 -67.137802) (xy 36.8843 -67.161194) (xy 36.930624 -67.19161)
			(xy 36.972057 -67.22841) (xy 36.990274 -67.249294) (xy 36.997863 -67.25743) (xy 37.018023 -67.266779)
			(xy 37.029136 -67.267328) (xy 37.107114 -67.267328) (xy 37.118223 -67.266769) (xy 37.138378 -67.257418)
			(xy 37.145976 -67.249294) (xy 37.164186 -67.228403) (xy 37.205614 -67.191592) (xy 37.251936 -67.161169)
			(xy 37.302176 -67.137778) (xy 37.355275 -67.12191) (xy 37.410112 -67.1139) (xy 37.437822 -67.113404)
			(xy 37.465887 -67.113897) (xy 37.521411 -67.122114) (xy 37.57513 -67.138382) (xy 37.625884 -67.16235)
			(xy 37.672576 -67.1935) (xy 37.714197 -67.231158) (xy 37.749848 -67.274511) (xy 37.76472 -67.298316)
			(xy 37.768022 -67.30365) (xy 38.086284 -67.621912) (xy 39.11041 -67.621912) (xy 39.114481 -67.56629)
			(xy 39.126607 -67.511853) (xy 39.14653 -67.459762) (xy 39.173826 -67.411127) (xy 39.207912 -67.366984)
			(xy 39.248061 -67.328275) (xy 39.293419 -67.295824) (xy 39.343019 -67.270323) (xy 39.395803 -67.252316)
			(xy 39.450646 -67.242186) (xy 39.50638 -67.240149) (xy 39.561817 -67.246249) (xy 39.615774 -67.260355)
			(xy 39.667103 -67.282167) (xy 39.714709 -67.311221) (xy 39.757577 -67.346896) (xy 39.794794 -67.388433)
			(xy 39.825567 -67.434946) (xy 39.849239 -67.485443) (xy 39.865307 -67.53885) (xy 39.873427 -67.594026)
			(xy 39.873936 -67.621912) (xy 39.873427 -67.649798) (xy 39.865307 -67.704974) (xy 39.849239 -67.758381)
			(xy 39.825567 -67.808878) (xy 39.794794 -67.855391) (xy 39.757577 -67.896928) (xy 39.714709 -67.932603)
			(xy 39.667103 -67.961657) (xy 39.615774 -67.983469) (xy 39.561817 -67.997575) (xy 39.50638 -68.003675)
			(xy 39.450646 -68.001638) (xy 39.395803 -67.991508) (xy 39.343019 -67.973501) (xy 39.293419 -67.948)
			(xy 39.248061 -67.915549) (xy 39.207912 -67.87684) (xy 39.173826 -67.832697) (xy 39.14653 -67.784062)
			(xy 39.126607 -67.731971) (xy 39.114481 -67.677534) (xy 39.11041 -67.621912) (xy 38.086284 -67.621912)
			(xy 38.745668 -68.281296) (xy 38.753076 -68.287986) (xy 38.771512 -68.29558) (xy 38.781482 -68.296028)
			(xy 40.40378 -68.296028) (xy 40.413742 -68.29554) (xy 40.432165 -68.287952) (xy 40.439594 -68.281296)
			(xy 42.662348 -66.058796) (xy 42.683199 -66.038673) (xy 42.730049 -66.004575) (xy 42.781658 -65.978227)
			(xy 42.836754 -65.96028) (xy 42.89398 -65.951175) (xy 42.922952 -65.950592) (xy 48.2092 -65.950592)
			(xy 48.238175 -65.951147) (xy 48.295406 -65.960249) (xy 48.350507 -65.978195) (xy 48.402121 -66.004545)
			(xy 48.448974 -66.038649) (xy 48.469804 -66.058796) (xy 49.858676 -67.447414) (xy 49.866074 -67.454258)
			(xy 49.884674 -67.461978) (xy 49.894744 -67.4624) (xy 50.245518 -67.4624) (xy 50.255587 -67.461973)
			(xy 50.274186 -67.454254) (xy 50.281586 -67.447414) (xy 50.414936 -67.314064) (xy 50.421611 -67.306651)
			(xy 50.429174 -67.288215) (xy 50.429668 -67.27825) (xy 50.429668 -3.999992) (xy 50.429183 -3.926054)
			(xy 50.42119 -3.778395) (xy 50.405215 -3.631385) (xy 50.381303 -3.485455) (xy 50.349526 -3.341034)
			(xy 50.309976 -3.198546) (xy 50.262769 -3.058408) (xy 50.208045 -2.921031) (xy 50.145962 -2.786819)
			(xy 50.076704 -2.656164) (xy 50.000474 -2.529452) (xy 49.917495 -2.407052) (xy 49.828011 -2.289324)
			(xy 49.732284 -2.176614) (xy 49.630596 -2.069253) (xy 49.523243 -1.967554) (xy 49.410542 -1.871817)
			(xy 49.292823 -1.782322) (xy 49.170431 -1.699332) (xy 49.043725 -1.62309) (xy 48.913077 -1.55382)
			(xy 48.77887 -1.491725) (xy 48.641499 -1.436988) (xy 48.501365 -1.389768) (xy 48.35888 -1.350205)
			(xy 48.214462 -1.318414) (xy 48.068535 -1.294489) (xy 47.921526 -1.2785) (xy 47.773868 -1.270494)
			(xy 47.69993 -1.27) (xy 37.2872 -1.27) (xy 37.27713 -1.270423) (xy 37.258525 -1.278138) (xy 37.251132 -1.284986)
			(xy 36.524946 -2.011172) (xy 36.518106 -2.018572) (xy 36.51039 -2.037171) (xy 36.50996 -2.04724)
			(xy 36.50996 -4.50957) (xy 43.243235 -4.50957) (xy 43.243235 -4.38043) (xy 43.251185 -4.251535) (xy 43.267055 -4.123375)
			(xy 43.290784 -3.996434) (xy 43.322283 -3.871195) (xy 43.361432 -3.748132) (xy 43.408083 -3.627713)
			(xy 43.462058 -3.510394) (xy 43.523153 -3.39662) (xy 43.591136 -3.286823) (xy 43.66575 -3.18142)
			(xy 43.746711 -3.08081) (xy 43.833711 -2.985375) (xy 43.926422 -2.895476) (xy 44.024492 -2.811455)
			(xy 44.127547 -2.733631) (xy 44.235198 -2.662299) (xy 44.347037 -2.597729) (xy 44.462638 -2.540167)
			(xy 44.581563 -2.48983) (xy 44.703362 -2.44691) (xy 44.827572 -2.411569) (xy 44.953721 -2.383942)
			(xy 45.081333 -2.364133) (xy 45.209922 -2.352217) (xy 45.339 -2.348241) (xy 45.468078 -2.352217)
			(xy 45.596667 -2.364133) (xy 45.724279 -2.383942) (xy 45.850428 -2.411569) (xy 45.974638 -2.44691)
			(xy 46.096437 -2.48983) (xy 46.215362 -2.540167) (xy 46.330963 -2.597729) (xy 46.442802 -2.662299)
			(xy 46.550453 -2.733631) (xy 46.653508 -2.811455) (xy 46.751578 -2.895476) (xy 46.844289 -2.985375)
			(xy 46.931289 -3.08081) (xy 47.01225 -3.18142) (xy 47.086864 -3.286823) (xy 47.154847 -3.39662) (xy 47.215942 -3.510394)
			(xy 47.269917 -3.627713) (xy 47.316568 -3.748132) (xy 47.355717 -3.871195) (xy 47.387216 -3.996434)
			(xy 47.410945 -4.123375) (xy 47.426815 -4.251535) (xy 47.434765 -4.38043) (xy 47.435262 -4.445) (xy 47.434765 -4.50957)
			(xy 47.426815 -4.638465) (xy 47.410945 -4.766625) (xy 47.387216 -4.893566) (xy 47.355717 -5.018805)
			(xy 47.316568 -5.141868) (xy 47.269917 -5.262287) (xy 47.215942 -5.379606) (xy 47.154847 -5.49338)
			(xy 47.086864 -5.603177) (xy 47.01225 -5.70858) (xy 46.931289 -5.80919) (xy 46.844289 -5.904625)
			(xy 46.751578 -5.994524) (xy 46.653508 -6.078545) (xy 46.550453 -6.156369) (xy 46.442802 -6.227701)
			(xy 46.330963 -6.292271) (xy 46.215362 -6.349833) (xy 46.096437 -6.40017) (xy 45.974638 -6.44309)
			(xy 45.850428 -6.478431) (xy 45.724279 -6.506058) (xy 45.596667 -6.525867) (xy 45.468078 -6.537783)
			(xy 45.339 -6.54176) (xy 45.209922 -6.537783) (xy 45.081333 -6.525867) (xy 44.953721 -6.506058) (xy 44.827572 -6.478431)
			(xy 44.703362 -6.44309) (xy 44.581563 -6.40017) (xy 44.462638 -6.349833) (xy 44.347037 -6.292271)
			(xy 44.235198 -6.227701) (xy 44.127547 -6.156369) (xy 44.024492 -6.078545) (xy 43.926422 -5.994524)
			(xy 43.833711 -5.904625) (xy 43.746711 -5.80919) (xy 43.66575 -5.70858) (xy 43.591136 -5.603177)
			(xy 43.523153 -5.49338) (xy 43.462058 -5.379606) (xy 43.408083 -5.262287) (xy 43.361432 -5.141868)
			(xy 43.322283 -5.018805) (xy 43.290784 -4.893566) (xy 43.267055 -4.766625) (xy 43.251185 -4.638465)
			(xy 43.243235 -4.50957) (xy 36.50996 -4.50957) (xy 36.50996 -10.999978) (xy 36.50945 -11.071344)
			(xy 36.501205 -11.213836) (xy 36.484746 -11.355615) (xy 36.460127 -11.496207) (xy 36.427431 -11.635143)
			(xy 36.386767 -11.771959) (xy 36.338271 -11.906199) (xy 36.282104 -12.037414) (xy 36.218454 -12.165167)
			(xy 36.147534 -12.289032) (xy 36.069579 -12.408595) (xy 36.068593 -12.409932) (xy 42.1861 -12.409932)
			(xy 42.190144 -12.328902) (xy 42.202236 -12.248678) (xy 42.222255 -12.170056) (xy 42.250004 -12.093818)
			(xy 42.285205 -12.020722) (xy 42.327509 -11.951494) (xy 42.376496 -11.886822) (xy 42.431679 -11.82735)
			(xy 42.492509 -11.773667) (xy 42.558382 -11.726307) (xy 42.628643 -11.685742) (xy 42.702594 -11.652374)
			(xy 42.7795 -11.626535) (xy 42.858597 -11.608482) (xy 42.939098 -11.598394) (xy 43.020203 -11.596371)
			(xy 43.101107 -11.602434) (xy 43.181005 -11.616522) (xy 43.259103 -11.638495) (xy 43.334625 -11.668136)
			(xy 43.406821 -11.705148) (xy 43.474973 -11.749165) (xy 43.538403 -11.79975) (xy 43.596482 -11.856398)
			(xy 43.648632 -11.918548) (xy 43.694334 -11.985581) (xy 43.733135 -12.056831) (xy 43.764649 -12.131591)
			(xy 43.788563 -12.209117) (xy 43.804638 -12.288639) (xy 43.812716 -12.369367) (xy 43.813222 -12.409932)
			(xy 44.186096 -12.409932) (xy 44.19014 -12.328902) (xy 44.202232 -12.248678) (xy 44.222251 -12.170056)
			(xy 44.25 -12.093818) (xy 44.285201 -12.020722) (xy 44.327505 -11.951494) (xy 44.376492 -11.886822)
			(xy 44.431675 -11.82735) (xy 44.492505 -11.773667) (xy 44.558378 -11.726307) (xy 44.628639 -11.685742)
			(xy 44.70259 -11.652374) (xy 44.779496 -11.626535) (xy 44.858593 -11.608482) (xy 44.939094 -11.598394)
			(xy 45.020199 -11.596371) (xy 45.101103 -11.602434) (xy 45.181001 -11.616522) (xy 45.259099 -11.638495)
			(xy 45.334621 -11.668136) (xy 45.406817 -11.705148) (xy 45.474969 -11.749165) (xy 45.538399 -11.79975)
			(xy 45.596478 -11.856398) (xy 45.648628 -11.918548) (xy 45.69433 -11.985581) (xy 45.733131 -12.056831)
			(xy 45.764645 -12.131591) (xy 45.788559 -12.209117) (xy 45.804634 -12.288639) (xy 45.812712 -12.369367)
			(xy 45.813218 -12.409932) (xy 45.812712 -12.450497) (xy 45.804634 -12.531225) (xy 45.788559 -12.610747)
			(xy 45.764645 -12.688273) (xy 45.733131 -12.763033) (xy 45.69433 -12.834283) (xy 45.648628 -12.901316)
			(xy 45.596478 -12.963466) (xy 45.538399 -13.020114) (xy 45.474969 -13.070699) (xy 45.406817 -13.114716)
			(xy 45.334621 -13.151728) (xy 45.259099 -13.181369) (xy 45.181001 -13.203342) (xy 45.101103 -13.21743)
			(xy 45.020199 -13.223493) (xy 44.939094 -13.22147) (xy 44.858593 -13.211382) (xy 44.779496 -13.193329)
			(xy 44.70259 -13.16749) (xy 44.628639 -13.134122) (xy 44.558378 -13.093557) (xy 44.492505 -13.046197)
			(xy 44.431675 -12.992514) (xy 44.376492 -12.933042) (xy 44.327505 -12.86837) (xy 44.285201 -12.799142)
			(xy 44.25 -12.726046) (xy 44.222251 -12.649808) (xy 44.202232 -12.571186) (xy 44.19014 -12.490962)
			(xy 44.186096 -12.409932) (xy 43.813222 -12.409932) (xy 43.812716 -12.450497) (xy 43.804638 -12.531225)
			(xy 43.788563 -12.610747) (xy 43.764649 -12.688273) (xy 43.733135 -12.763033) (xy 43.694334 -12.834283)
			(xy 43.648632 -12.901316) (xy 43.596482 -12.963466) (xy 43.538403 -13.020114) (xy 43.474973 -13.070699)
			(xy 43.406821 -13.114716) (xy 43.334625 -13.151728) (xy 43.259103 -13.181369) (xy 43.181005 -13.203342)
			(xy 43.101107 -13.21743) (xy 43.020203 -13.223493) (xy 42.939098 -13.22147) (xy 42.858597 -13.211382)
			(xy 42.7795 -13.193329) (xy 42.702594 -13.16749) (xy 42.628643 -13.134122) (xy 42.558382 -13.093557)
			(xy 42.492509 -13.046197) (xy 42.431679 -12.992514) (xy 42.376496 -12.933042) (xy 42.327509 -12.86837)
			(xy 42.285205 -12.799142) (xy 42.250004 -12.726046) (xy 42.222255 -12.649808) (xy 42.202236 -12.571186)
			(xy 42.190144 -12.490962) (xy 42.1861 -12.409932) (xy 36.068593 -12.409932) (xy 35.984851 -12.523457)
			(xy 35.893632 -12.633235) (xy 35.796225 -12.737562) (xy 35.692957 -12.836091) (xy 35.584172 -12.928492)
			(xy 35.470233 -13.014457) (xy 35.351521 -13.0937) (xy 35.22843 -13.165956) (xy 35.101373 -13.230984)
			(xy 34.970772 -13.288566) (xy 34.837065 -13.338511) (xy 34.700697 -13.380652) (xy 34.562123 -13.414849)
			(xy 34.421805 -13.440986) (xy 34.280212 -13.458978) (xy 34.137817 -13.468763) (xy 33.995094 -13.47031)
			(xy 33.85252 -13.463613) (xy 33.781492 -13.456666) (xy 33.781492 -13.2588) (xy 33.781072 -13.248779)
			(xy 33.773402 -13.230264) (xy 33.75923 -13.216093) (xy 33.740713 -13.208426) (xy 33.730692 -13.208)
			(xy 30.079442 -13.208) (xy 30.069568 -13.208467) (xy 30.05128 -13.215921) (xy 30.043882 -13.222478)
			(xy 29.98597 -13.278866) (xy 29.978096 -13.2969) (xy 29.977842 -13.30706) (xy 29.976221 -13.34999)
			(xy 29.965741 -13.435264) (xy 29.947088 -13.519129) (xy 29.920435 -13.600805) (xy 29.88603 -13.679531)
			(xy 29.844194 -13.754572) (xy 29.795317 -13.82523) (xy 29.739855 -13.890845) (xy 29.678325 -13.950806)
			(xy 29.611299 -14.004555) (xy 29.539403 -14.051591) (xy 29.463306 -14.091474) (xy 29.383718 -14.123834)
			(xy 29.301381 -14.148369) (xy 29.217061 -14.16485) (xy 29.131546 -14.173124) (xy 29.088588 -14.173708)
			(xy 29.042192 -14.173123) (xy 28.949902 -14.163488) (xy 28.859118 -14.144294) (xy 28.770826 -14.115749)
			(xy 28.728162 -14.097508) (xy 28.718222 -14.093688) (xy 28.696954 -14.093688) (xy 28.687014 -14.097508)
			(xy 28.644349 -14.115745) (xy 28.556055 -14.144282) (xy 28.465272 -14.163477) (xy 28.372983 -14.173121)
			(xy 28.326588 -14.173708) (xy 28.283629 -14.17319) (xy 28.198112 -14.164906) (xy 28.113791 -14.148415)
			(xy 28.031453 -14.123872) (xy 27.951865 -14.091504) (xy 27.875769 -14.051615) (xy 27.803872 -14.004574)
			(xy 27.736846 -13.950822) (xy 27.675314 -13.890857) (xy 27.61985 -13.82524) (xy 27.570971 -13.754581)
			(xy 27.529131 -13.679539) (xy 27.494722 -13.600812) (xy 27.468063 -13.519135) (xy 27.449402 -13.435268)
			(xy 27.438914 -13.349992) (xy 27.437334 -13.30706) (xy 27.43708 -13.2969) (xy 27.429206 -13.278866)
			(xy 27.371294 -13.222478) (xy 27.363917 -13.215885) (xy 27.345617 -13.208413) (xy 27.335734 -13.208)
			(xy 17.958308 -13.208) (xy 17.948286 -13.208418) (xy 17.929766 -13.216087) (xy 17.915591 -13.230259)
			(xy 17.90792 -13.248778) (xy 17.907508 -13.2588) (xy 17.907508 -13.419328) (xy 17.907015 -13.429332)
			(xy 17.899351 -13.447816) (xy 17.885199 -13.461962) (xy 17.866713 -13.469619) (xy 17.856708 -13.470128)
			(xy 17.652492 -13.470128) (xy 17.652238 -13.469874) (xy 17.583086 -13.469186) (xy 17.445019 -13.461034)
			(xy 17.307625 -13.445168) (xy 17.171334 -13.421638) (xy 17.036574 -13.390517) (xy 16.903766 -13.351903)
			(xy 16.773328 -13.305917) (xy 16.645667 -13.252704) (xy 16.521185 -13.192429) (xy 16.400271 -13.125282)
			(xy 16.283304 -13.051473) (xy 16.170652 -12.971235) (xy 16.062666 -12.884817) (xy 15.959686 -12.792491)
			(xy 15.862034 -12.694547) (xy 15.770017 -12.591292) (xy 15.683923 -12.483048) (xy 15.604021 -12.370156)
			(xy 15.530563 -12.25297) (xy 15.463778 -12.131855) (xy 15.403875 -12.007193) (xy 15.351043 -11.879375)
			(xy 15.305448 -11.748799) (xy 15.267231 -11.615877) (xy 15.236513 -11.481024) (xy 15.213391 -11.344663)
			(xy 15.197936 -11.207222) (xy 15.190197 -11.069132) (xy 15.189708 -10.999978) (xy 15.189708 -2.04724)
			(xy 15.189269 -2.037208) (xy 15.181694 -2.018634) (xy 15.174976 -2.011172) (xy 14.44879 -1.284986)
			(xy 14.441395 -1.278132) (xy 14.422796 -1.270387) (xy 14.412722 -1.27) (xy 3.999992 -1.27) (xy 3.926052 -1.270492)
			(xy 3.778388 -1.278498) (xy 3.631374 -1.294486) (xy 3.485442 -1.318411) (xy 3.341018 -1.350201) (xy 3.198528 -1.389763)
			(xy 3.058388 -1.436981) (xy 2.921011 -1.491717) (xy 2.786798 -1.553811) (xy 2.656144 -1.623079) (xy 2.529431 -1.69932)
			(xy 2.407032 -1.782308) (xy 2.289305 -1.871802) (xy 2.176596 -1.967538) (xy 2.069235 -2.069235) (xy 1.967538 -2.176596)
			(xy 1.871802 -2.289305) (xy 1.782308 -2.407032) (xy 1.69932 -2.529431) (xy 1.623079 -2.656144) (xy 1.553811 -2.786798)
			(xy 1.491717 -2.921011) (xy 1.436981 -3.058388) (xy 1.389763 -3.198528) (xy 1.350201 -3.341018) (xy 1.318411 -3.485442)
			(xy 1.294486 -3.631374) (xy 1.278498 -3.778388) (xy 1.270492 -3.926052) (xy 1.27 -3.999992) (xy 1.27 -4.50957)
			(xy 9.080235 -4.50957) (xy 9.080235 -4.38043) (xy 9.088185 -4.251535) (xy 9.104055 -4.123375) (xy 9.127784 -3.996434)
			(xy 9.159283 -3.871195) (xy 9.198432 -3.748132) (xy 9.245083 -3.627713) (xy 9.299058 -3.510394) (xy 9.360153 -3.39662)
			(xy 9.428136 -3.286823) (xy 9.50275 -3.18142) (xy 9.583711 -3.08081) (xy 9.670711 -2.985375) (xy 9.763422 -2.895476)
			(xy 9.861492 -2.811455) (xy 9.964547 -2.733631) (xy 10.072198 -2.662299) (xy 10.184037 -2.597729)
			(xy 10.299638 -2.540167) (xy 10.418563 -2.48983) (xy 10.540362 -2.44691) (xy 10.664572 -2.411569)
			(xy 10.790721 -2.383942) (xy 10.918333 -2.364133) (xy 11.046922 -2.352217) (xy 11.176 -2.348241)
			(xy 11.305078 -2.352217) (xy 11.433667 -2.364133) (xy 11.561279 -2.383942) (xy 11.687428 -2.411569)
			(xy 11.811638 -2.44691) (xy 11.933437 -2.48983) (xy 12.052362 -2.540167) (xy 12.167963 -2.597729)
			(xy 12.279802 -2.662299) (xy 12.387453 -2.733631) (xy 12.490508 -2.811455) (xy 12.588578 -2.895476)
			(xy 12.681289 -2.985375) (xy 12.768289 -3.08081) (xy 12.84925 -3.18142) (xy 12.923864 -3.286823)
			(xy 12.991847 -3.39662) (xy 13.052942 -3.510394) (xy 13.106917 -3.627713) (xy 13.153568 -3.748132)
			(xy 13.192717 -3.871195) (xy 13.224216 -3.996434) (xy 13.247945 -4.123375) (xy 13.263815 -4.251535)
			(xy 13.271765 -4.38043) (xy 13.272262 -4.445) (xy 13.271765 -4.50957) (xy 13.263815 -4.638465) (xy 13.247945 -4.766625)
			(xy 13.224216 -4.893566) (xy 13.192717 -5.018805) (xy 13.153568 -5.141868) (xy 13.106917 -5.262287)
			(xy 13.052942 -5.379606) (xy 12.991847 -5.49338) (xy 12.923864 -5.603177) (xy 12.84925 -5.70858)
			(xy 12.768289 -5.80919) (xy 12.681289 -5.904625) (xy 12.588578 -5.994524) (xy 12.490508 -6.078545)
			(xy 12.387453 -6.156369) (xy 12.279802 -6.227701) (xy 12.167963 -6.292271) (xy 12.052362 -6.349833)
			(xy 11.933437 -6.40017) (xy 11.811638 -6.44309) (xy 11.687428 -6.478431) (xy 11.561279 -6.506058)
			(xy 11.433667 -6.525867) (xy 11.305078 -6.537783) (xy 11.176 -6.54176) (xy 11.046922 -6.537783) (xy 10.918333 -6.525867)
			(xy 10.790721 -6.506058) (xy 10.664572 -6.478431) (xy 10.540362 -6.44309) (xy 10.418563 -6.40017)
			(xy 10.299638 -6.349833) (xy 10.184037 -6.292271) (xy 10.072198 -6.227701) (xy 9.964547 -6.156369)
			(xy 9.861492 -6.078545) (xy 9.763422 -5.994524) (xy 9.670711 -5.904625) (xy 9.583711 -5.80919) (xy 9.50275 -5.70858)
			(xy 9.428136 -5.603177) (xy 9.360153 -5.49338) (xy 9.299058 -5.379606) (xy 9.245083 -5.262287) (xy 9.198432 -5.141868)
			(xy 9.159283 -5.018805) (xy 9.127784 -4.893566) (xy 9.104055 -4.766625) (xy 9.088185 -4.638465) (xy 9.080235 -4.50957)
			(xy 1.27 -4.50957) (xy 1.27 -10.340594) (xy 1.270427 -10.349652) (xy 1.276819 -10.366611) (xy 1.288675 -10.380317)
			(xy 1.296416 -10.385044) (xy 1.387094 -10.434828) (xy 1.414526 -10.433812) (xy 1.426464 -10.426192)
			(xy 1.46223 -10.403951) (xy 1.537197 -10.365552) (xy 1.615458 -10.334412) (xy 1.696311 -10.310808)
			(xy 1.779034 -10.294952) (xy 1.862886 -10.286986) (xy 1.905 -10.286492) (xy 1.947348 -10.286996)
			(xy 2.031662 -10.295047) (xy 2.114828 -10.311076) (xy 2.196095 -10.334937) (xy 2.274725 -10.366416)
			(xy 2.350006 -10.405227) (xy 2.421258 -10.451017) (xy 2.487834 -10.503373) (xy 2.549132 -10.561821)
			(xy 2.604597 -10.625831) (xy 2.653726 -10.694823) (xy 2.696075 -10.768173) (xy 2.731259 -10.845216)
			(xy 2.758961 -10.925255) (xy 2.778929 -11.007564) (xy 2.790982 -11.091399) (xy 2.795013 -11.176)
			(xy 2.790982 -11.260601) (xy 2.778929 -11.344436) (xy 2.758961 -11.426745) (xy 2.731259 -11.506784)
			(xy 2.696075 -11.583827) (xy 2.653726 -11.657177) (xy 2.604597 -11.726169) (xy 2.549132 -11.790179)
			(xy 2.487834 -11.848627) (xy 2.421258 -11.900983) (xy 2.350006 -11.946773) (xy 2.274725 -11.985584)
			(xy 2.196095 -12.017063) (xy 2.114828 -12.040924) (xy 2.031662 -12.056953) (xy 1.947348 -12.065004)
			(xy 1.905 -12.065508) (xy 1.862886 -12.065015) (xy 1.779034 -12.057052) (xy 1.696311 -12.041197)
			(xy 1.615457 -12.017592) (xy 1.537197 -11.986449) (xy 1.462232 -11.948046) (xy 1.426464 -11.925808)
			(xy 1.414526 -11.918188) (xy 1.387094 -11.917172) (xy 1.296416 -11.966956) (xy 1.288623 -11.971619)
			(xy 1.276728 -11.985324) (xy 1.270397 -12.002331) (xy 1.27 -12.011406) (xy 1.27 -12.44986) (xy 5.887178 -12.44986)
			(xy 5.887178 -12.369996) (xy 5.895007 -12.290517) (xy 5.910587 -12.212188) (xy 5.933771 -12.135763)
			(xy 5.964334 -12.061979) (xy 6.001981 -11.991545) (xy 6.046351 -11.925141) (xy 6.097016 -11.863406)
			(xy 6.153489 -11.806934) (xy 6.215224 -11.756269) (xy 6.281629 -11.711899) (xy 6.352062 -11.674252)
			(xy 6.425847 -11.643689) (xy 6.502272 -11.620506) (xy 6.580601 -11.604926) (xy 6.66008 -11.597098)
			(xy 6.700012 -11.596624) (xy 6.714566 -11.596679) (xy 6.743656 -11.597695) (xy 6.758178 -11.598656)
			(xy 6.774434 -11.599926) (xy 6.801866 -11.583416) (xy 6.853428 -11.466068) (xy 6.847078 -11.434826)
			(xy 6.835394 -11.42365) (xy 6.799432 -11.388935) (xy 6.732509 -11.314679) (xy 6.671691 -11.235344)
			(xy 6.617362 -11.151433) (xy 6.569865 -11.063474) (xy 6.5295 -10.972023) (xy 6.496521 -10.877656)
			(xy 6.471137 -10.780969) (xy 6.453507 -10.682573) (xy 6.443743 -10.583087) (xy 6.441906 -10.48314)
			(xy 6.448009 -10.383363) (xy 6.462012 -10.284385) (xy 6.483827 -10.186831) (xy 6.513317 -10.091317)
			(xy 6.550295 -9.998444) (xy 6.594528 -9.908799) (xy 6.645737 -9.822949) (xy 6.703599 -9.741434) (xy 6.767749 -9.664769)
			(xy 6.837781 -9.593438) (xy 6.913255 -9.52789) (xy 6.993693 -9.46854) (xy 7.078588 -9.415762) (xy 7.167405 -9.36989)
			(xy 7.259583 -9.331211) (xy 7.354539 -9.299972) (xy 7.451676 -9.276368) (xy 7.55038 -9.260549) (xy 7.650028 -9.252614)
			(xy 7.749992 -9.252614) (xy 7.84964 -9.260549) (xy 7.948344 -9.276368) (xy 8.045481 -9.299972) (xy 8.140437 -9.331211)
			(xy 8.232615 -9.36989) (xy 8.321432 -9.415762) (xy 8.406327 -9.46854) (xy 8.486765 -9.52789) (xy 8.562239 -9.593438)
			(xy 8.632271 -9.664769) (xy 8.696421 -9.741434) (xy 8.754283 -9.822949) (xy 8.805492 -9.908799) (xy 8.849725 -9.998444)
			(xy 8.886703 -10.091317) (xy 8.916193 -10.186831) (xy 8.938008 -10.284385) (xy 8.952011 -10.383363)
			(xy 8.958114 -10.48314) (xy 8.956277 -10.583087) (xy 8.946513 -10.682573) (xy 8.928883 -10.780969)
			(xy 8.903499 -10.877656) (xy 8.87052 -10.972023) (xy 8.830155 -11.063474) (xy 8.782658 -11.151433)
			(xy 8.728329 -11.235344) (xy 8.667511 -11.314679) (xy 8.600588 -11.388935) (xy 8.564626 -11.42365)
			(xy 8.552942 -11.434826) (xy 8.546592 -11.466068) (xy 8.598154 -11.583416) (xy 8.625586 -11.599926)
			(xy 8.641842 -11.598656) (xy 8.656364 -11.59769) (xy 8.685454 -11.596675) (xy 8.700008 -11.596624)
			(xy 8.739938 -11.59709) (xy 8.819415 -11.604919) (xy 8.897741 -11.620499) (xy 8.974163 -11.643682)
			(xy 9.047944 -11.674244) (xy 9.118375 -11.71189) (xy 9.184777 -11.756259) (xy 9.24651 -11.806922)
			(xy 9.30298 -11.863392) (xy 9.353643 -11.925126) (xy 9.398011 -11.991527) (xy 9.435657 -12.061958)
			(xy 9.466219 -12.13574) (xy 9.489401 -12.212162) (xy 9.504982 -12.290488) (xy 9.51281 -12.369964)
			(xy 9.512811 -12.449825) (xy 9.504983 -12.529301) (xy 9.489404 -12.607628) (xy 9.466222 -12.68405)
			(xy 9.435662 -12.757832) (xy 9.398016 -12.828263) (xy 9.353649 -12.894666) (xy 9.302987 -12.9564)
			(xy 9.246518 -13.012871) (xy 9.184785 -13.063535) (xy 9.118384 -13.107904) (xy 9.047954 -13.145552)
			(xy 8.974173 -13.176114) (xy 8.897751 -13.199298) (xy 8.819425 -13.21488) (xy 8.739949 -13.222709)
			(xy 8.660088 -13.222711) (xy 8.580612 -13.214885) (xy 8.502285 -13.199307) (xy 8.425863 -13.176127)
			(xy 8.35208 -13.145567) (xy 8.281648 -13.107923) (xy 8.215245 -13.063557) (xy 8.15351 -13.012896)
			(xy 8.097038 -12.956427) (xy 8.046373 -12.894696) (xy 8.002003 -12.828295) (xy 7.964354 -12.757866)
			(xy 7.93379 -12.684085) (xy 7.910605 -12.607664) (xy 7.895022 -12.529338) (xy 7.887191 -12.449862)
			(xy 7.8867 -12.409932) (xy 7.887152 -12.370802) (xy 7.894667 -12.292904) (xy 7.909631 -12.216088)
			(xy 7.931906 -12.141064) (xy 7.961285 -12.068528) (xy 7.997496 -11.99915) (xy 8.040205 -11.933571)
			(xy 8.064246 -11.902694) (xy 8.074406 -11.889994) (xy 8.076438 -11.85799) (xy 8.008874 -11.749024)
			(xy 7.97941 -11.736578) (xy 7.963662 -11.73988) (xy 7.911593 -11.750474) (xy 7.80618 -11.763903)
			(xy 7.70001 -11.76839) (xy 7.59384 -11.763903) (xy 7.488427 -11.750474) (xy 7.436358 -11.73988) (xy 7.42061 -11.736578)
			(xy 7.391146 -11.749024) (xy 7.323582 -11.85799) (xy 7.325614 -11.889994) (xy 7.335774 -11.902694)
			(xy 7.359814 -11.933571) (xy 7.402517 -11.999153) (xy 7.438724 -12.068532) (xy 7.468099 -12.141068)
			(xy 7.490372 -12.216091) (xy 7.505337 -12.292906) (xy 7.512854 -12.370803) (xy 7.51332 -12.409932)
			(xy 7.512842 -12.449864) (xy 7.505013 -12.529343) (xy 7.489433 -12.607672) (xy 7.466249 -12.684097)
			(xy 7.435686 -12.757881) (xy 7.398039 -12.828315) (xy 7.353669 -12.894719) (xy 7.303004 -12.956454)
			(xy 7.246531 -13.012926) (xy 7.184796 -13.063591) (xy 7.118391 -13.107961) (xy 7.047958 -13.145608)
			(xy 6.974173 -13.176171) (xy 6.897748 -13.199354) (xy 6.819419 -13.214934) (xy 6.73994 -13.222762)
			(xy 6.660076 -13.222762) (xy 6.580597 -13.214933) (xy 6.502268 -13.199353) (xy 6.425843 -13.176169)
			(xy 6.352059 -13.145606) (xy 6.281625 -13.107959) (xy 6.215221 -13.063589) (xy 6.153486 -13.012924)
			(xy 6.097014 -12.956451) (xy 6.046349 -12.894716) (xy 6.001979 -12.828311) (xy 5.964332 -12.757878)
			(xy 5.933769 -12.684093) (xy 5.910586 -12.607668) (xy 5.895006 -12.529339) (xy 5.887178 -12.44986)
			(xy 1.27 -12.44986) (xy 1.27 -16.409924) (xy 5.378133 -16.409924) (xy 5.382265 -16.305491) (xy 5.394637 -16.20171)
			(xy 5.415171 -16.099232) (xy 5.443738 -15.998697) (xy 5.48016 -15.900734) (xy 5.524209 -15.805955)
			(xy 5.57561 -15.714953) (xy 5.634041 -15.628297) (xy 5.699137 -15.546529) (xy 5.77049 -15.470161)
			(xy 5.847655 -15.39967) (xy 5.930148 -15.335496) (xy 6.017455 -15.278042) (xy 6.109028 -15.227667)
			(xy 6.156452 -15.20571) (xy 6.16839 -15.200122) (xy 6.184138 -15.179294) (xy 6.199124 -15.067788)
			(xy 6.189726 -15.043404) (xy 6.179566 -15.035022) (xy 6.149432 -15.009305) (xy 6.093774 -14.952922)
			(xy 6.043861 -14.891396) (xy 6.000166 -14.825308) (xy 5.963102 -14.755286) (xy 5.933021 -14.681992)
			(xy 5.910208 -14.606122) (xy 5.894878 -14.528392) (xy 5.887177 -14.449541) (xy 5.886704 -14.409928)
			(xy 5.887194 -14.369997) (xy 5.895022 -14.290519) (xy 5.910602 -14.212191) (xy 5.933785 -14.135768)
			(xy 5.964347 -14.061984) (xy 6.001994 -13.991552) (xy 6.046363 -13.925149) (xy 6.097027 -13.863414)
			(xy 6.153498 -13.806943) (xy 6.215233 -13.756279) (xy 6.281636 -13.71191) (xy 6.352068 -13.674263)
			(xy 6.425852 -13.643701) (xy 6.502275 -13.620518) (xy 6.580603 -13.604938) (xy 6.660081 -13.59711)
			(xy 6.739943 -13.59711) (xy 6.819421 -13.604938) (xy 6.897749 -13.620518) (xy 6.974172 -13.643701)
			(xy 7.047956 -13.674263) (xy 7.118388 -13.71191) (xy 7.184791 -13.756279) (xy 7.246526 -13.806943)
			(xy 7.302997 -13.863414) (xy 7.353661 -13.925149) (xy 7.39803 -13.991552) (xy 7.435677 -14.061984)
			(xy 7.466239 -14.135768) (xy 7.489422 -14.212191) (xy 7.505002 -14.290519) (xy 7.51283 -14.369997)
			(xy 7.51332 -14.409928) (xy 7.512838 -14.449541) (xy 7.505135 -14.528391) (xy 7.489803 -14.606118)
			(xy 7.466989 -14.681988) (xy 7.436909 -14.755281) (xy 7.399847 -14.825303) (xy 7.356154 -14.89139)
			(xy 7.306244 -14.952918) (xy 7.25059 -15.009304) (xy 7.220458 -15.035022) (xy 7.210298 -15.043404)
			(xy 7.2009 -15.067788) (xy 7.215886 -15.179294) (xy 7.231634 -15.200122) (xy 7.243572 -15.20571)
			(xy 7.291724 -15.228007) (xy 7.384633 -15.279287) (xy 7.473129 -15.337855) (xy 7.556641 -15.403335)
			(xy 7.634631 -15.475302) (xy 7.706596 -15.553295) (xy 7.772073 -15.63681) (xy 7.830638 -15.725308)
			(xy 7.881915 -15.818219) (xy 7.904226 -15.866364) (xy 7.909814 -15.878302) (xy 7.930642 -15.89405)
			(xy 8.042148 -15.909036) (xy 8.066532 -15.899638) (xy 8.074914 -15.889478) (xy 8.100641 -15.859352)
			(xy 8.157022 -15.803693) (xy 8.218547 -15.753779) (xy 8.284633 -15.710083) (xy 8.354653 -15.673018)
			(xy 8.427946 -15.642936) (xy 8.503816 -15.620121) (xy 8.581544 -15.604791) (xy 8.660395 -15.59709)
			(xy 8.700008 -15.596616) (xy 8.73994 -15.597082) (xy 8.81942 -15.60491) (xy 8.89775 -15.620491) (xy 8.974176 -15.643674)
			(xy 9.047961 -15.674237) (xy 9.118395 -15.711884) (xy 9.1848 -15.756255) (xy 9.246536 -15.80692)
			(xy 9.303009 -15.863393) (xy 9.353674 -15.925129) (xy 9.398045 -15.991533) (xy 9.435693 -16.061967)
			(xy 9.466255 -16.135753) (xy 9.489439 -16.212178) (xy 9.50502 -16.290508) (xy 9.512848 -16.369988)
			(xy 9.512848 -16.449852) (xy 9.50502 -16.529332) (xy 9.489439 -16.607662) (xy 9.466255 -16.684087)
			(xy 9.435693 -16.757873) (xy 9.398045 -16.828307) (xy 9.353674 -16.894711) (xy 9.303009 -16.956447)
			(xy 9.246536 -17.01292) (xy 9.1848 -17.063585) (xy 9.118395 -17.107956) (xy 9.047961 -17.145603)
			(xy 8.974176 -17.176166) (xy 8.89775 -17.199349) (xy 8.81942 -17.21493) (xy 8.73994 -17.222758) (xy 8.700008 -17.223232)
			(xy 8.660396 -17.22272) (xy 8.581547 -17.21502) (xy 8.50382 -17.199692) (xy 8.427951 -17.176882)
			(xy 8.354659 -17.146805) (xy 8.284637 -17.109747) (xy 8.218548 -17.066058) (xy 8.15702 -17.016151)
			(xy 8.100633 -16.960501) (xy 8.074914 -16.93037) (xy 8.066532 -16.92021) (xy 8.042148 -16.910812)
			(xy 7.930642 -16.925798) (xy 7.909814 -16.941546) (xy 7.904226 -16.953484) (xy 7.881919 -17.00163)
			(xy 7.830639 -17.09454) (xy 7.772072 -17.183036) (xy 7.706594 -17.266548) (xy 7.634627 -17.344538)
			(xy 7.556636 -17.416504) (xy 7.473123 -17.481981) (xy 7.384626 -17.540547) (xy 7.291716 -17.591826)
			(xy 7.243572 -17.614138) (xy 7.231634 -17.619726) (xy 7.215886 -17.640554) (xy 7.2009 -17.75206)
			(xy 7.210298 -17.776444) (xy 7.220458 -17.784826) (xy 7.250597 -17.810537) (xy 7.306254 -17.866921)
			(xy 7.356167 -17.928449) (xy 7.399862 -17.994537) (xy 7.436925 -18.06456) (xy 7.467005 -18.137854)
			(xy 7.489818 -18.213725) (xy 7.505147 -18.291455) (xy 7.512847 -18.370307) (xy 7.51332 -18.40992)
			(xy 7.51283 -18.449851) (xy 7.505002 -18.529329) (xy 7.489422 -18.607657) (xy 7.466239 -18.68408)
			(xy 7.435677 -18.757864) (xy 7.39803 -18.828296) (xy 7.353661 -18.894699) (xy 7.302997 -18.956434)
			(xy 7.246526 -19.012905) (xy 7.184791 -19.063569) (xy 7.118388 -19.107938) (xy 7.047956 -19.145585)
			(xy 6.974172 -19.176147) (xy 6.897749 -19.19933) (xy 6.819421 -19.21491) (xy 6.739943 -19.222738)
			(xy 6.660081 -19.222738) (xy 6.580603 -19.21491) (xy 6.502275 -19.19933) (xy 6.425852 -19.176147)
			(xy 6.352068 -19.145585) (xy 6.281636 -19.107938) (xy 6.215233 -19.063569) (xy 6.153498 -19.012905)
			(xy 6.097027 -18.956434) (xy 6.046363 -18.894699) (xy 6.001994 -18.828296) (xy 5.964347 -18.757864)
			(xy 5.933785 -18.68408) (xy 5.910602 -18.607657) (xy 5.895022 -18.529329) (xy 5.887194 -18.449851)
			(xy 5.886704 -18.40992) (xy 5.887212 -18.370308) (xy 5.894911 -18.291459) (xy 5.910238 -18.213731)
			(xy 5.933048 -18.137862) (xy 5.963126 -18.064569) (xy 6.000185 -17.994547) (xy 6.043875 -17.928458)
			(xy 6.093783 -17.86693) (xy 6.149435 -17.810545) (xy 6.179566 -17.784826) (xy 6.189726 -17.776444)
			(xy 6.199124 -17.75206) (xy 6.184138 -17.640554) (xy 6.16839 -17.619726) (xy 6.156452 -17.614138)
			(xy 6.109028 -17.592181) (xy 6.017455 -17.541806) (xy 5.930148 -17.484352) (xy 5.847655 -17.420178)
			(xy 5.77049 -17.349687) (xy 5.699137 -17.273319) (xy 5.634041 -17.191551) (xy 5.57561 -17.104895)
			(xy 5.524209 -17.013893) (xy 5.48016 -16.919114) (xy 5.443738 -16.821151) (xy 5.415171 -16.720616)
			(xy 5.394637 -16.618138) (xy 5.382265 -16.514357) (xy 5.378133 -16.409924) (xy 1.27 -16.409924) (xy 1.27 -22.409911)
			(xy 5.378136 -22.409911) (xy 5.382268 -22.305478) (xy 5.39464 -22.201698) (xy 5.415173 -22.09922)
			(xy 5.443741 -21.998685) (xy 5.480163 -21.900721) (xy 5.524212 -21.805943) (xy 5.575612 -21.714941)
			(xy 5.634043 -21.628285) (xy 5.699138 -21.546517) (xy 5.770491 -21.470149) (xy 5.847656 -21.399658)
			(xy 5.930149 -21.335485) (xy 6.017455 -21.278031) (xy 6.109028 -21.227655) (xy 6.156452 -21.205698)
			(xy 6.16839 -21.20011) (xy 6.184138 -21.179282) (xy 6.199124 -21.067776) (xy 6.189726 -21.043392)
			(xy 6.179566 -21.03501) (xy 6.149431 -21.009294) (xy 6.093773 -20.952911) (xy 6.04386 -20.891384)
			(xy 6.000165 -20.825297) (xy 5.963101 -20.755275) (xy 5.933021 -20.681981) (xy 5.910207 -20.60611)
			(xy 5.894878 -20.528381) (xy 5.887177 -20.449529) (xy 5.886704 -20.409916) (xy 5.887182 -20.369984)
			(xy 5.895008 -20.290504) (xy 5.910588 -20.212174) (xy 5.93377 -20.135749) (xy 5.964332 -20.061964)
			(xy 6.001979 -19.99153) (xy 6.046349 -19.925125) (xy 6.097014 -19.863389) (xy 6.153486 -19.806916)
			(xy 6.215222 -19.756251) (xy 6.281626 -19.711881) (xy 6.35206 -19.674234) (xy 6.425845 -19.643671)
			(xy 6.502271 -19.620489) (xy 6.5806 -19.604909) (xy 6.66008 -19.597082) (xy 6.700012 -19.596608)
			(xy 6.739625 -19.597091) (xy 6.818475 -19.604794) (xy 6.896203 -19.620124) (xy 6.972073 -19.642937)
			(xy 7.045366 -19.673017) (xy 7.115388 -19.71008) (xy 7.181476 -19.753773) (xy 7.243003 -19.803683)
			(xy 7.299388 -19.859337) (xy 7.325106 -19.88947) (xy 7.333488 -19.89963) (xy 7.357872 -19.909028)
			(xy 7.469378 -19.894042) (xy 7.490206 -19.878294) (xy 7.495794 -19.866356) (xy 7.51811 -19.818213)
			(xy 7.569387 -19.725303) (xy 7.627953 -19.636807) (xy 7.69343 -19.553294) (xy 7.765395 -19.475303)
			(xy 7.843386 -19.403337) (xy 7.926898 -19.337859) (xy 8.015394 -19.279292) (xy 8.108304 -19.228014)
			(xy 8.156448 -19.205702) (xy 8.168386 -19.200114) (xy 8.184134 -19.179286) (xy 8.19912 -19.06778)
			(xy 8.189722 -19.043396) (xy 8.179562 -19.035014) (xy 8.149428 -19.009297) (xy 8.09377 -18.952914)
			(xy 8.043857 -18.891387) (xy 8.000162 -18.8253) (xy 7.963099 -18.755278) (xy 7.933018 -18.681984)
			(xy 7.910204 -18.606114) (xy 7.894874 -18.528384) (xy 7.887173 -18.449533) (xy 7.8867 -18.40992)
			(xy 7.88719 -18.369989) (xy 7.895018 -18.290511) (xy 7.910598 -18.212183) (xy 7.933781 -18.13576)
			(xy 7.964343 -18.061976) (xy 8.00199 -17.991544) (xy 8.046359 -17.925141) (xy 8.097023 -17.863406)
			(xy 8.153494 -17.806935) (xy 8.215229 -17.756271) (xy 8.281632 -17.711902) (xy 8.352064 -17.674255)
			(xy 8.425848 -17.643693) (xy 8.502271 -17.62051) (xy 8.580599 -17.60493) (xy 8.660077 -17.597102)
			(xy 8.739939 -17.597102) (xy 8.819417 -17.60493) (xy 8.897745 -17.62051) (xy 8.974168 -17.643693)
			(xy 9.047952 -17.674255) (xy 9.118384 -17.711902) (xy 9.184787 -17.756271) (xy 9.246522 -17.806935)
			(xy 9.302993 -17.863406) (xy 9.353657 -17.925141) (xy 9.398026 -17.991544) (xy 9.435673 -18.061976)
			(xy 9.466235 -18.13576) (xy 9.489418 -18.212183) (xy 9.504998 -18.290511) (xy 9.512826 -18.369989)
			(xy 9.513316 -18.40992) (xy 9.51283 -18.449533) (xy 9.505127 -18.528382) (xy 9.489796 -18.60611)
			(xy 9.466983 -18.68198) (xy 9.436903 -18.755273) (xy 9.399841 -18.825294) (xy 9.356149 -18.891382)
			(xy 9.30624 -18.95291) (xy 9.250586 -19.009296) (xy 9.220454 -19.035014) (xy 9.210294 -19.043396)
			(xy 9.200896 -19.06778) (xy 9.215882 -19.179286) (xy 9.23163 -19.200114) (xy 9.243568 -19.205702)
			(xy 9.290989 -19.227665) (xy 9.382562 -19.278041) (xy 9.469868 -19.335495) (xy 9.552361 -19.399668)
			(xy 9.629526 -19.470159) (xy 9.700879 -19.546527) (xy 9.765974 -19.628294) (xy 9.824405 -19.71495)
			(xy 9.875806 -19.805951) (xy 9.919855 -19.90073) (xy 9.956277 -19.998693) (xy 9.984844 -20.099228)
			(xy 10.005378 -20.201705) (xy 10.01775 -20.305485) (xy 10.021883 -20.409918) (xy 10.01775 -20.514351)
			(xy 10.005378 -20.618131) (xy 9.984845 -20.720609) (xy 9.956278 -20.821144) (xy 9.919856 -20.919107)
			(xy 9.875807 -21.013886) (xy 9.824407 -21.104888) (xy 9.765976 -21.191543) (xy 9.700881 -21.273311)
			(xy 9.629528 -21.349679) (xy 9.552364 -21.42017) (xy 9.469871 -21.484343) (xy 9.382565 -21.541797)
			(xy 9.290991 -21.592173) (xy 9.243568 -21.61413) (xy 9.23163 -21.619718) (xy 9.215882 -21.640546)
			(xy 9.200896 -21.752052) (xy 9.210294 -21.776436) (xy 9.220454 -21.784818) (xy 9.250588 -21.810535)
			(xy 9.306246 -21.866918) (xy 9.356159 -21.928444) (xy 9.399854 -21.994532) (xy 9.436918 -22.064554)
			(xy 9.466999 -22.137848) (xy 9.489812 -22.213718) (xy 9.505142 -22.291448) (xy 9.512843 -22.370299)
			(xy 9.513316 -22.409912) (xy 9.51283 -22.449843) (xy 9.505001 -22.529321) (xy 9.489419 -22.607648)
			(xy 9.466236 -22.684072) (xy 9.435673 -22.757855) (xy 9.398026 -22.828287) (xy 9.353656 -22.894689)
			(xy 9.302992 -22.956424) (xy 9.246521 -23.012895) (xy 9.184786 -23.063559) (xy 9.118383 -23.107928)
			(xy 9.047951 -23.145575) (xy 8.974168 -23.176137) (xy 8.897745 -23.19932) (xy 8.819417 -23.214901)
			(xy 8.739939 -23.22273) (xy 8.700008 -23.22322) (xy 8.660396 -23.222712) (xy 8.581547 -23.215012)
			(xy 8.50382 -23.199684) (xy 8.42795 -23.176874) (xy 8.354658 -23.146796) (xy 8.284636 -23.109737)
			(xy 8.218547 -23.066047) (xy 8.157019 -23.01614) (xy 8.100633 -22.960489) (xy 8.074914 -22.930358)
			(xy 8.066532 -22.920198) (xy 8.042148 -22.9108) (xy 7.930642 -22.925786) (xy 7.909814 -22.941534)
			(xy 7.904226 -22.953472) (xy 7.881914 -23.001616) (xy 7.830635 -23.094525) (xy 7.772068 -23.183022)
			(xy 7.706591 -23.266534) (xy 7.634625 -23.344525) (xy 7.556634 -23.416491) (xy 7.473122 -23.481968)
			(xy 7.384625 -23.540535) (xy 7.291716 -23.591814) (xy 7.243572 -23.614126) (xy 7.231634 -23.619714)
			(xy 7.215886 -23.640542) (xy 7.2009 -23.752048) (xy 7.210298 -23.776432) (xy 7.220458 -23.784814)
			(xy 7.250591 -23.810532) (xy 7.306249 -23.866915) (xy 7.356162 -23.928441) (xy 7.399857 -23.994529)
			(xy 7.436921 -24.064551) (xy 7.467002 -24.137844) (xy 7.489815 -24.213715) (xy 7.505145 -24.291444)
			(xy 7.512846 -24.370295) (xy 7.51332 -24.409908) (xy 7.886194 -24.409908) (xy 7.890238 -24.328878)
			(xy 7.90233 -24.248654) (xy 7.922349 -24.170032) (xy 7.950098 -24.093794) (xy 7.985299 -24.020698)
			(xy 8.027603 -23.95147) (xy 8.07659 -23.886798) (xy 8.131773 -23.827326) (xy 8.192603 -23.773643)
			(xy 8.258476 -23.726283) (xy 8.328737 -23.685718) (xy 8.402688 -23.65235) (xy 8.479594 -23.626511)
			(xy 8.558691 -23.608458) (xy 8.639192 -23.59837) (xy 8.720297 -23.596347) (xy 8.801201 -23.60241)
			(xy 8.881099 -23.616498) (xy 8.959197 -23.638471) (xy 9.034719 -23.668112) (xy 9.106915 -23.705124)
			(xy 9.175067 -23.749141) (xy 9.238497 -23.799726) (xy 9.296576 -23.856374) (xy 9.348726 -23.918524)
			(xy 9.394428 -23.985557) (xy 9.433229 -24.056807) (xy 9.464743 -24.131567) (xy 9.488657 -24.209093)
			(xy 9.504732 -24.288615) (xy 9.51281 -24.369343) (xy 9.513316 -24.409908) (xy 9.51281 -24.450473)
			(xy 9.504732 -24.531201) (xy 9.488657 -24.610723) (xy 9.464743 -24.688249) (xy 9.433229 -24.763009)
			(xy 9.394428 -24.834259) (xy 9.348726 -24.901292) (xy 9.296576 -24.963442) (xy 9.238497 -25.02009)
			(xy 9.175067 -25.070675) (xy 9.106915 -25.114692) (xy 9.034719 -25.151704) (xy 8.959197 -25.181345)
			(xy 8.881099 -25.203318) (xy 8.801201 -25.217406) (xy 8.720297 -25.223469) (xy 8.639192 -25.221446)
			(xy 8.558691 -25.211358) (xy 8.479594 -25.193305) (xy 8.402688 -25.167466) (xy 8.328737 -25.134098)
			(xy 8.258476 -25.093533) (xy 8.192603 -25.046173) (xy 8.131773 -24.99249) (xy 8.07659 -24.933018)
			(xy 8.027603 -24.868346) (xy 7.985299 -24.799118) (xy 7.950098 -24.726022) (xy 7.922349 -24.649784)
			(xy 7.90233 -24.571162) (xy 7.890238 -24.490938) (xy 7.886194 -24.409908) (xy 7.51332 -24.409908)
			(xy 7.51283 -24.449839) (xy 7.505002 -24.529317) (xy 7.489422 -24.607645) (xy 7.466239 -24.684068)
			(xy 7.435677 -24.757852) (xy 7.39803 -24.828284) (xy 7.353661 -24.894687) (xy 7.302997 -24.956422)
			(xy 7.246526 -25.012893) (xy 7.184791 -25.063557) (xy 7.118388 -25.107926) (xy 7.047956 -25.145573)
			(xy 6.974172 -25.176135) (xy 6.897749 -25.199318) (xy 6.819421 -25.214898) (xy 6.739943 -25.222726)
			(xy 6.660081 -25.222726) (xy 6.580603 -25.214898) (xy 6.502275 -25.199318) (xy 6.425852 -25.176135)
			(xy 6.352068 -25.145573) (xy 6.281636 -25.107926) (xy 6.215233 -25.063557) (xy 6.153498 -25.012893)
			(xy 6.097027 -24.956422) (xy 6.046363 -24.894687) (xy 6.001994 -24.828284) (xy 5.964347 -24.757852)
			(xy 5.933785 -24.684068) (xy 5.910602 -24.607645) (xy 5.895022 -24.529317) (xy 5.887194 -24.449839)
			(xy 5.886704 -24.409908) (xy 5.887203 -24.370296) (xy 5.894904 -24.291446) (xy 5.910232 -24.213718)
			(xy 5.933043 -24.137849) (xy 5.963121 -24.064556) (xy 6.000182 -23.994534) (xy 6.043873 -23.928446)
			(xy 6.093781 -23.866918) (xy 6.149434 -23.810532) (xy 6.179566 -23.784814) (xy 6.189726 -23.776432)
			(xy 6.199124 -23.752048) (xy 6.184138 -23.640542) (xy 6.16839 -23.619714) (xy 6.156452 -23.614126)
			(xy 6.10903 -23.592166) (xy 6.017457 -23.54179) (xy 5.93015 -23.484336) (xy 5.847657 -23.420163)
			(xy 5.770492 -23.349672) (xy 5.699139 -23.273304) (xy 5.634044 -23.191536) (xy 5.575613 -23.104881)
			(xy 5.524212 -23.013879) (xy 5.480163 -22.9191) (xy 5.443741 -22.821137) (xy 5.415174 -22.720602)
			(xy 5.39464 -22.618124) (xy 5.382268 -22.514344) (xy 5.378136 -22.409911) (xy 1.27 -22.409911) (xy 1.27 -26.409904)
			(xy 5.886198 -26.409904) (xy 5.890242 -26.328874) (xy 5.902334 -26.24865) (xy 5.922353 -26.170028)
			(xy 5.950102 -26.09379) (xy 5.985303 -26.020694) (xy 6.027607 -25.951466) (xy 6.076594 -25.886794)
			(xy 6.131777 -25.827322) (xy 6.192607 -25.773639) (xy 6.25848 -25.726279) (xy 6.328741 -25.685714)
			(xy 6.402692 -25.652346) (xy 6.479598 -25.626507) (xy 6.558695 -25.608454) (xy 6.639196 -25.598366)
			(xy 6.720301 -25.596343) (xy 6.801205 -25.602406) (xy 6.881103 -25.616494) (xy 6.959201 -25.638467)
			(xy 7.034723 -25.668108) (xy 7.106919 -25.70512) (xy 7.175071 -25.749137) (xy 7.238501 -25.799722)
			(xy 7.29658 -25.85637) (xy 7.34873 -25.91852) (xy 7.394432 -25.985553) (xy 7.433233 -26.056803) (xy 7.464747 -26.131563)
			(xy 7.488661 -26.209089) (xy 7.504736 -26.288611) (xy 7.512814 -26.369339) (xy 7.51332 -26.409904)
			(xy 7.886194 -26.409904) (xy 7.890238 -26.328874) (xy 7.90233 -26.24865) (xy 7.922349 -26.170028)
			(xy 7.950098 -26.09379) (xy 7.985299 -26.020694) (xy 8.027603 -25.951466) (xy 8.07659 -25.886794)
			(xy 8.131773 -25.827322) (xy 8.192603 -25.773639) (xy 8.258476 -25.726279) (xy 8.328737 -25.685714)
			(xy 8.402688 -25.652346) (xy 8.479594 -25.626507) (xy 8.558691 -25.608454) (xy 8.639192 -25.598366)
			(xy 8.720297 -25.596343) (xy 8.801201 -25.602406) (xy 8.881099 -25.616494) (xy 8.959197 -25.638467)
			(xy 9.034719 -25.668108) (xy 9.106915 -25.70512) (xy 9.175067 -25.749137) (xy 9.238497 -25.799722)
			(xy 9.296576 -25.85637) (xy 9.348726 -25.91852) (xy 9.394428 -25.985553) (xy 9.433229 -26.056803)
			(xy 9.464743 -26.131563) (xy 9.488657 -26.209089) (xy 9.504732 -26.288611) (xy 9.51281 -26.369339)
			(xy 9.513316 -26.409904) (xy 9.51281 -26.450469) (xy 9.504732 -26.531197) (xy 9.488657 -26.610719)
			(xy 9.464743 -26.688245) (xy 9.433229 -26.763005) (xy 9.394428 -26.834255) (xy 9.348726 -26.901288)
			(xy 9.296576 -26.963438) (xy 9.238497 -27.020086) (xy 9.175067 -27.070671) (xy 9.106915 -27.114688)
			(xy 9.034719 -27.1517) (xy 8.959197 -27.181341) (xy 8.881099 -27.203314) (xy 8.801201 -27.217402)
			(xy 8.720297 -27.223465) (xy 8.639192 -27.221442) (xy 8.558691 -27.211354) (xy 8.479594 -27.193301)
			(xy 8.402688 -27.167462) (xy 8.328737 -27.134094) (xy 8.258476 -27.093529) (xy 8.192603 -27.046169)
			(xy 8.131773 -26.992486) (xy 8.07659 -26.933014) (xy 8.027603 -26.868342) (xy 7.985299 -26.799114)
			(xy 7.950098 -26.726018) (xy 7.922349 -26.64978) (xy 7.90233 -26.571158) (xy 7.890238 -26.490934)
			(xy 7.886194 -26.409904) (xy 7.51332 -26.409904) (xy 7.512814 -26.450469) (xy 7.504736 -26.531197)
			(xy 7.488661 -26.610719) (xy 7.464747 -26.688245) (xy 7.433233 -26.763005) (xy 7.394432 -26.834255)
			(xy 7.34873 -26.901288) (xy 7.29658 -26.963438) (xy 7.238501 -27.020086) (xy 7.175071 -27.070671)
			(xy 7.106919 -27.114688) (xy 7.034723 -27.1517) (xy 6.959201 -27.181341) (xy 6.881103 -27.203314)
			(xy 6.801205 -27.217402) (xy 6.720301 -27.223465) (xy 6.639196 -27.221442) (xy 6.558695 -27.211354)
			(xy 6.479598 -27.193301) (xy 6.402692 -27.167462) (xy 6.328741 -27.134094) (xy 6.25848 -27.093529)
			(xy 6.192607 -27.046169) (xy 6.131777 -26.992486) (xy 6.076594 -26.933014) (xy 6.027607 -26.868342)
			(xy 5.985303 -26.799114) (xy 5.950102 -26.726018) (xy 5.922353 -26.64978) (xy 5.902334 -26.571158)
			(xy 5.890242 -26.490934) (xy 5.886198 -26.409904) (xy 1.27 -26.409904) (xy 1.27 -38.649656) (xy 10.387838 -38.649656)
			(xy 10.388269 -38.611368) (xy 10.394891 -38.535077) (xy 10.408039 -38.459638) (xy 10.427617 -38.385605)
			(xy 10.440162 -38.349428) (xy 10.442827 -38.340996) (xy 10.442813 -38.323322) (xy 10.440162 -38.314884)
			(xy 10.427591 -38.278714) (xy 10.407999 -38.204683) (xy 10.394852 -38.12924) (xy 10.388247 -38.052946)
			(xy 10.387838 -38.014656) (xy 10.388364 -37.971538) (xy 10.396707 -37.885706) (xy 10.41332 -37.801085)
			(xy 10.438046 -37.71847) (xy 10.453878 -37.67836) (xy 10.45724 -37.668998) (xy 10.457224 -37.649122)
			(xy 10.453878 -37.639752) (xy 10.438056 -37.599638) (xy 10.413323 -37.517025) (xy 10.396702 -37.432405)
			(xy 10.388349 -37.346574) (xy 10.387838 -37.303456) (xy 10.388313 -37.262354) (xy 10.395898 -37.180499)
			(xy 10.411003 -37.099694) (xy 10.4335 -37.020628) (xy 10.463196 -36.943974) (xy 10.499838 -36.870387)
			(xy 10.543114 -36.800495) (xy 10.592653 -36.734894) (xy 10.648034 -36.674144) (xy 10.708784 -36.618763)
			(xy 10.774385 -36.569224) (xy 10.844277 -36.525948) (xy 10.917864 -36.489306) (xy 10.994518 -36.45961)
			(xy 11.073584 -36.437113) (xy 11.154389 -36.422008) (xy 11.236244 -36.414423) (xy 11.277346 -36.413948)
			(xy 11.323741 -36.414545) (xy 11.416029 -36.424185) (xy 11.506813 -36.443377) (xy 11.595107 -36.471912)
			(xy 11.637772 -36.490148) (xy 11.647712 -36.493968) (xy 11.66898 -36.493968) (xy 11.67892 -36.490148)
			(xy 11.721577 -36.471891) (xy 11.809871 -36.44335) (xy 11.900658 -36.42416) (xy 11.99295 -36.414531)
			(xy 12.039346 -36.413948) (xy 12.080448 -36.41443) (xy 12.162302 -36.422015) (xy 12.243107 -36.43712)
			(xy 12.322174 -36.459616) (xy 12.398828 -36.489311) (xy 12.472414 -36.525952) (xy 12.542306 -36.569227)
			(xy 12.607907 -36.618766) (xy 12.668657 -36.674147) (xy 12.724039 -36.734897) (xy 12.773578 -36.800497)
			(xy 12.816854 -36.870389) (xy 12.853496 -36.943975) (xy 12.883192 -37.020629) (xy 12.905689 -37.099695)
			(xy 12.920794 -37.1805) (xy 12.928379 -37.262354) (xy 12.928854 -37.303456) (xy 12.928332 -37.346574)
			(xy 12.919988 -37.432406) (xy 12.903374 -37.517027) (xy 12.878647 -37.599643) (xy 12.862814 -37.639752)
			(xy 12.859501 -37.649128) (xy 12.859485 -37.668991) (xy 12.862814 -37.67836) (xy 12.878639 -37.718473)
			(xy 12.903372 -37.801087) (xy 12.919992 -37.885706) (xy 12.928343 -37.971538) (xy 12.928854 -38.014656)
			(xy 12.928427 -38.052944) (xy 12.921804 -38.129235) (xy 12.908654 -38.204675) (xy 12.889075 -38.278707)
			(xy 12.87653 -38.314884) (xy 12.873909 -38.323327) (xy 12.873895 -38.34099) (xy 12.87653 -38.349428)
			(xy 12.889104 -38.385597) (xy 12.908695 -38.459628) (xy 12.921842 -38.535071) (xy 12.928446 -38.611366)
			(xy 12.928854 -38.649656) (xy 12.928394 -38.690759) (xy 12.920809 -38.772615) (xy 12.905704 -38.853422)
			(xy 12.883208 -38.93249) (xy 12.853511 -39.009145) (xy 12.816869 -39.082734) (xy 12.773593 -39.152627)
			(xy 12.724053 -39.218229) (xy 12.66867 -39.27898) (xy 12.607919 -39.334363) (xy 12.542317 -39.383903)
			(xy 12.472424 -39.427179) (xy 12.398835 -39.463821) (xy 12.32218 -39.493518) (xy 12.243112 -39.516014)
			(xy 12.162305 -39.531119) (xy 12.080449 -39.538704) (xy 12.039346 -39.539164) (xy 11.992951 -39.538569)
			(xy 11.900663 -39.528928) (xy 11.809879 -39.509736) (xy 11.721585 -39.4812) (xy 11.67892 -39.462964)
			(xy 11.66898 -39.459144) (xy 11.647712 -39.459144) (xy 11.637772 -39.462964) (xy 11.595102 -39.481191)
			(xy 11.506813 -39.50974) (xy 11.41603 -39.528938) (xy 11.323741 -39.538577) (xy 11.277346 -39.539164)
			(xy 11.236243 -39.538697) (xy 11.154389 -39.531112) (xy 11.073583 -39.516006) (xy 10.994516 -39.493509)
			(xy 10.917862 -39.463813) (xy 10.844275 -39.427171) (xy 10.774383 -39.383895) (xy 10.708782 -39.334355)
			(xy 10.648031 -39.278973) (xy 10.59265 -39.218222) (xy 10.543111 -39.152621) (xy 10.499835 -39.082728)
			(xy 10.463194 -39.009141) (xy 10.433498 -38.932486) (xy 10.411002 -38.853419) (xy 10.395897 -38.772613)
			(xy 10.388312 -38.690759) (xy 10.387838 -38.649656) (xy 1.27 -38.649656) (xy 1.27 -39.342822) (xy 2.633978 -39.342822)
			(xy 2.638049 -39.2872) (xy 2.650175 -39.232763) (xy 2.670098 -39.180672) (xy 2.697394 -39.132037)
			(xy 2.73148 -39.087894) (xy 2.771629 -39.049185) (xy 2.816987 -39.016734) (xy 2.866587 -38.991233)
			(xy 2.919371 -38.973226) (xy 2.974214 -38.963096) (xy 3.029948 -38.961059) (xy 3.085385 -38.967159)
			(xy 3.139342 -38.981265) (xy 3.190671 -39.003077) (xy 3.238277 -39.032131) (xy 3.281145 -39.067806)
			(xy 3.318362 -39.109343) (xy 3.349135 -39.155856) (xy 3.372807 -39.206353) (xy 3.388875 -39.25976)
			(xy 3.396995 -39.314936) (xy 3.397504 -39.342822) (xy 3.396995 -39.370708) (xy 3.388875 -39.425884)
			(xy 3.372807 -39.479291) (xy 3.349135 -39.529788) (xy 3.318362 -39.576301) (xy 3.281145 -39.617838)
			(xy 3.238277 -39.653513) (xy 3.190671 -39.682567) (xy 3.139342 -39.704379) (xy 3.085385 -39.718485)
			(xy 3.029948 -39.724585) (xy 2.974214 -39.722548) (xy 2.919371 -39.712418) (xy 2.866587 -39.694411)
			(xy 2.816987 -39.66891) (xy 2.771629 -39.636459) (xy 2.73148 -39.59775) (xy 2.697394 -39.553607)
			(xy 2.670098 -39.504972) (xy 2.650175 -39.452881) (xy 2.638049 -39.398444) (xy 2.633978 -39.342822)
			(xy 1.27 -39.342822) (xy 1.27 -41.463722) (xy 1.881124 -41.463722) (xy 1.881649 -41.434805) (xy 1.890375 -41.377634)
			(xy 1.907631 -41.322435) (xy 1.933022 -41.270473) (xy 1.965965 -41.222939) (xy 2.005705 -41.180922)
			(xy 2.02819 -41.162732) (xy 2.036932 -41.15515) (xy 2.047127 -41.134407) (xy 2.047748 -41.122854)
			(xy 2.047748 -41.04259) (xy 2.047201 -41.031019) (xy 2.036992 -41.010247) (xy 2.02819 -41.002712)
			(xy 2.00571 -40.984517) (xy 1.965975 -40.942498) (xy 1.933036 -40.894963) (xy 1.907647 -40.843003)
			(xy 1.89039 -40.787806) (xy 1.88166 -40.730638) (xy 1.881124 -40.701722) (xy 1.88161 -40.674471)
			(xy 1.889366 -40.620523) (xy 1.904721 -40.568228) (xy 1.927363 -40.518651) (xy 1.956829 -40.472801)
			(xy 1.99252 -40.43161) (xy 2.033711 -40.395919) (xy 2.079561 -40.366453) (xy 2.129138 -40.343811)
			(xy 2.181433 -40.328456) (xy 2.235381 -40.3207) (xy 2.289883 -40.3207) (xy 2.343831 -40.328456) (xy 2.396126 -40.343811)
			(xy 2.445703 -40.366453) (xy 2.491553 -40.395919) (xy 2.532744 -40.43161) (xy 2.568435 -40.472801)
			(xy 2.597901 -40.518651) (xy 2.620543 -40.568228) (xy 2.635898 -40.620523) (xy 2.643654 -40.674471)
			(xy 2.64414 -40.701722) (xy 2.643588 -40.730638) (xy 2.634869 -40.787809) (xy 2.617619 -40.843008)
			(xy 2.592234 -40.89497) (xy 2.559295 -40.942505) (xy 2.519558 -40.984522) (xy 2.497074 -41.002712)
			(xy 2.488307 -41.010268) (xy 2.478127 -41.031031) (xy 2.477516 -41.04259) (xy 2.477516 -41.122854)
			(xy 2.478107 -41.134419) (xy 2.488287 -41.155191) (xy 2.497074 -41.162732) (xy 2.519554 -41.180927)
			(xy 2.55929 -41.222946) (xy 2.592229 -41.27048) (xy 2.617618 -41.32244) (xy 2.634875 -41.377637)
			(xy 2.643605 -41.434806) (xy 2.64414 -41.463722) (xy 2.643654 -41.490973) (xy 2.635898 -41.544921)
			(xy 2.620543 -41.597216) (xy 2.597901 -41.646793) (xy 2.568435 -41.692643) (xy 2.532744 -41.733834)
			(xy 2.491553 -41.769525) (xy 2.445703 -41.798991) (xy 2.396126 -41.821633) (xy 2.343831 -41.836988)
			(xy 2.289883 -41.844744) (xy 2.235381 -41.844744) (xy 2.181433 -41.836988) (xy 2.129138 -41.821633)
			(xy 2.079561 -41.798991) (xy 2.033711 -41.769525) (xy 1.99252 -41.733834) (xy 1.956829 -41.692643)
			(xy 1.927363 -41.646793) (xy 1.904721 -41.597216) (xy 1.889366 -41.544921) (xy 1.88161 -41.490973)
			(xy 1.881124 -41.463722) (xy 1.27 -41.463722) (xy 1.27 -44.181522) (xy 2.465324 -44.181522) (xy 2.465849 -44.152605)
			(xy 2.474575 -44.095434) (xy 2.491831 -44.040235) (xy 2.517222 -43.988273) (xy 2.550165 -43.940739)
			(xy 2.589905 -43.898722) (xy 2.61239 -43.880532) (xy 2.621132 -43.87295) (xy 2.631327 -43.852207)
			(xy 2.631948 -43.840654) (xy 2.631948 -43.76039) (xy 2.631401 -43.748819) (xy 2.621192 -43.728047)
			(xy 2.61239 -43.720512) (xy 2.58991 -43.702317) (xy 2.550175 -43.660298) (xy 2.517236 -43.612763)
			(xy 2.491847 -43.560803) (xy 2.47459 -43.505606) (xy 2.46586 -43.448438) (xy 2.465324 -43.419522)
			(xy 2.465787 -43.392269) (xy 2.473544 -43.338318) (xy 2.4889 -43.28602) (xy 2.511542 -43.23644) (xy 2.54101 -43.190587)
			(xy 2.576704 -43.149394) (xy 2.617897 -43.1137) (xy 2.66375 -43.084232) (xy 2.71333 -43.06159) (xy 2.765628 -43.046234)
			(xy 2.819579 -43.038477) (xy 2.846832 -43.038014) (xy 2.874203 -43.038458) (xy 2.928383 -43.046281)
			(xy 2.980887 -43.061775) (xy 3.030633 -43.084621) (xy 3.076599 -43.114351) (xy 3.09753 -43.131994)
			(xy 3.104642 -43.13809) (xy 3.12166 -43.14444) (xy 3.207004 -43.14444) (xy 3.224022 -43.13809) (xy 3.231134 -43.131994)
			(xy 3.252079 -43.114371) (xy 3.298049 -43.084657) (xy 3.347793 -43.061818) (xy 3.40029 -43.046323)
			(xy 3.454464 -43.038491) (xy 3.481832 -43.038014) (xy 3.509083 -43.038496) (xy 3.563031 -43.046253)
			(xy 3.615326 -43.061608) (xy 3.664904 -43.08425) (xy 3.710754 -43.113716) (xy 3.751944 -43.149408)
			(xy 3.787636 -43.190599) (xy 3.817102 -43.23645) (xy 3.839743 -43.286027) (xy 3.855098 -43.338323)
			(xy 3.862854 -43.392271) (xy 3.86334 -43.419522) (xy 3.862788 -43.448438) (xy 3.854069 -43.505609)
			(xy 3.836819 -43.560808) (xy 3.811434 -43.61277) (xy 3.778495 -43.660305) (xy 3.738758 -43.702322)
			(xy 3.716274 -43.720512) (xy 3.707507 -43.728068) (xy 3.697327 -43.748831) (xy 3.696716 -43.76039)
			(xy 3.696716 -43.840654) (xy 3.697307 -43.852219) (xy 3.707487 -43.872991) (xy 3.716274 -43.880532)
			(xy 3.738754 -43.898727) (xy 3.77849 -43.940746) (xy 3.811429 -43.98828) (xy 3.836818 -44.04024)
			(xy 3.854075 -44.095437) (xy 3.862805 -44.152606) (xy 3.86334 -44.181522) (xy 3.862854 -44.208773)
			(xy 3.855097 -44.262721) (xy 3.854999 -44.263056) (xy 10.41019 -44.263056) (xy 10.410793 -44.216661)
			(xy 10.420432 -44.124373) (xy 10.439622 -44.033589) (xy 10.468155 -43.945295) (xy 10.48639 -43.90263)
			(xy 10.490321 -43.892716) (xy 10.490304 -43.871404) (xy 10.48639 -43.861482) (xy 10.468131 -43.818826)
			(xy 10.43959 -43.730531) (xy 10.420401 -43.639744) (xy 10.410773 -43.547453) (xy 10.41019 -43.501056)
			(xy 10.410625 -43.459953) (xy 10.418213 -43.378098) (xy 10.433322 -43.297292) (xy 10.455822 -43.218224)
			(xy 10.485522 -43.14157) (xy 10.522167 -43.067983) (xy 10.565445 -42.998092) (xy 10.614987 -42.932491)
			(xy 10.670371 -42.871741) (xy 10.731123 -42.81636) (xy 10.796726 -42.766821) (xy 10.86662 -42.723546)
			(xy 10.940209 -42.686905) (xy 11.016864 -42.657209) (xy 11.095932 -42.634713) (xy 11.176739 -42.619608)
			(xy 11.258595 -42.612023) (xy 11.299698 -42.611548) (xy 11.346094 -42.612127) (xy 11.438382 -42.621772)
			(xy 11.529166 -42.640969) (xy 11.617459 -42.669509) (xy 11.660124 -42.687748) (xy 11.670064 -42.691568)
			(xy 11.691332 -42.691568) (xy 11.701272 -42.687748) (xy 11.743936 -42.669507) (xy 11.832227 -42.640961)
			(xy 11.923012 -42.621767) (xy 12.015302 -42.612133) (xy 12.061698 -42.611548) (xy 12.1028 -42.612029)
			(xy 12.184654 -42.619613) (xy 12.265459 -42.634718) (xy 12.344526 -42.657214) (xy 12.42118 -42.68691)
			(xy 12.494766 -42.723551) (xy 12.564658 -42.766826) (xy 12.630259 -42.816366) (xy 12.691009 -42.871746)
			(xy 12.746391 -42.932496) (xy 12.79593 -42.998097) (xy 12.839206 -43.067988) (xy 12.875848 -43.141575)
			(xy 12.905544 -43.218228) (xy 12.928041 -43.297295) (xy 12.943146 -43.3781) (xy 12.950731 -43.459954)
			(xy 12.951206 -43.501056) (xy 12.950608 -43.547451) (xy 12.940967 -43.639739) (xy 12.921776 -43.730523)
			(xy 12.893242 -43.818817) (xy 12.875006 -43.861482) (xy 12.871127 -43.871412) (xy 12.87111 -43.892709)
			(xy 12.875006 -43.90263) (xy 12.893236 -43.945298) (xy 12.921784 -44.033588) (xy 12.940981 -44.124372)
			(xy 12.950619 -44.21666) (xy 12.951206 -44.263056) (xy 12.950706 -44.304159) (xy 12.943125 -44.386013)
			(xy 12.928023 -44.466819) (xy 12.90553 -44.545887) (xy 12.875837 -44.622542) (xy 12.839197 -44.69613)
			(xy 12.795924 -44.766023) (xy 12.746387 -44.831626) (xy 12.691007 -44.892377) (xy 12.630258 -44.94776)
			(xy 12.564658 -44.997301) (xy 12.494767 -45.040577) (xy 12.42118 -45.07722) (xy 12.344527 -45.106917)
			(xy 12.26546 -45.129414) (xy 12.184655 -45.144519) (xy 12.1028 -45.152104) (xy 12.061698 -45.152564)
			(xy 12.015302 -45.151986) (xy 11.923014 -45.14234) (xy 11.83223 -45.123143) (xy 11.743937 -45.094603)
			(xy 11.701272 -45.076364) (xy 11.691332 -45.072544) (xy 11.670064 -45.072544) (xy 11.660124 -45.076364)
			(xy 11.617461 -45.094607) (xy 11.529169 -45.123152) (xy 11.438384 -45.142346) (xy 11.346094 -45.151979)
			(xy 11.299698 -45.152564) (xy 11.258595 -45.15211) (xy 11.176739 -45.144524) (xy 11.095932 -45.129419)
			(xy 11.016864 -45.106922) (xy 10.940208 -45.077225) (xy 10.86662 -45.040582) (xy 10.796727 -44.997306)
			(xy 10.731124 -44.947765) (xy 10.670373 -44.892383) (xy 10.614991 -44.831631) (xy 10.565451 -44.766028)
			(xy 10.522175 -44.696135) (xy 10.485533 -44.622546) (xy 10.455836 -44.545891) (xy 10.43334 -44.466822)
			(xy 10.418235 -44.386015) (xy 10.41065 -44.304159) (xy 10.41019 -44.263056) (xy 3.854999 -44.263056)
			(xy 3.839742 -44.315015) (xy 3.817101 -44.364593) (xy 3.787635 -44.410443) (xy 3.751943 -44.451633)
			(xy 3.710753 -44.487325) (xy 3.664903 -44.516791) (xy 3.615325 -44.539432) (xy 3.563031 -44.554787)
			(xy 3.509083 -44.562544) (xy 3.481832 -44.56303) (xy 3.454462 -44.562562) (xy 3.400282 -44.554747)
			(xy 3.347778 -44.53926) (xy 3.298031 -44.516418) (xy 3.252065 -44.486692) (xy 3.231134 -44.46905)
			(xy 3.224022 -44.462954) (xy 3.207004 -44.456604) (xy 3.12166 -44.456604) (xy 3.104642 -44.462954)
			(xy 3.09753 -44.46905) (xy 3.076591 -44.486681) (xy 3.030621 -44.516396) (xy 2.980875 -44.539234)
			(xy 2.928376 -44.554727) (xy 2.874201 -44.562556) (xy 2.846832 -44.56303) (xy 2.819581 -44.56254)
			(xy 2.765633 -44.554784) (xy 2.713339 -44.539429) (xy 2.663762 -44.516789) (xy 2.617911 -44.487323)
			(xy 2.576721 -44.451632) (xy 2.54103 -44.410442) (xy 2.511563 -44.364592) (xy 2.488922 -44.315015)
			(xy 2.473567 -44.262721) (xy 2.46581 -44.208773) (xy 2.465324 -44.181522) (xy 1.27 -44.181522) (xy 1.27 -46.315122)
			(xy 2.940812 -46.315122) (xy 2.941342 -46.286205) (xy 2.950068 -46.229035) (xy 2.967323 -46.173836)
			(xy 2.992713 -46.121874) (xy 3.025654 -46.07434) (xy 3.065393 -46.032322) (xy 3.087878 -46.014132)
			(xy 3.096634 -46.006565) (xy 3.106817 -45.98581) (xy 3.107436 -45.974254) (xy 3.107436 -45.89399)
			(xy 3.106894 -45.882418) (xy 3.096681 -45.861646) (xy 3.087878 -45.854112) (xy 3.065396 -45.83592)
			(xy 3.025661 -45.7939) (xy 2.992723 -45.746365) (xy 2.967335 -45.694404) (xy 2.950078 -45.639207)
			(xy 2.941348 -45.582038) (xy 2.940812 -45.553122) (xy 2.941298 -45.525871) (xy 2.949054 -45.471923)
			(xy 2.964409 -45.419628) (xy 2.987051 -45.370051) (xy 3.016517 -45.324201) (xy 3.052208 -45.28301)
			(xy 3.093399 -45.247319) (xy 3.139249 -45.217853) (xy 3.188826 -45.195211) (xy 3.241121 -45.179856)
			(xy 3.295069 -45.1721) (xy 3.349571 -45.1721) (xy 3.403519 -45.179856) (xy 3.455814 -45.195211) (xy 3.505391 -45.217853)
			(xy 3.551241 -45.247319) (xy 3.592432 -45.28301) (xy 3.628123 -45.324201) (xy 3.657589 -45.370051)
			(xy 3.680231 -45.419628) (xy 3.695586 -45.471923) (xy 3.703342 -45.525871) (xy 3.703828 -45.553122)
			(xy 3.703281 -45.582038) (xy 3.694562 -45.639209) (xy 3.677311 -45.694409) (xy 3.651925 -45.746371)
			(xy 3.618985 -45.793905) (xy 3.579246 -45.835922) (xy 3.556762 -45.854112) (xy 3.547993 -45.861667)
			(xy 3.537815 -45.882431) (xy 3.537204 -45.89399) (xy 3.537204 -45.974254) (xy 3.537799 -45.985819)
			(xy 3.547976 -46.00659) (xy 3.556762 -46.014132) (xy 3.579242 -46.032327) (xy 3.618977 -46.074346)
			(xy 3.651917 -46.12188) (xy 3.677306 -46.173841) (xy 3.694563 -46.229037) (xy 3.703293 -46.286206)
			(xy 3.703828 -46.315122) (xy 3.703342 -46.342373) (xy 3.696305 -46.391322) (xy 7.843012 -46.391322)
			(xy 7.843601 -46.344927) (xy 7.853244 -46.252638) (xy 7.872438 -46.161855) (xy 7.900975 -46.073561)
			(xy 7.919212 -46.030896) (xy 7.923019 -46.020952) (xy 7.923028 -45.999687) (xy 7.919212 -45.989748)
			(xy 7.900976 -45.947082) (xy 7.872429 -45.858791) (xy 7.853234 -45.768007) (xy 7.843598 -45.675718)
			(xy 7.843012 -45.629322) (xy 7.843516 -45.586974) (xy 7.851567 -45.50266) (xy 7.867596 -45.419494)
			(xy 7.891457 -45.338227) (xy 7.922936 -45.259597) (xy 7.961747 -45.184316) (xy 8.007537 -45.113064)
			(xy 8.059893 -45.046488) (xy 8.118341 -44.98519) (xy 8.182351 -44.929725) (xy 8.251343 -44.880596)
			(xy 8.324693 -44.838247) (xy 8.401736 -44.803063) (xy 8.481775 -44.775361) (xy 8.564084 -44.755393)
			(xy 8.647919 -44.74334) (xy 8.73252 -44.73931) (xy 8.817121 -44.74334) (xy 8.900956 -44.755393) (xy 8.983265 -44.775361)
			(xy 9.063304 -44.803063) (xy 9.140347 -44.838247) (xy 9.213697 -44.880596) (xy 9.282689 -44.929725)
			(xy 9.346699 -44.98519) (xy 9.405147 -45.046488) (xy 9.457503 -45.113064) (xy 9.503293 -45.184316)
			(xy 9.542104 -45.259597) (xy 9.573583 -45.338227) (xy 9.597444 -45.419494) (xy 9.613473 -45.50266)
			(xy 9.621524 -45.586974) (xy 9.622028 -45.629322) (xy 9.621416 -45.675717) (xy 9.611779 -45.768004)
			(xy 9.592592 -45.858788) (xy 9.564062 -45.947082) (xy 9.545828 -45.989748) (xy 9.541998 -45.999684)
			(xy 9.542006 -46.020956) (xy 9.545828 -46.030896) (xy 9.564081 -46.073555) (xy 9.592623 -46.161848)
			(xy 9.611813 -46.252635) (xy 9.621444 -46.344926) (xy 9.622028 -46.391322) (xy 9.621525 -46.434214)
			(xy 9.613256 -46.519598) (xy 9.596807 -46.603789) (xy 9.57233 -46.686007) (xy 9.540053 -46.765486)
			(xy 9.500276 -46.84149) (xy 9.453367 -46.913312) (xy 9.399763 -46.980285) (xy 9.339961 -47.041787)
			(xy 9.274517 -47.097248) (xy 9.204038 -47.146151) (xy 9.16686 -47.167546) (xy 9.154414 -47.174658)
			(xy 9.140444 -47.198788) (xy 9.143492 -47.317152) (xy 9.158224 -47.340774) (xy 9.171178 -47.347124)
			(xy 9.207714 -47.365908) (xy 9.27754 -47.409202) (xy 9.343075 -47.45875) (xy 9.403763 -47.51413)
			(xy 9.459086 -47.57487) (xy 9.508572 -47.640452) (xy 9.551801 -47.710318) (xy 9.588403 -47.783872)
			(xy 9.618066 -47.860488) (xy 9.640539 -47.939513) (xy 9.655629 -48.020273) (xy 9.663209 -48.102081)
			(xy 9.663684 -48.14316) (xy 9.663089 -48.189555) (xy 9.653448 -48.281843) (xy 9.634255 -48.372627)
			(xy 9.60572 -48.460921) (xy 9.587484 -48.503586) (xy 9.583688 -48.513533) (xy 9.583672 -48.534795)
			(xy 9.587484 -48.544734) (xy 9.605714 -48.587402) (xy 9.634262 -48.675692) (xy 9.65346 -48.766475)
			(xy 9.663097 -48.858764) (xy 9.663684 -48.90516) (xy 9.663171 -48.947331) (xy 9.655174 -49.031292)
			(xy 9.639267 -49.11412) (xy 9.615592 -49.195071) (xy 9.584362 -49.273417) (xy 9.545857 -49.348457)
			(xy 9.500424 -49.419515) (xy 9.448469 -49.485955) (xy 9.39046 -49.547179) (xy 9.326917 -49.602639)
			(xy 9.25841 -49.651836) (xy 9.222232 -49.67351) (xy 9.210548 -49.680368) (xy 9.19734 -49.703228)
			(xy 9.19607 -49.817782) (xy 9.209024 -49.840896) (xy 9.220708 -49.848008) (xy 9.255817 -49.869949)
			(xy 9.322216 -49.919412) (xy 9.383731 -49.974831) (xy 9.439829 -50.035727) (xy 9.490027 -50.101572)
			(xy 9.533888 -50.171797) (xy 9.571033 -50.245794) (xy 9.601142 -50.322923) (xy 9.623953 -50.402516)
			(xy 9.639269 -50.483884) (xy 9.646957 -50.566323) (xy 9.647428 -50.607722) (xy 9.646816 -50.654117)
			(xy 9.637179 -50.746404) (xy 9.617992 -50.837188) (xy 9.589462 -50.925482) (xy 9.571228 -50.968148)
			(xy 9.567398 -50.978084) (xy 9.567406 -50.999356) (xy 9.571228 -51.009296) (xy 9.589481 -51.051955)
			(xy 9.618023 -51.140248) (xy 9.637213 -51.231035) (xy 9.646844 -51.323326) (xy 9.647428 -51.369722)
			(xy 9.646924 -51.41207) (xy 9.638873 -51.496384) (xy 9.622844 -51.57955) (xy 9.598983 -51.660817)
			(xy 9.567504 -51.739447) (xy 9.528693 -51.814728) (xy 9.482903 -51.88598) (xy 9.430547 -51.952556)
			(xy 9.372099 -52.013854) (xy 9.308089 -52.069319) (xy 9.239097 -52.118448) (xy 9.165747 -52.160797)
			(xy 9.088704 -52.195981) (xy 9.008665 -52.223683) (xy 8.926356 -52.243651) (xy 8.842521 -52.255704)
			(xy 8.75792 -52.259735) (xy 8.673319 -52.255704) (xy 8.589484 -52.243651) (xy 8.507175 -52.223683)
			(xy 8.427136 -52.195981) (xy 8.350093 -52.160797) (xy 8.276743 -52.118448) (xy 8.207751 -52.069319)
			(xy 8.143741 -52.013854) (xy 8.085293 -51.952556) (xy 8.032937 -51.88598) (xy 7.987147 -51.814728)
			(xy 7.948336 -51.739447) (xy 7.916857 -51.660817) (xy 7.892996 -51.57955) (xy 7.876967 -51.496384)
			(xy 7.868916 -51.41207) (xy 7.868412 -51.369722) (xy 7.869001 -51.323327) (xy 7.878644 -51.231038)
			(xy 7.897838 -51.140255) (xy 7.926375 -51.051961) (xy 7.944612 -51.009296) (xy 7.948419 -50.999352)
			(xy 7.948428 -50.978087) (xy 7.944612 -50.968148) (xy 7.926376 -50.925482) (xy 7.897829 -50.837191)
			(xy 7.878634 -50.746407) (xy 7.868998 -50.654118) (xy 7.868412 -50.607722) (xy 7.868912 -50.565551)
			(xy 7.876911 -50.481589) (xy 7.89282 -50.398761) (xy 7.916496 -50.31781) (xy 7.947728 -50.239464)
			(xy 7.986233 -50.164424) (xy 8.031668 -50.093366) (xy 8.083624 -50.026926) (xy 8.141634 -49.965702)
			(xy 8.205178 -49.910243) (xy 8.273685 -49.861046) (xy 8.309864 -49.839372) (xy 8.321548 -49.832514)
			(xy 8.334756 -49.809654) (xy 8.336026 -49.6951) (xy 8.323072 -49.671986) (xy 8.311388 -49.664874)
			(xy 8.27629 -49.642915) (xy 8.209891 -49.593454) (xy 8.148376 -49.538037) (xy 8.092277 -49.477143)
			(xy 8.042079 -49.4113) (xy 7.998217 -49.341077) (xy 7.96107 -49.267081) (xy 7.93096 -49.189954) (xy 7.908148 -49.110363)
			(xy 7.89283 -49.028996) (xy 7.88514 -48.946558) (xy 7.884668 -48.90516) (xy 7.885274 -48.858765)
			(xy 7.894913 -48.766477) (xy 7.914102 -48.675694) (xy 7.942634 -48.587399) (xy 7.960868 -48.544734)
			(xy 7.964709 -48.534801) (xy 7.964694 -48.513527) (xy 7.960868 -48.503586) (xy 7.942609 -48.46093)
			(xy 7.914069 -48.372635) (xy 7.89488 -48.281848) (xy 7.885251 -48.189557) (xy 7.884668 -48.14316)
			(xy 7.88524 -48.10027) (xy 7.893501 -48.014888) (xy 7.909943 -47.930699) (xy 7.934412 -47.848482)
			(xy 7.966682 -47.769003) (xy 8.006452 -47.693) (xy 8.053354 -47.621177) (xy 8.106952 -47.554203)
			(xy 8.166748 -47.492699) (xy 8.232187 -47.437237) (xy 8.30266 -47.388332) (xy 8.339836 -47.366936)
			(xy 8.352282 -47.359824) (xy 8.366252 -47.335694) (xy 8.363204 -47.21733) (xy 8.348472 -47.193708)
			(xy 8.335518 -47.187358) (xy 8.298973 -47.16859) (xy 8.229148 -47.125295) (xy 8.163612 -47.075745)
			(xy 8.102925 -47.020364) (xy 8.047602 -46.959622) (xy 7.998116 -46.894038) (xy 7.954889 -46.824171)
			(xy 7.918287 -46.750615) (xy 7.888625 -46.673998) (xy 7.866153 -46.594972) (xy 7.851064 -46.51421)
			(xy 7.843487 -46.432401) (xy 7.843012 -46.391322) (xy 3.696305 -46.391322) (xy 3.695586 -46.396321)
			(xy 3.680231 -46.448616) (xy 3.657589 -46.498193) (xy 3.628123 -46.544043) (xy 3.592432 -46.585234)
			(xy 3.551241 -46.620925) (xy 3.505391 -46.650391) (xy 3.455814 -46.673033) (xy 3.403519 -46.688388)
			(xy 3.349571 -46.696144) (xy 3.295069 -46.696144) (xy 3.241121 -46.688388) (xy 3.188826 -46.673033)
			(xy 3.139249 -46.650391) (xy 3.093399 -46.620925) (xy 3.052208 -46.585234) (xy 3.016517 -46.544043)
			(xy 2.987051 -46.498193) (xy 2.964409 -46.448616) (xy 2.949054 -46.396321) (xy 2.941298 -46.342373)
			(xy 2.940812 -46.315122) (xy 1.27 -46.315122) (xy 1.27 -48.982122) (xy 2.940812 -48.982122) (xy 2.941342 -48.953205)
			(xy 2.950068 -48.896035) (xy 2.967323 -48.840836) (xy 2.992713 -48.788874) (xy 3.025654 -48.74134)
			(xy 3.065393 -48.699322) (xy 3.087878 -48.681132) (xy 3.096634 -48.673565) (xy 3.106817 -48.65281)
			(xy 3.107436 -48.641254) (xy 3.107436 -48.56099) (xy 3.106894 -48.549418) (xy 3.096681 -48.528646)
			(xy 3.087878 -48.521112) (xy 3.065396 -48.50292) (xy 3.025661 -48.4609) (xy 2.992723 -48.413365)
			(xy 2.967335 -48.361404) (xy 2.950078 -48.306207) (xy 2.941348 -48.249038) (xy 2.940812 -48.220122)
			(xy 2.941298 -48.192871) (xy 2.949054 -48.138923) (xy 2.964409 -48.086628) (xy 2.987051 -48.037051)
			(xy 3.016517 -47.991201) (xy 3.052208 -47.95001) (xy 3.093399 -47.914319) (xy 3.139249 -47.884853)
			(xy 3.188826 -47.862211) (xy 3.241121 -47.846856) (xy 3.295069 -47.8391) (xy 3.349571 -47.8391) (xy 3.403519 -47.846856)
			(xy 3.455814 -47.862211) (xy 3.505391 -47.884853) (xy 3.551241 -47.914319) (xy 3.592432 -47.95001)
			(xy 3.628123 -47.991201) (xy 3.657589 -48.037051) (xy 3.680231 -48.086628) (xy 3.695586 -48.138923)
			(xy 3.703342 -48.192871) (xy 3.703828 -48.220122) (xy 3.703281 -48.249038) (xy 3.694562 -48.306209)
			(xy 3.677311 -48.361409) (xy 3.651925 -48.413371) (xy 3.618985 -48.460905) (xy 3.579246 -48.502922)
			(xy 3.556762 -48.521112) (xy 3.547993 -48.528667) (xy 3.537815 -48.549431) (xy 3.537204 -48.56099)
			(xy 3.537204 -48.641254) (xy 3.537799 -48.652819) (xy 3.547976 -48.67359) (xy 3.556762 -48.681132)
			(xy 3.579242 -48.699327) (xy 3.618977 -48.741346) (xy 3.651917 -48.78888) (xy 3.677306 -48.840841)
			(xy 3.694563 -48.896037) (xy 3.703293 -48.953206) (xy 3.703828 -48.982122) (xy 3.703342 -49.009373)
			(xy 3.695586 -49.063321) (xy 3.680231 -49.115616) (xy 3.657589 -49.165193) (xy 3.628123 -49.211043)
			(xy 3.592432 -49.252234) (xy 3.551241 -49.287925) (xy 3.505391 -49.317391) (xy 3.455814 -49.340033)
			(xy 3.403519 -49.355388) (xy 3.349571 -49.363144) (xy 3.295069 -49.363144) (xy 3.241121 -49.355388)
			(xy 3.188826 -49.340033) (xy 3.139249 -49.317391) (xy 3.093399 -49.287925) (xy 3.052208 -49.252234)
			(xy 3.016517 -49.211043) (xy 2.987051 -49.165193) (xy 2.964409 -49.115616) (xy 2.949054 -49.063321)
			(xy 2.941298 -49.009373) (xy 2.940812 -48.982122) (xy 1.27 -48.982122) (xy 1.27 -51.217322) (xy 3.067812 -51.217322)
			(xy 3.068342 -51.188405) (xy 3.077068 -51.131235) (xy 3.094323 -51.076036) (xy 3.119713 -51.024074)
			(xy 3.152654 -50.97654) (xy 3.192393 -50.934522) (xy 3.214878 -50.916332) (xy 3.223634 -50.908765)
			(xy 3.233817 -50.88801) (xy 3.234436 -50.876454) (xy 3.234436 -50.79619) (xy 3.233894 -50.784618)
			(xy 3.223681 -50.763846) (xy 3.214878 -50.756312) (xy 3.192396 -50.73812) (xy 3.152661 -50.6961)
			(xy 3.119723 -50.648565) (xy 3.094335 -50.596604) (xy 3.077078 -50.541407) (xy 3.068348 -50.484238)
			(xy 3.067812 -50.455322) (xy 3.068298 -50.428071) (xy 3.076054 -50.374123) (xy 3.091409 -50.321828)
			(xy 3.114051 -50.272251) (xy 3.143517 -50.226401) (xy 3.179208 -50.18521) (xy 3.220399 -50.149519)
			(xy 3.266249 -50.120053) (xy 3.315826 -50.097411) (xy 3.368121 -50.082056) (xy 3.422069 -50.0743)
			(xy 3.476571 -50.0743) (xy 3.530519 -50.082056) (xy 3.582814 -50.097411) (xy 3.632391 -50.120053)
			(xy 3.678241 -50.149519) (xy 3.719432 -50.18521) (xy 3.755123 -50.226401) (xy 3.784589 -50.272251)
			(xy 3.807231 -50.321828) (xy 3.822586 -50.374123) (xy 3.830342 -50.428071) (xy 3.830828 -50.455322)
			(xy 3.830281 -50.484238) (xy 3.821562 -50.541409) (xy 3.804311 -50.596609) (xy 3.778925 -50.648571)
			(xy 3.745985 -50.696105) (xy 3.706246 -50.738122) (xy 3.683762 -50.756312) (xy 3.674993 -50.763867)
			(xy 3.664815 -50.784631) (xy 3.664204 -50.79619) (xy 3.664204 -50.876454) (xy 3.664799 -50.888019)
			(xy 3.674976 -50.90879) (xy 3.683762 -50.916332) (xy 3.706242 -50.934527) (xy 3.745977 -50.976546)
			(xy 3.778917 -51.02408) (xy 3.804306 -51.076041) (xy 3.821563 -51.131237) (xy 3.830293 -51.188406)
			(xy 3.830828 -51.217322) (xy 3.830342 -51.244573) (xy 3.822586 -51.298521) (xy 3.807231 -51.350816)
			(xy 3.784589 -51.400393) (xy 3.755123 -51.446243) (xy 3.719432 -51.487434) (xy 3.678241 -51.523125)
			(xy 3.632391 -51.552591) (xy 3.582814 -51.575233) (xy 3.530519 -51.590588) (xy 3.476571 -51.598344)
			(xy 3.422069 -51.598344) (xy 3.368121 -51.590588) (xy 3.315826 -51.575233) (xy 3.266249 -51.552591)
			(xy 3.220399 -51.523125) (xy 3.179208 -51.487434) (xy 3.143517 -51.446243) (xy 3.114051 -51.400393)
			(xy 3.091409 -51.350816) (xy 3.076054 -51.298521) (xy 3.068298 -51.244573) (xy 3.067812 -51.217322)
			(xy 1.27 -51.217322) (xy 1.27 -53.347112) (xy 3.375406 -53.347112) (xy 3.375931 -53.318195) (xy 3.384658 -53.261024)
			(xy 3.401915 -53.205826) (xy 3.427305 -53.153864) (xy 3.460248 -53.10633) (xy 3.499987 -53.064312)
			(xy 3.522472 -53.046122) (xy 3.531231 -53.038559) (xy 3.541413 -53.0178) (xy 3.54203 -53.006244)
			(xy 3.54203 -52.92598) (xy 3.541438 -52.914414) (xy 3.531261 -52.893641) (xy 3.522472 -52.886102)
			(xy 3.499984 -52.867917) (xy 3.46025 -52.825895) (xy 3.427312 -52.778359) (xy 3.401925 -52.726396)
			(xy 3.38467 -52.671198) (xy 3.375941 -52.614028) (xy 3.375406 -52.585112) (xy 3.375892 -52.557861)
			(xy 3.383648 -52.503913) (xy 3.399003 -52.451618) (xy 3.421645 -52.402041) (xy 3.451111 -52.356191)
			(xy 3.486802 -52.315) (xy 3.527993 -52.279309) (xy 3.573843 -52.249843) (xy 3.62342 -52.227201) (xy 3.675715 -52.211846)
			(xy 3.729663 -52.20409) (xy 3.784165 -52.20409) (xy 3.838113 -52.211846) (xy 3.890408 -52.227201)
			(xy 3.939985 -52.249843) (xy 3.985835 -52.279309) (xy 4.027026 -52.315) (xy 4.062717 -52.356191)
			(xy 4.092183 -52.402041) (xy 4.114825 -52.451618) (xy 4.13018 -52.503913) (xy 4.137936 -52.557861)
			(xy 4.138422 -52.585112) (xy 4.13787 -52.614028) (xy 4.129152 -52.671199) (xy 4.111903 -52.726398)
			(xy 4.086518 -52.778361) (xy 4.053578 -52.825895) (xy 4.01384 -52.867912) (xy 3.991356 -52.886102)
			(xy 3.98259 -52.89366) (xy 3.972411 -52.914422) (xy 3.971798 -52.92598) (xy 3.971798 -53.006244)
			(xy 3.972402 -53.017807) (xy 3.982573 -53.038579) (xy 3.991356 -53.046122) (xy 4.013837 -53.064316)
			(xy 4.053572 -53.106335) (xy 4.086511 -53.15387) (xy 4.1119 -53.20583) (xy 4.129157 -53.261027) (xy 4.137887 -53.318196)
			(xy 4.138422 -53.347112) (xy 4.137936 -53.374363) (xy 4.13018 -53.428311) (xy 4.12419 -53.448712)
			(xy 6.525006 -53.448712) (xy 6.525592 -53.402316) (xy 6.535236 -53.310028) (xy 6.554431 -53.219244)
			(xy 6.582968 -53.130951) (xy 6.601206 -53.088286) (xy 6.605103 -53.078362) (xy 6.605108 -53.05706)
			(xy 6.601206 -53.047138) (xy 6.582966 -53.004474) (xy 6.554421 -52.916182) (xy 6.535226 -52.825398)
			(xy 6.525592 -52.733108) (xy 6.525006 -52.686712) (xy 6.52551 -52.644364) (xy 6.533561 -52.56005)
			(xy 6.54959 -52.476884) (xy 6.573451 -52.395617) (xy 6.60493 -52.316987) (xy 6.643741 -52.241706)
			(xy 6.689531 -52.170454) (xy 6.741887 -52.103878) (xy 6.800335 -52.04258) (xy 6.864345 -51.987115)
			(xy 6.933337 -51.937986) (xy 7.006687 -51.895637) (xy 7.08373 -51.860453) (xy 7.163769 -51.832751)
			(xy 7.246078 -51.812783) (xy 7.329913 -51.80073) (xy 7.414514 -51.7967) (xy 7.499115 -51.80073) (xy 7.58295 -51.812783)
			(xy 7.665259 -51.832751) (xy 7.745298 -51.860453) (xy 7.822341 -51.895637) (xy 7.895691 -51.937986)
			(xy 7.964683 -51.987115) (xy 8.028693 -52.04258) (xy 8.087141 -52.103878) (xy 8.139497 -52.170454)
			(xy 8.185287 -52.241706) (xy 8.224098 -52.316987) (xy 8.255577 -52.395617) (xy 8.279438 -52.476884)
			(xy 8.295467 -52.56005) (xy 8.303518 -52.644364) (xy 8.304022 -52.686712) (xy 8.303442 -52.733108)
			(xy 8.293796 -52.825396) (xy 8.274599 -52.91618) (xy 8.24606 -53.004473) (xy 8.227822 -53.047138)
			(xy 8.223909 -53.057058) (xy 8.223914 -53.078364) (xy 8.227822 -53.088286) (xy 8.246072 -53.130946)
			(xy 8.274614 -53.219239) (xy 8.293806 -53.310025) (xy 8.303438 -53.402316) (xy 8.304022 -53.448712)
			(xy 8.303518 -53.49106) (xy 8.295467 -53.575374) (xy 8.279438 -53.65854) (xy 8.255577 -53.739807)
			(xy 8.224098 -53.818437) (xy 8.185287 -53.893718) (xy 8.139497 -53.96497) (xy 8.087141 -54.031546)
			(xy 8.028693 -54.092844) (xy 7.964683 -54.148309) (xy 7.895691 -54.197438) (xy 7.822341 -54.239787)
			(xy 7.745298 -54.274971) (xy 7.665259 -54.302673) (xy 7.58295 -54.322641) (xy 7.499115 -54.334694)
			(xy 7.414514 -54.338725) (xy 7.329913 -54.334694) (xy 7.246078 -54.322641) (xy 7.163769 -54.302673)
			(xy 7.08373 -54.274971) (xy 7.006687 -54.239787) (xy 6.933337 -54.197438) (xy 6.864345 -54.148309)
			(xy 6.800335 -54.092844) (xy 6.741887 -54.031546) (xy 6.689531 -53.96497) (xy 6.643741 -53.893718)
			(xy 6.60493 -53.818437) (xy 6.573451 -53.739807) (xy 6.54959 -53.65854) (xy 6.533561 -53.575374)
			(xy 6.52551 -53.49106) (xy 6.525006 -53.448712) (xy 4.12419 -53.448712) (xy 4.114825 -53.480606)
			(xy 4.092183 -53.530183) (xy 4.062717 -53.576033) (xy 4.027026 -53.617224) (xy 3.985835 -53.652915)
			(xy 3.939985 -53.682381) (xy 3.890408 -53.705023) (xy 3.838113 -53.720378) (xy 3.784165 -53.728134)
			(xy 3.729663 -53.728134) (xy 3.675715 -53.720378) (xy 3.62342 -53.705023) (xy 3.573843 -53.682381)
			(xy 3.527993 -53.652915) (xy 3.486802 -53.617224) (xy 3.451111 -53.576033) (xy 3.421645 -53.530183)
			(xy 3.399003 -53.480606) (xy 3.383648 -53.428311) (xy 3.375892 -53.374363) (xy 3.375406 -53.347112)
			(xy 1.27 -53.347112) (xy 1.27 -58.913776) (xy 2.81559 -58.913776) (xy 2.816029 -58.875488) (xy 2.822649 -58.799198)
			(xy 2.835796 -58.723758) (xy 2.855371 -58.649726) (xy 2.867914 -58.613548) (xy 2.870567 -58.605113)
			(xy 2.870559 -58.587442) (xy 2.867914 -58.579004) (xy 2.855351 -58.542832) (xy 2.835756 -58.468802)
			(xy 2.822607 -58.39336) (xy 2.816 -58.317066) (xy 2.81559 -58.278776) (xy 2.816044 -58.237673) (xy 2.823631 -58.155818)
			(xy 2.838738 -58.075013) (xy 2.861236 -57.995946) (xy 2.890934 -57.919292) (xy 2.927578 -57.845705)
			(xy 2.970854 -57.775813) (xy 3.020395 -57.710212) (xy 3.075778 -57.649462) (xy 3.136529 -57.594081)
			(xy 3.202131 -57.544542) (xy 3.272024 -57.501267) (xy 3.345612 -57.464625) (xy 3.422267 -57.434929)
			(xy 3.501334 -57.412433) (xy 3.58214 -57.397328) (xy 3.663995 -57.389743) (xy 3.705098 -57.389268)
			(xy 3.74403 -57.389697) (xy 3.821594 -57.396535) (xy 3.898262 -57.410133) (xy 3.973446 -57.430385)
			(xy 4.010152 -57.44337) (xy 4.018701 -57.446134) (xy 4.036655 -57.446134) (xy 4.045204 -57.44337)
			(xy 4.081909 -57.430385) (xy 4.157097 -57.410148) (xy 4.233764 -57.396554) (xy 4.311326 -57.389707)
			(xy 4.350258 -57.389268) (xy 4.38919 -57.389709) (xy 4.466753 -57.396543) (xy 4.543421 -57.410138)
			(xy 4.618606 -57.430387) (xy 4.655312 -57.44337) (xy 4.663861 -57.446134) (xy 4.681815 -57.446134)
			(xy 4.690364 -57.44337) (xy 4.727073 -57.430397) (xy 4.802259 -57.410156) (xy 4.878926 -57.396559)
			(xy 4.956487 -57.389709) (xy 4.995418 -57.389268) (xy 5.03652 -57.389749) (xy 5.118374 -57.397333)
			(xy 5.199179 -57.412438) (xy 5.278246 -57.434934) (xy 5.3549 -57.46463) (xy 5.428486 -57.501271)
			(xy 5.498378 -57.544546) (xy 5.563979 -57.594086) (xy 5.624729 -57.649466) (xy 5.680111 -57.710216)
			(xy 5.72965 -57.775817) (xy 5.772926 -57.845708) (xy 5.809568 -57.919295) (xy 5.839264 -57.995948)
			(xy 5.861761 -58.075015) (xy 5.876866 -58.15582) (xy 5.884451 -58.237674) (xy 5.884926 -58.278776)
			(xy 5.884501 -58.317064) (xy 5.877877 -58.393355) (xy 5.864726 -58.468794) (xy 5.845147 -58.542827)
			(xy 5.832602 -58.579004) (xy 5.829972 -58.587445) (xy 5.829964 -58.60511) (xy 5.832602 -58.613548)
			(xy 5.839714 -58.633614) (xy 5.84454 -58.648092) (xy 5.868162 -58.666888) (xy 5.991098 -58.678064)
			(xy 6.017768 -58.66384) (xy 6.025134 -58.650632) (xy 6.046384 -58.612989) (xy 6.095134 -58.541597)
			(xy 6.15058 -58.475271) (xy 6.212199 -58.414638) (xy 6.27941 -58.360268) (xy 6.351579 -58.312676)
			(xy 6.428024 -58.272309) (xy 6.508026 -58.23955) (xy 6.590827 -58.214706) (xy 6.675649 -58.198013)
			(xy 6.76169 -58.189627) (xy 6.804914 -58.189114) (xy 6.843846 -58.189535) (xy 6.92141 -58.196375)
			(xy 6.998078 -58.209975) (xy 7.073263 -58.23023) (xy 7.109968 -58.243216) (xy 7.118517 -58.24598)
			(xy 7.136471 -58.24598) (xy 7.14502 -58.243216) (xy 7.181732 -58.230253) (xy 7.256917 -58.21001)
			(xy 7.333583 -58.19641) (xy 7.411143 -58.189556) (xy 7.450074 -58.189114) (xy 7.489006 -58.189547)
			(xy 7.56657 -58.196384) (xy 7.643238 -58.20998) (xy 7.718422 -58.230232) (xy 7.755128 -58.243216)
			(xy 7.763677 -58.24598) (xy 7.781631 -58.24598) (xy 7.79018 -58.243216) (xy 7.826886 -58.230236)
			(xy 7.902074 -58.209998) (xy 7.978741 -58.196402) (xy 8.056303 -58.189554) (xy 8.095234 -58.189114)
			(xy 8.136337 -58.189583) (xy 8.218191 -58.197168) (xy 8.298997 -58.212274) (xy 8.378064 -58.23477)
			(xy 8.454718 -58.264467) (xy 8.528305 -58.301109) (xy 8.598197 -58.344385) (xy 8.663798 -58.393925)
			(xy 8.724548 -58.449306) (xy 8.750624 -58.47791) (xy 9.058409 -58.47791) (xy 9.06244 -58.393309)
			(xy 9.074493 -58.309475) (xy 9.094461 -58.227165) (xy 9.122163 -58.147127) (xy 9.157347 -58.070084)
			(xy 9.199695 -57.996735) (xy 9.248824 -57.927743) (xy 9.304288 -57.863733) (xy 9.365586 -57.805286)
			(xy 9.432162 -57.75293) (xy 9.503414 -57.707139) (xy 9.578695 -57.668329) (xy 9.657325 -57.63685)
			(xy 9.73859 -57.612988) (xy 9.821756 -57.596959) (xy 9.90607 -57.588908) (xy 9.948418 -57.588404)
			(xy 9.994814 -57.588979) (xy 10.087102 -57.598627) (xy 10.177886 -57.617825) (xy 10.266179 -57.646365)
			(xy 10.308844 -57.664604) (xy 10.318784 -57.668424) (xy 10.340052 -57.668424) (xy 10.349992 -57.664604)
			(xy 10.392652 -57.646354) (xy 10.480945 -57.617811) (xy 10.571731 -57.59862) (xy 10.664022 -57.588988)
			(xy 10.710418 -57.588404) (xy 10.75201 -57.588898) (xy 10.834832 -57.596655) (xy 10.916568 -57.612109)
			(xy 10.996504 -57.635126) (xy 11.073943 -57.665503) (xy 11.148208 -57.702977) (xy 11.218651 -57.74722)
			(xy 11.284657 -57.797844) (xy 11.345649 -57.854409) (xy 11.401094 -57.916421) (xy 11.42619 -57.949592)
			(xy 11.433302 -57.959498) (xy 11.454892 -57.97042) (xy 11.561064 -57.970166) (xy 11.582654 -57.959244)
			(xy 11.589766 -57.949338) (xy 11.614802 -57.915872) (xy 11.67025 -57.853328) (xy 11.731321 -57.796261)
			(xy 11.797476 -57.745175) (xy 11.868131 -57.700519) (xy 11.942663 -57.662688) (xy 12.020416 -57.632016)
			(xy 12.100703 -57.608772) (xy 12.182816 -57.593162) (xy 12.266032 -57.585324) (xy 12.307824 -57.584848)
			(xy 12.354219 -57.585453) (xy 12.446507 -57.595091) (xy 12.537291 -57.61428) (xy 12.625585 -57.642813)
			(xy 12.66825 -57.661048) (xy 12.67819 -57.664868) (xy 12.699458 -57.664868) (xy 12.709398 -57.661048)
			(xy 12.752058 -57.642799) (xy 12.840351 -57.614255) (xy 12.931137 -57.595063) (xy 13.023428 -57.585432)
			(xy 13.069824 -57.584848) (xy 13.116219 -57.585453) (xy 13.208507 -57.595091) (xy 13.299291 -57.61428)
			(xy 13.387585 -57.642813) (xy 13.43025 -57.661048) (xy 13.44019 -57.664868) (xy 13.461458 -57.664868)
			(xy 13.471398 -57.661048) (xy 13.514058 -57.642799) (xy 13.602351 -57.614255) (xy 13.693137 -57.595063)
			(xy 13.785428 -57.585432) (xy 13.831824 -57.584848) (xy 13.872926 -57.585323) (xy 13.954781 -57.592908)
			(xy 14.035586 -57.608013) (xy 14.114652 -57.63051) (xy 14.191306 -57.660206) (xy 14.264893 -57.696848)
			(xy 14.334785 -57.740124) (xy 14.400386 -57.789663) (xy 14.461136 -57.845044) (xy 14.516517 -57.905794)
			(xy 14.566056 -57.971395) (xy 14.609332 -58.041287) (xy 14.645974 -58.114874) (xy 14.67567 -58.191528)
			(xy 14.698167 -58.270594) (xy 14.713272 -58.351399) (xy 14.720857 -58.433254) (xy 14.721332 -58.474356)
			(xy 14.720914 -58.51413) (xy 14.713826 -58.593361) (xy 14.699686 -58.671642) (xy 14.678607 -58.748345)
			(xy 14.650756 -58.822858) (xy 14.633956 -58.858912) (xy 14.629432 -58.869587) (xy 14.629555 -58.892744)
			(xy 14.63421 -58.903362) (xy 14.651954 -58.940222) (xy 14.681378 -59.016561) (xy 14.703673 -59.095277)
			(xy 14.718651 -59.175707) (xy 14.726187 -59.257172) (xy 14.726666 -59.298078) (xy 14.726227 -59.339182)
			(xy 14.718643 -59.42104) (xy 14.703539 -59.501848) (xy 14.681043 -59.580918) (xy 14.651346 -59.657575)
			(xy 14.614703 -59.731165) (xy 14.571426 -59.80106) (xy 14.521884 -59.866663) (xy 14.466501 -59.927415)
			(xy 14.405747 -59.982797) (xy 14.340143 -60.032337) (xy 14.270247 -60.075613) (xy 14.196657 -60.112254)
			(xy 14.119999 -60.141949) (xy 14.040929 -60.164443) (xy 13.96012 -60.179546) (xy 13.878262 -60.187128)
			(xy 13.837158 -60.187586) (xy 13.790763 -60.186985) (xy 13.698475 -60.177345) (xy 13.607691 -60.158155)
			(xy 13.519397 -60.129621) (xy 13.476732 -60.111386) (xy 13.466792 -60.107566) (xy 13.445524 -60.107566)
			(xy 13.435584 -60.111386) (xy 13.392927 -60.129643) (xy 13.304633 -60.158184) (xy 13.213846 -60.177374)
			(xy 13.121555 -60.187003) (xy 13.075158 -60.187586) (xy 13.028763 -60.186985) (xy 12.936475 -60.177345)
			(xy 12.845691 -60.158155) (xy 12.757397 -60.129621) (xy 12.714732 -60.111386) (xy 12.704792 -60.107566)
			(xy 12.683524 -60.107566) (xy 12.673584 -60.111386) (xy 12.630927 -60.129643) (xy 12.542633 -60.158184)
			(xy 12.451846 -60.177374) (xy 12.359555 -60.187003) (xy 12.313158 -60.187586) (xy 12.272055 -60.187115)
			(xy 12.190201 -60.17953) (xy 12.109395 -60.164425) (xy 12.030329 -60.141928) (xy 11.953675 -60.112232)
			(xy 11.880088 -60.07559) (xy 11.810195 -60.032314) (xy 11.744594 -59.982774) (xy 11.683844 -59.927393)
			(xy 11.628463 -59.866643) (xy 11.578923 -59.801041) (xy 11.535648 -59.731149) (xy 11.499006 -59.657562)
			(xy 11.469311 -59.580908) (xy 11.446814 -59.501841) (xy 11.431709 -59.421035) (xy 11.424125 -59.339181)
			(xy 11.42365 -59.298078) (xy 11.424412 -59.261248) (xy 11.42492 -59.246262) (xy 11.410188 -59.220862)
			(xy 11.301222 -59.165236) (xy 11.272012 -59.16803) (xy 11.260074 -59.177174) (xy 11.22651 -59.202979)
			(xy 11.155282 -59.248757) (xy 11.080025 -59.287555) (xy 11.00142 -59.319022) (xy 10.92018 -59.342874)
			(xy 10.83704 -59.358893) (xy 10.752753 -59.366935) (xy 10.710418 -59.36742) (xy 10.664023 -59.36683)
			(xy 10.571734 -59.357187) (xy 10.480951 -59.337993) (xy 10.392657 -59.309457) (xy 10.349992 -59.29122)
			(xy 10.340052 -59.2874) (xy 10.318784 -59.2874) (xy 10.308844 -59.29122) (xy 10.26618 -59.30946)
			(xy 10.177888 -59.338005) (xy 10.087104 -59.357199) (xy 9.994814 -59.366834) (xy 9.948418 -59.36742)
			(xy 9.90607 -59.366912) (xy 9.821756 -59.358861) (xy 9.73859 -59.342832) (xy 9.657325 -59.31897)
			(xy 9.578695 -59.287491) (xy 9.503414 -59.248681) (xy 9.432162 -59.20289) (xy 9.365586 -59.150534)
			(xy 9.304288 -59.092087) (xy 9.248824 -59.028077) (xy 9.199695 -58.959085) (xy 9.157347 -58.885736)
			(xy 9.122163 -58.808693) (xy 9.094461 -58.728655) (xy 9.074493 -58.646345) (xy 9.06244 -58.562511)
			(xy 9.058409 -58.47791) (xy 8.750624 -58.47791) (xy 8.779929 -58.510057) (xy 8.829469 -58.575658)
			(xy 8.872744 -58.645551) (xy 8.909386 -58.719138) (xy 8.939081 -58.795792) (xy 8.961578 -58.874859)
			(xy 8.976683 -58.955665) (xy 8.984267 -59.037519) (xy 8.984742 -59.078622) (xy 8.9843 -59.11691)
			(xy 8.977681 -59.1932) (xy 8.964535 -59.26864) (xy 8.944961 -59.342672) (xy 8.932418 -59.37885) (xy 8.929765 -59.387285)
			(xy 8.929772 -59.404956) (xy 8.932418 -59.413394) (xy 8.944982 -59.449566) (xy 8.964576 -59.523596)
			(xy 8.977725 -59.599038) (xy 8.984332 -59.675332) (xy 8.984742 -59.713622) (xy 8.984265 -59.754724)
			(xy 8.97668 -59.836579) (xy 8.961575 -59.917384) (xy 8.939079 -59.99645) (xy 8.909383 -60.073104)
			(xy 8.872741 -60.146691) (xy 8.829466 -60.216583) (xy 8.779926 -60.282184) (xy 8.724545 -60.342934)
			(xy 8.663795 -60.398315) (xy 8.598194 -60.447854) (xy 8.528302 -60.49113) (xy 8.454716 -60.527772)
			(xy 8.378062 -60.557468) (xy 8.298996 -60.579965) (xy 8.218191 -60.59507) (xy 8.136336 -60.602655)
			(xy 8.095234 -60.60313) (xy 8.055664 -60.602722) (xy 7.976836 -60.595712) (xy 7.898942 -60.581726)
			(xy 7.822599 -60.560875) (xy 7.785354 -60.547504) (xy 7.776687 -60.544664) (xy 7.758461 -60.544664)
			(xy 7.749794 -60.547504) (xy 7.712552 -60.560882) (xy 7.636207 -60.581726) (xy 7.558312 -60.595706)
			(xy 7.479484 -60.602711) (xy 7.439914 -60.60313) (xy 7.401626 -60.602708) (xy 7.325335 -60.596082)
			(xy 7.249895 -60.582931) (xy 7.175863 -60.563352) (xy 7.139686 -60.550806) (xy 7.131248 -60.548164)
			(xy 7.11358 -60.548164) (xy 7.105142 -60.550806) (xy 7.068976 -60.563388) (xy 6.994943 -60.582977)
			(xy 6.919499 -60.596121) (xy 6.843204 -60.602723) (xy 6.804914 -60.60313) (xy 6.763811 -60.602664)
			(xy 6.681956 -60.595079) (xy 6.601149 -60.579974) (xy 6.522081 -60.557478) (xy 6.445426 -60.527782)
			(xy 6.371838 -60.49114) (xy 6.301945 -60.447864) (xy 6.236343 -60.398324) (xy 6.175592 -60.342943)
			(xy 6.12021 -60.282192) (xy 6.070669 -60.21659) (xy 6.027393 -60.146697) (xy 5.99075 -60.073109)
			(xy 5.961054 -59.996455) (xy 5.938557 -59.917387) (xy 5.923451 -59.83658) (xy 5.915866 -59.754725)
			(xy 5.915406 -59.713622) (xy 5.915829 -59.675334) (xy 5.922453 -59.599043) (xy 5.935604 -59.523603)
			(xy 5.955184 -59.449571) (xy 5.96773 -59.413394) (xy 5.970359 -59.404953) (xy 5.970367 -59.387288)
			(xy 5.96773 -59.37885) (xy 5.960618 -59.358784) (xy 5.955792 -59.344306) (xy 5.93217 -59.32551) (xy 5.809234 -59.314334)
			(xy 5.782564 -59.328558) (xy 5.775198 -59.341766) (xy 5.753923 -59.379395) (xy 5.705176 -59.450787)
			(xy 5.649732 -59.517112) (xy 5.588116 -59.577746) (xy 5.520907 -59.632117) (xy 5.448741 -59.67971)
			(xy 5.372298 -59.720078) (xy 5.2923 -59.752839) (xy 5.2095 -59.777685) (xy 5.124681 -59.794381) (xy 5.038641 -59.802769)
			(xy 4.995418 -59.803284) (xy 4.955849 -59.802847) (xy 4.877021 -59.795845) (xy 4.799127 -59.781867)
			(xy 4.722783 -59.761025) (xy 4.685538 -59.747658) (xy 4.676871 -59.744818) (xy 4.658645 -59.744818)
			(xy 4.649978 -59.747658) (xy 4.612728 -59.761014) (xy 4.536386 -59.781864) (xy 4.458494 -59.79585)
			(xy 4.379667 -59.802861) (xy 4.340098 -59.803284) (xy 4.30181 -59.80284) (xy 4.22552 -59.796221)
			(xy 4.15008 -59.783077) (xy 4.076048 -59.763503) (xy 4.03987 -59.75096) (xy 4.031432 -59.748318)
			(xy 4.013764 -59.748318) (xy 4.005326 -59.75096) (xy 3.969151 -59.763516) (xy 3.895122 -59.783113)
			(xy 3.819681 -59.796264) (xy 3.743387 -59.802873) (xy 3.705098 -59.803284) (xy 3.663995 -59.80283)
			(xy 3.582139 -59.795244) (xy 3.501332 -59.780139) (xy 3.422264 -59.757642) (xy 3.345608 -59.727945)
			(xy 3.27202 -59.691302) (xy 3.202127 -59.648026) (xy 3.136524 -59.598485) (xy 3.075773 -59.543103)
			(xy 3.020391 -59.482351) (xy 2.970851 -59.416748) (xy 2.927575 -59.346855) (xy 2.890933 -59.273266)
			(xy 2.861236 -59.196611) (xy 2.83874 -59.117542) (xy 2.823635 -59.036735) (xy 2.81605 -58.954879)
			(xy 2.81559 -58.913776) (xy 1.27 -58.913776) (xy 1.27 -61.345064) (xy 2.005582 -61.345064) (xy 2.009653 -61.289442)
			(xy 2.021779 -61.235005) (xy 2.041702 -61.182914) (xy 2.068998 -61.134279) (xy 2.103084 -61.090136)
			(xy 2.143233 -61.051427) (xy 2.188591 -61.018976) (xy 2.238191 -60.993475) (xy 2.290975 -60.975468)
			(xy 2.345818 -60.965338) (xy 2.401552 -60.963301) (xy 2.456989 -60.969401) (xy 2.510946 -60.983507)
			(xy 2.562275 -61.005319) (xy 2.609881 -61.034373) (xy 2.652749 -61.070048) (xy 2.689966 -61.111585)
			(xy 2.720739 -61.158098) (xy 2.744411 -61.208595) (xy 2.760479 -61.262002) (xy 2.768599 -61.317178)
			(xy 2.769108 -61.345064) (xy 2.768599 -61.37295) (xy 2.760479 -61.428126) (xy 2.744411 -61.481533)
			(xy 2.720739 -61.53203) (xy 2.689966 -61.578543) (xy 2.652749 -61.62008) (xy 2.609881 -61.655755)
			(xy 2.562275 -61.684809) (xy 2.510946 -61.706621) (xy 2.456989 -61.720727) (xy 2.401552 -61.726827)
			(xy 2.345818 -61.72479) (xy 2.290975 -61.71466) (xy 2.238191 -61.696653) (xy 2.188591 -61.671152)
			(xy 2.143233 -61.638701) (xy 2.103084 -61.599992) (xy 2.068998 -61.555849) (xy 2.041702 -61.507214)
			(xy 2.021779 -61.455123) (xy 2.009653 -61.400686) (xy 2.005582 -61.345064) (xy 1.27 -61.345064) (xy 1.27 -62.5221)
			(xy 5.249162 -62.5221) (xy 5.253233 -62.466478) (xy 5.265359 -62.412041) (xy 5.285282 -62.35995)
			(xy 5.312578 -62.311315) (xy 5.346664 -62.267172) (xy 5.386813 -62.228463) (xy 5.432171 -62.196012)
			(xy 5.481771 -62.170511) (xy 5.534555 -62.152504) (xy 5.589398 -62.142374) (xy 5.645132 -62.140337)
			(xy 5.700569 -62.146437) (xy 5.754526 -62.160543) (xy 5.805855 -62.182355) (xy 5.853461 -62.211409)
			(xy 5.896329 -62.247084) (xy 5.933546 -62.288621) (xy 5.964319 -62.335134) (xy 5.987991 -62.385631)
			(xy 6.004059 -62.439038) (xy 6.012179 -62.494214) (xy 6.012688 -62.5221) (xy 6.012179 -62.549986)
			(xy 6.004059 -62.605162) (xy 5.987991 -62.658569) (xy 5.964319 -62.709066) (xy 5.933546 -62.755579)
			(xy 5.896329 -62.797116) (xy 5.853461 -62.832791) (xy 5.805855 -62.861845) (xy 5.754526 -62.883657)
			(xy 5.700569 -62.897763) (xy 5.645132 -62.903863) (xy 5.589398 -62.901826) (xy 5.534555 -62.891696)
			(xy 5.481771 -62.873689) (xy 5.432171 -62.848188) (xy 5.386813 -62.815737) (xy 5.346664 -62.777028)
			(xy 5.312578 -62.732885) (xy 5.285282 -62.68425) (xy 5.265359 -62.632159) (xy 5.253233 -62.577722)
			(xy 5.249162 -62.5221) (xy 1.27 -62.5221) (xy 1.27 -62.946863) (xy 3.375865 -62.946863) (xy 3.375865 -62.892357)
			(xy 3.383622 -62.838406) (xy 3.398979 -62.786108) (xy 3.421621 -62.736527) (xy 3.45109 -62.690674)
			(xy 3.486784 -62.649481) (xy 3.527977 -62.613787) (xy 3.573831 -62.58432) (xy 3.623411 -62.561677)
			(xy 3.67571 -62.546322) (xy 3.729661 -62.538565) (xy 3.756914 -62.538102) (xy 3.78588 -62.53865)
			(xy 3.843144 -62.547417) (xy 3.898426 -62.564739) (xy 3.950453 -62.590219) (xy 3.998031 -62.623271)
			(xy 4.040066 -62.663135) (xy 4.075592 -62.708896) (xy 4.090162 -62.733936) (xy 4.09701 -62.7454)
			(xy 4.115606 -62.764552) (xy 4.138527 -62.778236) (xy 4.16421 -62.785516) (xy 4.190902 -62.785897)
			(xy 4.216782 -62.779351) (xy 4.240084 -62.766327) (xy 4.249928 -62.757304) (xy 4.271431 -62.737029)
			(xy 4.319557 -62.702727) (xy 4.372396 -62.676258) (xy 4.428686 -62.658253) (xy 4.487079 -62.649144)
			(xy 4.516628 -62.648592) (xy 4.543881 -62.649055) (xy 4.597832 -62.656812) (xy 4.65013 -62.672168)
			(xy 4.699711 -62.69481) (xy 4.745564 -62.724278) (xy 4.786757 -62.759972) (xy 4.822451 -62.801164)
			(xy 4.851919 -62.847018) (xy 4.874562 -62.896598) (xy 4.889918 -62.948896) (xy 4.897675 -63.002847)
			(xy 4.897675 -63.057353) (xy 4.889918 -63.111304) (xy 4.881841 -63.138812) (xy 6.106412 -63.138812)
			(xy 6.110483 -63.08319) (xy 6.122609 -63.028753) (xy 6.142532 -62.976662) (xy 6.169828 -62.928027)
			(xy 6.203914 -62.883884) (xy 6.244063 -62.845175) (xy 6.289421 -62.812724) (xy 6.339021 -62.787223)
			(xy 6.391805 -62.769216) (xy 6.446648 -62.759086) (xy 6.502382 -62.757049) (xy 6.557819 -62.763149)
			(xy 6.611776 -62.777255) (xy 6.663105 -62.799067) (xy 6.710711 -62.828121) (xy 6.753579 -62.863796)
			(xy 6.790796 -62.905333) (xy 6.821569 -62.951846) (xy 6.845241 -63.002343) (xy 6.861309 -63.05575)
			(xy 6.869429 -63.110926) (xy 6.869938 -63.138812) (xy 6.869429 -63.166698) (xy 6.861309 -63.221874)
			(xy 6.845241 -63.275281) (xy 6.821569 -63.325778) (xy 6.790796 -63.372291) (xy 6.753579 -63.413828)
			(xy 6.710711 -63.449503) (xy 6.663105 -63.478557) (xy 6.611776 -63.500369) (xy 6.557819 -63.514475)
			(xy 6.502382 -63.520575) (xy 6.446648 -63.518538) (xy 6.391805 -63.508408) (xy 6.339021 -63.490401)
			(xy 6.289421 -63.4649) (xy 6.244063 -63.432449) (xy 6.203914 -63.39374) (xy 6.169828 -63.349597)
			(xy 6.142532 -63.300962) (xy 6.122609 -63.248871) (xy 6.110483 -63.194434) (xy 6.106412 -63.138812)
			(xy 4.881841 -63.138812) (xy 4.874562 -63.163602) (xy 4.851919 -63.213182) (xy 4.822451 -63.259036)
			(xy 4.786757 -63.300228) (xy 4.745564 -63.335922) (xy 4.699711 -63.36539) (xy 4.65013 -63.388032)
			(xy 4.597832 -63.403388) (xy 4.543881 -63.411145) (xy 4.516628 -63.411608) (xy 4.487663 -63.411051)
			(xy 4.430399 -63.402284) (xy 4.375119 -63.384962) (xy 4.323092 -63.359483) (xy 4.275514 -63.326433)
			(xy 4.233479 -63.286571) (xy 4.197951 -63.240813) (xy 4.18338 -63.215774) (xy 4.176478 -63.204345)
			(xy 4.157894 -63.185194) (xy 4.134984 -63.171508) (xy 4.109311 -63.164224) (xy 4.082627 -63.163837)
			(xy 4.056754 -63.170373) (xy 4.033457 -63.183388) (xy 4.023614 -63.192406) (xy 4.002095 -63.212663)
			(xy 3.953973 -63.246966) (xy 3.901138 -63.273439) (xy 3.844852 -63.291448) (xy 3.786462 -63.300563)
			(xy 3.756914 -63.301118) (xy 3.729661 -63.300655) (xy 3.67571 -63.292898) (xy 3.623411 -63.277543)
			(xy 3.573831 -63.2549) (xy 3.527977 -63.225433) (xy 3.486784 -63.189739) (xy 3.45109 -63.148546)
			(xy 3.421621 -63.102693) (xy 3.398979 -63.053112) (xy 3.383622 -63.000814) (xy 3.375865 -62.946863)
			(xy 1.27 -62.946863) (xy 1.27 -67.894962) (xy 2.157982 -67.894962) (xy 2.162053 -67.83934) (xy 2.174179 -67.784903)
			(xy 2.194102 -67.732812) (xy 2.221398 -67.684177) (xy 2.255484 -67.640034) (xy 2.295633 -67.601325)
			(xy 2.340991 -67.568874) (xy 2.390591 -67.543373) (xy 2.443375 -67.525366) (xy 2.498218 -67.515236)
			(xy 2.553952 -67.513199) (xy 2.609389 -67.519299) (xy 2.663346 -67.533405) (xy 2.714675 -67.555217)
			(xy 2.762281 -67.584271) (xy 2.805149 -67.619946) (xy 2.842366 -67.661483) (xy 2.873139 -67.707996)
			(xy 2.896811 -67.758493) (xy 2.912879 -67.8119) (xy 2.920999 -67.867076) (xy 2.921508 -67.894962)
			(xy 2.920999 -67.922848) (xy 2.917739 -67.945) (xy 4.178044 -67.945) (xy 4.182115 -67.889378) (xy 4.194241 -67.834941)
			(xy 4.214164 -67.78285) (xy 4.24146 -67.734215) (xy 4.275546 -67.690072) (xy 4.315695 -67.651363)
			(xy 4.361053 -67.618912) (xy 4.410653 -67.593411) (xy 4.463437 -67.575404) (xy 4.51828 -67.565274)
			(xy 4.574014 -67.563237) (xy 4.629451 -67.569337) (xy 4.683408 -67.583443) (xy 4.734737 -67.605255)
			(xy 4.782343 -67.634309) (xy 4.825211 -67.669984) (xy 4.862428 -67.711521) (xy 4.893201 -67.758034)
			(xy 4.916873 -67.808531) (xy 4.932941 -67.861938) (xy 4.941061 -67.917114) (xy 4.94157 -67.945) (xy 5.078982 -67.945)
			(xy 5.083053 -67.889378) (xy 5.095179 -67.834941) (xy 5.115102 -67.78285) (xy 5.142398 -67.734215)
			(xy 5.176484 -67.690072) (xy 5.216633 -67.651363) (xy 5.261991 -67.618912) (xy 5.311591 -67.593411)
			(xy 5.364375 -67.575404) (xy 5.419218 -67.565274) (xy 5.474952 -67.563237) (xy 5.530389 -67.569337)
			(xy 5.584346 -67.583443) (xy 5.635675 -67.605255) (xy 5.683281 -67.634309) (xy 5.726149 -67.669984)
			(xy 5.763366 -67.711521) (xy 5.794139 -67.758034) (xy 5.817811 -67.808531) (xy 5.833879 -67.861938)
			(xy 5.841999 -67.917114) (xy 5.842508 -67.945) (xy 5.841999 -67.972886) (xy 5.833879 -68.028062)
			(xy 5.817811 -68.081469) (xy 5.794139 -68.131966) (xy 5.763366 -68.178479) (xy 5.726149 -68.220016)
			(xy 5.683281 -68.255691) (xy 5.635675 -68.284745) (xy 5.584346 -68.306557) (xy 5.530389 -68.320663)
			(xy 5.474952 -68.326763) (xy 5.419218 -68.324726) (xy 5.364375 -68.314596) (xy 5.311591 -68.296589)
			(xy 5.261991 -68.271088) (xy 5.216633 -68.238637) (xy 5.176484 -68.199928) (xy 5.142398 -68.155785)
			(xy 5.115102 -68.10715) (xy 5.095179 -68.055059) (xy 5.083053 -68.000622) (xy 5.078982 -67.945) (xy 4.94157 -67.945)
			(xy 4.941061 -67.972886) (xy 4.932941 -68.028062) (xy 4.916873 -68.081469) (xy 4.893201 -68.131966)
			(xy 4.862428 -68.178479) (xy 4.825211 -68.220016) (xy 4.782343 -68.255691) (xy 4.734737 -68.284745)
			(xy 4.683408 -68.306557) (xy 4.629451 -68.320663) (xy 4.574014 -68.326763) (xy 4.51828 -68.324726)
			(xy 4.463437 -68.314596) (xy 4.410653 -68.296589) (xy 4.361053 -68.271088) (xy 4.315695 -68.238637)
			(xy 4.275546 -68.199928) (xy 4.24146 -68.155785) (xy 4.214164 -68.10715) (xy 4.194241 -68.055059)
			(xy 4.182115 -68.000622) (xy 4.178044 -67.945) (xy 2.917739 -67.945) (xy 2.912879 -67.978024) (xy 2.896811 -68.031431)
			(xy 2.873139 -68.081928) (xy 2.842366 -68.128441) (xy 2.805149 -68.169978) (xy 2.762281 -68.205653)
			(xy 2.714675 -68.234707) (xy 2.663346 -68.256519) (xy 2.609389 -68.270625) (xy 2.553952 -68.276725)
			(xy 2.498218 -68.274688) (xy 2.443375 -68.264558) (xy 2.390591 -68.246551) (xy 2.340991 -68.22105)
			(xy 2.295633 -68.188599) (xy 2.255484 -68.14989) (xy 2.221398 -68.105747) (xy 2.194102 -68.057112)
			(xy 2.174179 -68.005021) (xy 2.162053 -67.950584) (xy 2.157982 -67.894962) (xy 1.27 -67.894962) (xy 1.27 -70.475856)
			(xy 1.270417 -70.485907) (xy 1.278114 -70.504475) (xy 1.292347 -70.518668) (xy 1.301496 -70.522846)
			(xy 1.315974 -70.528688) (xy 1.345692 -70.522846) (xy 2.3368 -69.531738) (xy 2.340102 -69.526404)
			(xy 2.354993 -69.502614) (xy 2.390654 -69.459277) (xy 2.432278 -69.421631) (xy 2.478967 -69.390486)
			(xy 2.529713 -69.366516) (xy 2.583423 -69.350236) (xy 2.638939 -69.341997) (xy 2.667 -69.341492)
			(xy 2.69468 -69.341983) (xy 2.749458 -69.349981) (xy 2.802505 -69.365816) (xy 2.852704 -69.389156)
			(xy 2.899 -69.419509) (xy 2.940421 -69.456237) (xy 2.976095 -69.49857) (xy 2.991104 -69.521832) (xy 2.997454 -69.531992)
			(xy 3.016758 -69.544184) (xy 3.10769 -69.554598) (xy 3.119153 -69.55538) (xy 3.140833 -69.547837)
			(xy 3.149346 -69.54012) (xy 3.481324 -69.208396) (xy 3.502174 -69.188271) (xy 3.549024 -69.15417)
			(xy 3.600633 -69.12782) (xy 3.655729 -69.109869) (xy 3.712955 -69.10076) (xy 3.741928 -69.100192)
			(xy 4.660646 -69.100192) (xy 4.67061 -69.099709) (xy 4.689038 -69.092126) (xy 4.69646 -69.08546)
			(xy 5.028184 -68.753736) (xy 5.035585 -68.746899) (xy 5.054184 -68.739189) (xy 5.064252 -68.73875)
			(xy 6.129274 -68.73875) (xy 6.139337 -68.739188) (xy 6.157917 -68.746927) (xy 6.165342 -68.753736)
			(xy 6.497066 -69.08546) (xy 6.504472 -69.092154) (xy 6.522908 -69.099755) (xy 6.53288 -69.100192)
			(xy 6.674358 -69.100192) (xy 6.68331 -69.099838) (xy 6.700122 -69.093682) (xy 6.713806 -69.082135)
			(xy 6.718554 -69.074538) (xy 6.7691 -68.985892) (xy 6.768846 -68.958714) (xy 6.761734 -68.946776)
			(xy 6.749002 -68.924557) (xy 6.72895 -68.877437) (xy 6.715378 -68.828058) (xy 6.70853 -68.777309)
			(xy 6.70814 -68.751704) (xy 6.708626 -68.724453) (xy 6.716382 -68.670505) (xy 6.731737 -68.61821)
			(xy 6.754379 -68.568633) (xy 6.783845 -68.522783) (xy 6.819536 -68.481592) (xy 6.860727 -68.445901)
			(xy 6.906577 -68.416435) (xy 6.956154 -68.393793) (xy 7.008449 -68.378438) (xy 7.062397 -68.370682)
			(xy 7.116899 -68.370682) (xy 7.170847 -68.378438) (xy 7.223142 -68.393793) (xy 7.272719 -68.416435)
			(xy 7.318569 -68.445901) (xy 7.35976 -68.481592) (xy 7.395451 -68.522783) (xy 7.424917 -68.568633)
			(xy 7.447559 -68.61821) (xy 7.462914 -68.670505) (xy 7.47067 -68.724453) (xy 7.471156 -68.751704)
			(xy 7.470643 -68.779375) (xy 7.462615 -68.834131) (xy 7.44677 -68.887156) (xy 7.423441 -68.937341)
			(xy 7.408672 -68.960746) (xy 7.402068 -68.970906) (xy 7.399274 -68.994782) (xy 7.436612 -69.094604)
			(xy 7.454392 -69.11086) (xy 7.466076 -69.114162) (xy 7.496107 -69.123306) (xy 7.552749 -69.150363)
			(xy 7.603987 -69.186626) (xy 7.626604 -69.208396) (xy 7.848092 -69.429884) (xy 7.85547 -69.436697)
			(xy 7.874 -69.444399) (xy 7.894066 -69.444399) (xy 7.912596 -69.436697) (xy 7.919974 -69.429884)
			(xy 7.925562 -69.424296) (xy 7.932674 -69.41058) (xy 7.934198 -69.402706) (xy 7.939786 -69.376798)
			(xy 7.941056 -69.370702) (xy 7.941056 -68.123562) (xy 7.941614 -68.094588) (xy 7.95072 -68.037359)
			(xy 7.96867 -67.982261) (xy 7.995021 -67.93065) (xy 8.029124 -67.883799) (xy 8.04926 -67.862958)
			(xy 8.37946 -67.532504) (xy 8.386149 -67.525096) (xy 8.393739 -67.50666) (xy 8.394192 -67.49669)
			(xy 8.394192 -66.748152) (xy 8.393477 -66.7359) (xy 8.382203 -66.714141) (xy 8.372602 -66.706496)
			(xy 8.29437 -66.651632) (xy 8.269732 -66.64833) (xy 8.258048 -66.652648) (xy 8.226595 -66.663295)
			(xy 8.161199 -66.674784) (xy 8.128 -66.675508) (xy 8.100749 -66.675022) (xy 8.046801 -66.667266)
			(xy 7.994506 -66.651911) (xy 7.944929 -66.629269) (xy 7.899079 -66.599803) (xy 7.857888 -66.564112)
			(xy 7.822197 -66.522921) (xy 7.792731 -66.477071) (xy 7.770089 -66.427494) (xy 7.754734 -66.375199)
			(xy 7.746978 -66.321251) (xy 7.746978 -66.266749) (xy 7.754734 -66.212801) (xy 7.770089 -66.160506)
			(xy 7.792731 -66.110929) (xy 7.822197 -66.065079) (xy 7.857888 -66.023888) (xy 7.899079 -65.988197)
			(xy 7.944929 -65.958731) (xy 7.994506 -65.936089) (xy 8.046801 -65.920734) (xy 8.100749 -65.912978)
			(xy 8.128 -65.912492) (xy 8.161199 -65.913208) (xy 8.226595 -65.924702) (xy 8.258048 -65.935352)
			(xy 8.269732 -65.93967) (xy 8.29437 -65.936368) (xy 8.372602 -65.881504) (xy 8.382237 -65.873885)
			(xy 8.393521 -65.852113) (xy 8.394192 -65.839848) (xy 8.394192 -63.07455) (xy 8.393709 -63.064587)
			(xy 8.386124 -63.046159) (xy 8.37946 -63.038736) (xy 8.019542 -62.678564) (xy 8.012281 -62.671911)
			(xy 7.994171 -62.664223) (xy 7.974498 -62.663935) (xy 7.965186 -62.667134) (xy 7.864348 -62.70625)
			(xy 7.846822 -62.73038) (xy 7.84606 -62.74562) (xy 7.844373 -62.772007) (xy 7.834631 -62.823974)
			(xy 7.817807 -62.8741) (xy 7.794223 -62.921422) (xy 7.764333 -62.965035) (xy 7.728707 -63.004104)
			(xy 7.688028 -63.037881) (xy 7.643076 -63.065717) (xy 7.594711 -63.087081) (xy 7.54386 -63.101564)
			(xy 7.491496 -63.108887) (xy 7.46506 -63.109348) (xy 7.43781 -63.10886) (xy 7.383864 -63.101099)
			(xy 7.331572 -63.08574) (xy 7.281997 -63.063098) (xy 7.236149 -63.033631) (xy 7.19496 -62.99794)
			(xy 7.159269 -62.956751) (xy 7.129802 -62.910903) (xy 7.10716 -62.861328) (xy 7.091801 -62.809036)
			(xy 7.08404 -62.75509) (xy 7.083552 -62.72784) (xy 7.084112 -62.69817) (xy 7.09329 -62.639544) (xy 7.111432 -62.583044)
			(xy 7.1381 -62.530034) (xy 7.154926 -62.50559) (xy 7.163562 -62.493652) (xy 7.165594 -62.465712)
			(xy 7.117588 -62.37224) (xy 7.112928 -62.364189) (xy 7.099037 -62.351839) (xy 7.081669 -62.34522)
			(xy 7.072376 -62.344808) (xy 7.043928 -62.344808) (xy 7.033966 -62.345295) (xy 7.015544 -62.352885)
			(xy 7.008114 -62.35954) (xy 6.97992 -62.387734) (xy 6.97611 -62.399164) (xy 6.967276 -62.424122)
			(xy 6.94369 -62.471521) (xy 6.913783 -62.515208) (xy 6.878127 -62.554344) (xy 6.837408 -62.58818)
			(xy 6.792404 -62.616067) (xy 6.74398 -62.637469) (xy 6.693064 -62.651977) (xy 6.640631 -62.659313)
			(xy 6.61416 -62.659768) (xy 6.586912 -62.659279) (xy 6.53297 -62.651518) (xy 6.480683 -62.636159)
			(xy 6.431113 -62.613515) (xy 6.385271 -62.584047) (xy 6.344089 -62.548355) (xy 6.308405 -62.507165)
			(xy 6.278947 -62.461316) (xy 6.256313 -62.411742) (xy 6.240965 -62.359451) (xy 6.233215 -62.305508)
			(xy 6.232652 -62.27826) (xy 6.233264 -62.246483) (xy 6.243728 -62.183796) (xy 6.25348 -62.153546)
			(xy 6.255004 -62.148466) (xy 6.26127 -62.123569) (xy 6.279766 -62.075678) (xy 6.304732 -62.030818)
			(xy 6.335684 -61.989859) (xy 6.353556 -61.971428) (xy 6.609588 -61.715396) (xy 6.630437 -61.695269)
			(xy 6.677286 -61.661163) (xy 6.728895 -61.634808) (xy 6.783991 -61.616852) (xy 6.841218 -61.607737)
			(xy 6.870192 -61.607192) (xy 7.838186 -61.607192) (xy 7.867158 -61.607754) (xy 7.924382 -61.616867)
			(xy 7.979475 -61.634823) (xy 8.031079 -61.661181) (xy 8.077922 -61.69529) (xy 8.09879 -61.715396)
			(xy 8.571547 -62.188153) (xy 9.567367 -62.188153) (xy 9.567367 -62.133647) (xy 9.575125 -62.079696)
			(xy 9.590481 -62.027399) (xy 9.613124 -61.977819) (xy 9.642593 -61.931966) (xy 9.678287 -61.890775)
			(xy 9.719481 -61.855082) (xy 9.765335 -61.825615) (xy 9.814916 -61.802975) (xy 9.867214 -61.787621)
			(xy 9.921165 -61.779866) (xy 9.948418 -61.779404) (xy 9.977333 -61.77998) (xy 10.034501 -61.788696)
			(xy 10.089699 -61.805943) (xy 10.141661 -61.831324) (xy 10.189197 -61.864257) (xy 10.231216 -61.903989)
			(xy 10.249408 -61.92647) (xy 10.256959 -61.935243) (xy 10.277726 -61.945417) (xy 10.289286 -61.946028)
			(xy 10.36955 -61.946028) (xy 10.381118 -61.945454) (xy 10.401891 -61.935264) (xy 10.409428 -61.92647)
			(xy 10.427596 -61.903967) (xy 10.469621 -61.864234) (xy 10.517161 -61.831298) (xy 10.569127 -61.805914)
			(xy 10.624328 -61.788661) (xy 10.681501 -61.779937) (xy 10.710418 -61.779404) (xy 10.737669 -61.779867)
			(xy 10.791617 -61.787626) (xy 10.843911 -61.802983) (xy 10.893487 -61.825626) (xy 10.939337 -61.855094)
			(xy 10.980526 -61.890786) (xy 11.016217 -61.931977) (xy 11.045683 -61.977828) (xy 11.068323 -62.027406)
			(xy 11.083678 -62.079701) (xy 11.091434 -62.133649) (xy 11.091434 -62.188151) (xy 11.083678 -62.242099)
			(xy 11.068323 -62.294394) (xy 11.045683 -62.343972) (xy 11.016217 -62.389823) (xy 10.980526 -62.431014)
			(xy 10.939337 -62.466706) (xy 10.893487 -62.496174) (xy 10.843911 -62.518817) (xy 10.791617 -62.534174)
			(xy 10.737829 -62.54191) (xy 12.055609 -62.54191) (xy 12.05964 -62.457309) (xy 12.071693 -62.373475)
			(xy 12.091661 -62.291165) (xy 12.119363 -62.211127) (xy 12.154547 -62.134084) (xy 12.196895 -62.060735)
			(xy 12.246024 -61.991743) (xy 12.301488 -61.927733) (xy 12.362786 -61.869286) (xy 12.429362 -61.81693)
			(xy 12.500614 -61.771139) (xy 12.575895 -61.732329) (xy 12.654525 -61.70085) (xy 12.73579 -61.676988)
			(xy 12.818956 -61.660959) (xy 12.90327 -61.652908) (xy 12.945618 -61.652404) (xy 12.992014 -61.652979)
			(xy 13.084302 -61.662627) (xy 13.175086 -61.681825) (xy 13.263379 -61.710365) (xy 13.306044 -61.728604)
			(xy 13.315984 -61.732424) (xy 13.337252 -61.732424) (xy 13.347192 -61.728604) (xy 13.389852 -61.710354)
			(xy 13.478145 -61.681811) (xy 13.568931 -61.66262) (xy 13.661222 -61.652988) (xy 13.707618 -61.652404)
			(xy 13.754014 -61.652979) (xy 13.846302 -61.662627) (xy 13.937086 -61.681825) (xy 14.025379 -61.710365)
			(xy 14.068044 -61.728604) (xy 14.077984 -61.732424) (xy 14.099252 -61.732424) (xy 14.109192 -61.728604)
			(xy 14.151852 -61.710354) (xy 14.240145 -61.681811) (xy 14.330931 -61.66262) (xy 14.423222 -61.652988)
			(xy 14.469618 -61.652404) (xy 14.511967 -61.652888) (xy 14.596283 -61.660939) (xy 14.679451 -61.676968)
			(xy 14.760719 -61.70083) (xy 14.839351 -61.73231) (xy 14.914634 -61.771121) (xy 14.985887 -61.816912)
			(xy 15.052465 -61.869269) (xy 15.113764 -61.927718) (xy 15.16923 -61.991729) (xy 15.21836 -62.060723)
			(xy 15.26071 -62.134074) (xy 15.295895 -62.211119) (xy 15.323597 -62.291159) (xy 15.343566 -62.37347)
			(xy 15.35562 -62.457307) (xy 15.35965 -62.54191) (xy 15.35562 -62.626513) (xy 15.343566 -62.71035)
			(xy 15.323597 -62.792661) (xy 15.295895 -62.872701) (xy 15.26071 -62.949746) (xy 15.21836 -63.023097)
			(xy 15.16923 -63.092091) (xy 15.113764 -63.156102) (xy 15.052465 -63.214551) (xy 14.985887 -63.266908)
			(xy 14.914634 -63.312699) (xy 14.839351 -63.35151) (xy 14.760719 -63.38299) (xy 14.679451 -63.406852)
			(xy 14.596283 -63.422881) (xy 14.511967 -63.430932) (xy 14.469618 -63.43142) (xy 14.423223 -63.43083)
			(xy 14.330934 -63.421187) (xy 14.240151 -63.401993) (xy 14.151857 -63.373457) (xy 14.109192 -63.35522)
			(xy 14.099252 -63.3514) (xy 14.077984 -63.3514) (xy 14.068044 -63.35522) (xy 14.02538 -63.37346)
			(xy 13.937088 -63.402005) (xy 13.846304 -63.421199) (xy 13.754014 -63.430834) (xy 13.707618 -63.43142)
			(xy 13.661223 -63.43083) (xy 13.568934 -63.421187) (xy 13.478151 -63.401993) (xy 13.389857 -63.373457)
			(xy 13.347192 -63.35522) (xy 13.337252 -63.3514) (xy 13.315984 -63.3514) (xy 13.306044 -63.35522)
			(xy 13.26338 -63.37346) (xy 13.175088 -63.402005) (xy 13.084304 -63.421199) (xy 12.992014 -63.430834)
			(xy 12.945618 -63.43142) (xy 12.90327 -63.430912) (xy 12.818956 -63.422861) (xy 12.73579 -63.406832)
			(xy 12.654525 -63.38297) (xy 12.575895 -63.351491) (xy 12.500614 -63.312681) (xy 12.429362 -63.26689)
			(xy 12.362786 -63.214534) (xy 12.301488 -63.156087) (xy 12.246024 -63.092077) (xy 12.196895 -63.023085)
			(xy 12.154547 -62.949736) (xy 12.119363 -62.872693) (xy 12.091661 -62.792655) (xy 12.071693 -62.710345)
			(xy 12.05964 -62.626511) (xy 12.055609 -62.54191) (xy 10.737829 -62.54191) (xy 10.737669 -62.541933)
			(xy 10.710418 -62.54242) (xy 10.6815 -62.541919) (xy 10.624327 -62.533191) (xy 10.569126 -62.515931)
			(xy 10.517164 -62.490537) (xy 10.469631 -62.457589) (xy 10.427616 -62.417842) (xy 10.409428 -62.395354)
			(xy 10.401857 -62.386602) (xy 10.381105 -62.376415) (xy 10.36955 -62.375796) (xy 10.289286 -62.375796)
			(xy 10.277717 -62.37636) (xy 10.256947 -62.386559) (xy 10.249408 -62.395354) (xy 10.231226 -62.417845)
			(xy 10.189203 -62.457577) (xy 10.141666 -62.490514) (xy 10.089703 -62.5159) (xy 10.034504 -62.533156)
			(xy 9.977334 -62.541885) (xy 9.948418 -62.54242) (xy 9.921165 -62.541934) (xy 9.867214 -62.534179)
			(xy 9.814916 -62.518825) (xy 9.765335 -62.496185) (xy 9.719481 -62.466718) (xy 9.678287 -62.431025)
			(xy 9.642593 -62.389834) (xy 9.613124 -62.343981) (xy 9.590481 -62.294401) (xy 9.575125 -62.242104)
			(xy 9.567367 -62.188153) (xy 8.571547 -62.188153) (xy 9.023604 -62.64021) (xy 9.04373 -62.66106)
			(xy 9.077833 -62.70791) (xy 9.104185 -62.759518) (xy 9.122138 -62.814614) (xy 9.131249 -62.871841)
			(xy 9.131808 -62.900814) (xy 9.131808 -62.910466) (xy 9.132222 -62.920491) (xy 9.139886 -62.939018)
			(xy 9.15406 -62.9532) (xy 9.172583 -62.960873) (xy 9.182608 -62.961266) (xy 9.193784 -62.961266)
			(xy 9.204198 -62.95644) (xy 9.229841 -62.944823) (xy 9.283694 -62.928419) (xy 9.339373 -62.920114)
			(xy 9.36752 -62.91961) (xy 9.394771 -62.920096) (xy 9.448719 -62.927852) (xy 9.501014 -62.943208)
			(xy 9.550592 -62.965849) (xy 9.596443 -62.995315) (xy 9.637633 -63.031007) (xy 9.673325 -63.072197)
			(xy 9.702791 -63.118048) (xy 9.725432 -63.167626) (xy 9.740788 -63.219921) (xy 9.748544 -63.273869)
			(xy 9.748544 -63.328371) (xy 9.740788 -63.382319) (xy 9.725432 -63.434614) (xy 9.702791 -63.484192)
			(xy 9.673325 -63.530043) (xy 9.637633 -63.571233) (xy 9.596443 -63.606925) (xy 9.550592 -63.636391)
			(xy 9.501014 -63.659032) (xy 9.448719 -63.674388) (xy 9.394771 -63.682144) (xy 9.36752 -63.682626)
			(xy 9.340676 -63.682171) (xy 9.287517 -63.674653) (xy 9.261602 -63.66764) (xy 9.249918 -63.664338)
			(xy 9.22655 -63.668402) (xy 9.151874 -63.724536) (xy 9.142844 -63.732178) (xy 9.132377 -63.753361)
			(xy 9.131808 -63.765176) (xy 9.131808 -63.82258) (xy 10.364468 -63.82258) (xy 10.368539 -63.766958)
			(xy 10.380665 -63.712521) (xy 10.400588 -63.66043) (xy 10.427884 -63.611795) (xy 10.46197 -63.567652)
			(xy 10.502119 -63.528943) (xy 10.547477 -63.496492) (xy 10.597077 -63.470991) (xy 10.649861 -63.452984)
			(xy 10.704704 -63.442854) (xy 10.760438 -63.440817) (xy 10.815875 -63.446917) (xy 10.869832 -63.461023)
			(xy 10.921161 -63.482835) (xy 10.968767 -63.511889) (xy 11.011635 -63.547564) (xy 11.048852 -63.589101)
			(xy 11.079625 -63.635614) (xy 11.103297 -63.686111) (xy 11.119365 -63.739518) (xy 11.127485 -63.794694)
			(xy 11.127994 -63.82258) (xy 11.127485 -63.850466) (xy 11.119365 -63.905642) (xy 11.103297 -63.959049)
			(xy 11.079625 -64.009546) (xy 11.048852 -64.056059) (xy 11.011635 -64.097596) (xy 10.968767 -64.133271)
			(xy 10.921161 -64.162325) (xy 10.869832 -64.184137) (xy 10.815875 -64.198243) (xy 10.760438 -64.204343)
			(xy 10.704704 -64.202306) (xy 10.649861 -64.192176) (xy 10.597077 -64.174169) (xy 10.547477 -64.148668)
			(xy 10.502119 -64.116217) (xy 10.46197 -64.077508) (xy 10.427884 -64.033365) (xy 10.400588 -63.98473)
			(xy 10.380665 -63.932639) (xy 10.368539 -63.878202) (xy 10.364468 -63.82258) (xy 9.131808 -63.82258)
			(xy 9.131808 -65.843912) (xy 12.86891 -65.843912) (xy 12.86938 -65.816338) (xy 12.877332 -65.761765)
			(xy 12.893055 -65.708905) (xy 12.916225 -65.658859) (xy 12.946356 -65.612669) (xy 12.982823 -65.571298)
			(xy 13.00353 -65.553082) (xy 13.011657 -65.545487) (xy 13.021005 -65.52533) (xy 13.021564 -65.51422)
			(xy 13.021564 -65.437004) (xy 13.021021 -65.425891) (xy 13.011666 -65.405732) (xy 13.00353 -65.398142)
			(xy 12.982842 -65.379906) (xy 12.946369 -65.338543) (xy 12.916233 -65.292359) (xy 12.893063 -65.242315)
			(xy 12.877342 -65.189457) (xy 12.869398 -65.134885) (xy 12.86891 -65.107312) (xy 12.869367 -65.080059)
			(xy 12.877122 -65.026107) (xy 12.892478 -64.973807) (xy 12.91512 -64.924226) (xy 12.944589 -64.878372)
			(xy 12.980283 -64.837179) (xy 13.021477 -64.801485) (xy 13.067331 -64.772017) (xy 13.116913 -64.749376)
			(xy 13.169212 -64.734021) (xy 13.223165 -64.726266) (xy 13.250418 -64.725804) (xy 13.279333 -64.72638)
			(xy 13.336501 -64.735096) (xy 13.391699 -64.752343) (xy 13.443661 -64.777724) (xy 13.491197 -64.810657)
			(xy 13.533216 -64.850389) (xy 13.551408 -64.87287) (xy 13.558959 -64.881643) (xy 13.579726 -64.891817)
			(xy 13.591286 -64.892428) (xy 13.67155 -64.892428) (xy 13.683118 -64.891854) (xy 13.703891 -64.881664)
			(xy 13.711428 -64.87287) (xy 13.728181 -64.852087) (xy 13.766535 -64.814957) (xy 13.809689 -64.783535)
			(xy 13.856803 -64.758436) (xy 13.906955 -64.74015) (xy 13.959166 -64.729033) (xy 14.012418 -64.725303)
			(xy 14.06567 -64.729033) (xy 14.117881 -64.74015) (xy 14.168033 -64.758436) (xy 14.215147 -64.783535)
			(xy 14.258301 -64.814957) (xy 14.296655 -64.852087) (xy 14.313408 -64.87287) (xy 14.320959 -64.881643)
			(xy 14.341726 -64.891817) (xy 14.353286 -64.892428) (xy 14.43355 -64.892428) (xy 14.445118 -64.891854)
			(xy 14.465891 -64.881664) (xy 14.473428 -64.87287) (xy 14.490181 -64.852087) (xy 14.528535 -64.814957)
			(xy 14.571689 -64.783535) (xy 14.618803 -64.758436) (xy 14.668955 -64.74015) (xy 14.721166 -64.729033)
			(xy 14.774418 -64.725303) (xy 14.82767 -64.729033) (xy 14.879881 -64.74015) (xy 14.930033 -64.758436)
			(xy 14.977147 -64.783535) (xy 15.020301 -64.814957) (xy 15.058655 -64.852087) (xy 15.075408 -64.87287)
			(xy 15.082959 -64.881643) (xy 15.103726 -64.891817) (xy 15.115286 -64.892428) (xy 15.19555 -64.892428)
			(xy 15.207118 -64.891854) (xy 15.227891 -64.881664) (xy 15.235428 -64.87287) (xy 15.253596 -64.850367)
			(xy 15.295621 -64.810634) (xy 15.343161 -64.777698) (xy 15.395127 -64.752314) (xy 15.450328 -64.735061)
			(xy 15.507501 -64.726337) (xy 15.536418 -64.725804) (xy 15.56367 -64.726261) (xy 15.61762 -64.73402)
			(xy 15.669916 -64.749378) (xy 15.719494 -64.772022) (xy 15.765345 -64.801492) (xy 15.806535 -64.837186)
			(xy 15.842226 -64.878379) (xy 15.871692 -64.924233) (xy 15.894332 -64.973813) (xy 15.909686 -65.02611)
			(xy 15.917441 -65.08006) (xy 15.917926 -65.107312) (xy 15.917391 -65.134884) (xy 15.909451 -65.189453)
			(xy 15.893739 -65.242311) (xy 15.870582 -65.292358) (xy 15.840462 -65.338549) (xy 15.804007 -65.379924)
			(xy 15.783306 -65.398142) (xy 15.775174 -65.405732) (xy 15.765827 -65.425893) (xy 15.765272 -65.437004)
			(xy 15.765272 -65.51422) (xy 15.76579 -65.525337) (xy 15.775161 -65.545496) (xy 15.783306 -65.553082)
			(xy 15.804013 -65.571298) (xy 15.840483 -65.612666) (xy 15.870616 -65.658855) (xy 15.893782 -65.708902)
			(xy 15.9095 -65.761763) (xy 15.91744 -65.816338) (xy 15.917926 -65.843912) (xy 15.917433 -65.871163)
			(xy 15.909676 -65.925109) (xy 15.89432 -65.977403) (xy 15.871679 -66.026979) (xy 15.842213 -66.072828)
			(xy 15.806522 -66.114018) (xy 15.765333 -66.149709) (xy 15.719484 -66.179176) (xy 15.669908 -66.201818)
			(xy 15.617615 -66.217174) (xy 15.563669 -66.224933) (xy 15.536418 -66.22542) (xy 15.5075 -66.224919)
			(xy 15.450327 -66.216191) (xy 15.395126 -66.198931) (xy 15.343164 -66.173537) (xy 15.295631 -66.140589)
			(xy 15.253616 -66.100842) (xy 15.235428 -66.078354) (xy 15.227857 -66.069602) (xy 15.207105 -66.059415)
			(xy 15.19555 -66.058796) (xy 15.115286 -66.058796) (xy 15.103717 -66.05936) (xy 15.082947 -66.069559)
			(xy 15.075408 -66.078354) (xy 15.058655 -66.099137) (xy 15.020301 -66.136267) (xy 14.977147 -66.167689)
			(xy 14.930033 -66.192788) (xy 14.879881 -66.211074) (xy 14.82767 -66.222191) (xy 14.774418 -66.225921)
			(xy 14.721166 -66.222191) (xy 14.668955 -66.211074) (xy 14.618803 -66.192788) (xy 14.571689 -66.167689)
			(xy 14.528535 -66.136267) (xy 14.490181 -66.099137) (xy 14.473428 -66.078354) (xy 14.465857 -66.069602)
			(xy 14.445105 -66.059415) (xy 14.43355 -66.058796) (xy 14.353286 -66.058796) (xy 14.341717 -66.05936)
			(xy 14.320947 -66.069559) (xy 14.313408 -66.078354) (xy 14.296655 -66.099137) (xy 14.258301 -66.136267)
			(xy 14.215147 -66.167689) (xy 14.168033 -66.192788) (xy 14.117881 -66.211074) (xy 14.06567 -66.222191)
			(xy 14.012418 -66.225921) (xy 13.959166 -66.222191) (xy 13.906955 -66.211074) (xy 13.856803 -66.192788)
			(xy 13.809689 -66.167689) (xy 13.766535 -66.136267) (xy 13.728181 -66.099137) (xy 13.711428 -66.078354)
			(xy 13.703857 -66.069602) (xy 13.683105 -66.059415) (xy 13.67155 -66.058796) (xy 13.591286 -66.058796)
			(xy 13.579717 -66.05936) (xy 13.558947 -66.069559) (xy 13.551408 -66.078354) (xy 13.533226 -66.100845)
			(xy 13.491203 -66.140577) (xy 13.443666 -66.173514) (xy 13.391703 -66.1989) (xy 13.336504 -66.216156)
			(xy 13.279334 -66.224885) (xy 13.250418 -66.22542) (xy 13.223166 -66.224928) (xy 13.169217 -66.217174)
			(xy 13.11692 -66.201821) (xy 13.067341 -66.179181) (xy 13.021488 -66.149716) (xy 12.980296 -66.114025)
			(xy 12.944602 -66.072836) (xy 12.915133 -66.026985) (xy 12.89249 -65.977408) (xy 12.877133 -65.925112)
			(xy 12.869374 -65.871164) (xy 12.86891 -65.843912) (xy 9.131808 -65.843912) (xy 9.131808 -67.670426)
			(xy 9.131251 -67.6994) (xy 9.122146 -67.756629) (xy 9.104196 -67.811728) (xy 9.077844 -67.863338)
			(xy 9.043739 -67.910188) (xy 9.023604 -67.93103) (xy 8.693404 -68.261484) (xy 8.686717 -68.268893)
			(xy 8.679128 -68.287329) (xy 8.678672 -68.297298) (xy 8.678672 -69.370702) (xy 8.679942 -69.376798)
			(xy 8.682817 -69.388541) (xy 8.687262 -69.412308) (xy 8.688832 -69.424296) (xy 8.690356 -69.439028)
			(xy 8.708644 -69.46138) (xy 8.808974 -69.496178) (xy 8.81808 -69.498938) (xy 8.83708 -69.498229)
			(xy 8.854518 -69.49065) (xy 8.861552 -69.48424) (xy 10.415524 -67.930014) (xy 10.422886 -67.921888)
			(xy 10.430509 -67.901353) (xy 10.430256 -67.89039) (xy 10.42416 -67.80276) (xy 10.413746 -67.78371)
			(xy 10.404602 -67.776852) (xy 10.38132 -67.758714) (xy 10.340112 -67.716467) (xy 10.305903 -67.668377)
			(xy 10.279512 -67.61559) (xy 10.261568 -67.559368) (xy 10.2525 -67.501052) (xy 10.251948 -67.471544)
			(xy 10.252434 -67.444293) (xy 10.26019 -67.390345) (xy 10.275545 -67.33805) (xy 10.298187 -67.288473)
			(xy 10.327653 -67.242623) (xy 10.363344 -67.201432) (xy 10.404535 -67.165741) (xy 10.450385 -67.136275)
			(xy 10.499962 -67.113633) (xy 10.552257 -67.098278) (xy 10.606205 -67.090522) (xy 10.660707 -67.090522)
			(xy 10.714655 -67.098278) (xy 10.76695 -67.113633) (xy 10.816527 -67.136275) (xy 10.862377 -67.165741)
			(xy 10.903568 -67.201432) (xy 10.939259 -67.242623) (xy 10.968725 -67.288473) (xy 10.991367 -67.33805)
			(xy 11.006722 -67.390345) (xy 11.014478 -67.444293) (xy 11.014964 -67.471544) (xy 11.014261 -67.504339)
			(xy 11.003025 -67.568962) (xy 10.992612 -67.600068) (xy 10.988548 -67.612006) (xy 10.991596 -67.636136)
			(xy 11.046714 -67.714368) (xy 11.054374 -67.723929) (xy 11.076136 -67.735098) (xy 11.08837 -67.735704)
			(xy 12.109704 -67.735704) (xy 12.138679 -67.73626) (xy 12.195909 -67.745362) (xy 12.25101 -67.763309)
			(xy 12.302622 -67.78966) (xy 12.349474 -67.823765) (xy 12.370308 -67.843908) (xy 13.51534 -68.988686)
			(xy 13.524186 -68.996605) (xy 13.546703 -69.004039) (xy 13.55852 -69.00291) (xy 13.65123 -68.989448)
			(xy 13.670788 -68.975732) (xy 13.67663 -68.965064) (xy 13.691009 -68.939463) (xy 13.726415 -68.892624)
			(xy 13.768583 -68.851767) (xy 13.816517 -68.817858) (xy 13.869084 -68.7917) (xy 13.925039 -68.773911)
			(xy 13.98306 -68.764911) (xy 14.012418 -68.764404) (xy 14.041334 -68.764939) (xy 14.098504 -68.773669)
			(xy 14.153701 -68.790925) (xy 14.205663 -68.816313) (xy 14.253199 -68.84925) (xy 14.29522 -68.888984)
			(xy 14.313408 -68.91147) (xy 14.320941 -68.920275) (xy 14.341713 -68.930491) (xy 14.353286 -68.931028)
			(xy 14.43355 -68.931028) (xy 14.445106 -68.93041) (xy 14.465862 -68.920226) (xy 14.473428 -68.91147)
			(xy 14.490181 -68.890687) (xy 14.528535 -68.853557) (xy 14.571689 -68.822135) (xy 14.618803 -68.797036)
			(xy 14.668955 -68.77875) (xy 14.721166 -68.767633) (xy 14.774418 -68.763903) (xy 14.82767 -68.767633)
			(xy 14.879881 -68.77875) (xy 14.930033 -68.797036) (xy 14.977147 -68.822135) (xy 15.020301 -68.853557)
			(xy 15.058655 -68.890687) (xy 15.075408 -68.91147) (xy 15.082941 -68.920275) (xy 15.103713 -68.930491)
			(xy 15.115286 -68.931028) (xy 15.19555 -68.931028) (xy 15.207106 -68.93041) (xy 15.227862 -68.920226)
			(xy 15.235428 -68.91147) (xy 15.252181 -68.890687) (xy 15.290535 -68.853557) (xy 15.333689 -68.822135)
			(xy 15.380803 -68.797036) (xy 15.430955 -68.77875) (xy 15.483166 -68.767633) (xy 15.536418 -68.763903)
			(xy 15.58967 -68.767633) (xy 15.641881 -68.77875) (xy 15.692033 -68.797036) (xy 15.739147 -68.822135)
			(xy 15.782301 -68.853557) (xy 15.820655 -68.890687) (xy 15.837408 -68.91147) (xy 15.844941 -68.920275)
			(xy 15.865713 -68.930491) (xy 15.877286 -68.931028) (xy 15.95755 -68.931028) (xy 15.969106 -68.93041)
			(xy 15.989862 -68.920226) (xy 15.997428 -68.91147) (xy 16.015619 -68.888986) (xy 16.057636 -68.849247)
			(xy 16.10517 -68.816305) (xy 16.157132 -68.790916) (xy 16.212331 -68.77366) (xy 16.269502 -68.764934)
			(xy 16.298418 -68.764404) (xy 16.324945 -68.764861) (xy 16.377487 -68.772211) (xy 16.428505 -68.786767)
			(xy 16.477016 -68.808248) (xy 16.522084 -68.83624) (xy 16.562841 -68.870204) (xy 16.598502 -68.909486)
			(xy 16.628379 -68.953327) (xy 16.651897 -69.000884) (xy 16.668602 -69.051239) (xy 16.678172 -69.103423)
			(xy 16.679672 -69.12991) (xy 16.68018 -69.141594) (xy 16.690848 -69.161914) (xy 16.773652 -69.22262)
			(xy 16.796258 -69.226684) (xy 16.807434 -69.223636) (xy 16.831744 -69.217549) (xy 16.881436 -69.211056)
			(xy 16.906494 -69.210682) (xy 16.933746 -69.211167) (xy 16.987695 -69.218923) (xy 17.039991 -69.234278)
			(xy 17.089569 -69.256918) (xy 17.135421 -69.286384) (xy 17.176613 -69.322076) (xy 17.212306 -69.363266)
			(xy 17.241774 -69.409117) (xy 17.264417 -69.458694) (xy 17.279773 -69.51099) (xy 17.287531 -69.564938)
			(xy 17.288002 -69.59219) (xy 17.287505 -69.620252) (xy 17.279279 -69.67577) (xy 17.263004 -69.729483)
			(xy 17.239031 -69.78023) (xy 17.207878 -69.826914) (xy 17.170218 -69.868528) (xy 17.126866 -69.904172)
			(xy 17.10309 -69.919088) (xy 17.097756 -69.92239) (xy 16.909288 -70.110604) (xy 16.888438 -70.13073)
			(xy 16.841588 -70.164832) (xy 16.78998 -70.191184) (xy 16.734884 -70.209137) (xy 16.677657 -70.218248)
			(xy 16.648684 -70.218808) (xy 14.757908 -70.218808) (xy 14.74801 -70.219287) (xy 14.729689 -70.22679)
			(xy 14.715553 -70.240652) (xy 14.711172 -70.249542) (xy 14.6685 -70.349618) (xy 14.674088 -70.37959)
			(xy 14.684502 -70.390766) (xy 14.70434 -70.412202) (xy 14.737925 -70.459982) (xy 14.763829 -70.512325)
			(xy 14.781447 -70.568007) (xy 14.790366 -70.625725) (xy 14.790928 -70.654926) (xy 14.790187 -70.688605)
			(xy 14.778298 -70.754908) (xy 14.767306 -70.786752) (xy 14.762988 -70.79869) (xy 14.76629 -70.823582)
			(xy 14.830044 -70.912482) (xy 14.85265 -70.923912) (xy 14.865096 -70.923404) (xy 14.874494 -70.923404)
			(xy 14.901746 -70.923867) (xy 14.955696 -70.931623) (xy 15.007993 -70.946978) (xy 15.057572 -70.969619)
			(xy 15.103425 -70.999086) (xy 15.144617 -71.034779) (xy 15.18031 -71.07597) (xy 15.209778 -71.121822)
			(xy 15.23242 -71.171401) (xy 15.247776 -71.223698) (xy 15.255533 -71.277648) (xy 15.255533 -71.332152)
			(xy 15.247776 -71.386102) (xy 15.23242 -71.438399) (xy 15.209778 -71.487978) (xy 15.18031 -71.53383)
			(xy 15.144617 -71.575021) (xy 15.103425 -71.610714) (xy 15.057572 -71.640181) (xy 15.007993 -71.662822)
			(xy 14.955696 -71.678177) (xy 14.901746 -71.685933) (xy 14.874494 -71.68642) (xy 14.846785 -71.685923)
			(xy 14.79195 -71.677902) (xy 14.738853 -71.66203) (xy 14.688613 -71.638641) (xy 14.642285 -71.608228)
			(xy 14.600847 -71.57143) (xy 14.582648 -71.55053) (xy 14.575055 -71.542401) (xy 14.554897 -71.533057)
			(xy 14.543786 -71.532496) (xy 14.465808 -71.532496) (xy 14.454694 -71.533048) (xy 14.434523 -71.542384)
			(xy 14.426946 -71.55053) (xy 14.408735 -71.571421) (xy 14.367308 -71.608232) (xy 14.320986 -71.638655)
			(xy 14.270745 -71.662049) (xy 14.217647 -71.677919) (xy 14.16281 -71.685931) (xy 14.1351 -71.68642)
			(xy 14.107038 -71.685922) (xy 14.05152 -71.677695) (xy 13.997808 -71.66142) (xy 13.947061 -71.637447)
			(xy 13.900377 -71.606294) (xy 13.858763 -71.568635) (xy 13.823119 -71.525283) (xy 13.808202 -71.501508)
			(xy 13.8049 -71.496174) (xy 11.758422 -69.449696) (xy 11.751059 -69.44287) (xy 11.732548 -69.435129)
			(xy 11.712484 -69.435083) (xy 11.70305 -69.43852) (xy 11.688572 -69.444616) (xy 11.671808 -69.469762)
			(xy 11.671808 -70.80504) (xy 11.672159 -70.814642) (xy 11.679145 -70.832524) (xy 11.692258 -70.846545)
			(xy 11.700764 -70.851014) (xy 11.797284 -70.89648) (xy 11.82624 -70.892924) (xy 11.837924 -70.883526)
			(xy 11.858498 -70.867133) (xy 11.903301 -70.839562) (xy 11.951468 -70.818413) (xy 12.002085 -70.804086)
			(xy 12.054191 -70.796853) (xy 12.080494 -70.796404) (xy 12.107746 -70.796867) (xy 12.161696 -70.804623)
			(xy 12.213993 -70.819978) (xy 12.263572 -70.842619) (xy 12.309425 -70.872086) (xy 12.350617 -70.907779)
			(xy 12.38631 -70.94897) (xy 12.415778 -70.994822) (xy 12.43842 -71.044401) (xy 12.453776 -71.096698)
			(xy 12.461533 -71.150648) (xy 12.461533 -71.205152) (xy 12.453776 -71.259102) (xy 12.43842 -71.311399)
			(xy 12.415778 -71.360978) (xy 12.38631 -71.40683) (xy 12.350617 -71.448021) (xy 12.309425 -71.483714)
			(xy 12.263572 -71.513181) (xy 12.213993 -71.535822) (xy 12.161696 -71.551177) (xy 12.107746 -71.558933)
			(xy 12.080494 -71.55942) (xy 12.054191 -71.558978) (xy 12.002085 -71.551744) (xy 11.951468 -71.537414)
			(xy 11.903303 -71.516261) (xy 11.858503 -71.488685) (xy 11.837924 -71.472298) (xy 11.82624 -71.4629)
			(xy 11.797284 -71.459344) (xy 11.700764 -71.50481) (xy 11.692293 -71.509319) (xy 11.679228 -71.523358)
			(xy 11.672189 -71.541196) (xy 11.671808 -71.550784) (xy 11.671808 -72.343264) (xy 11.672294 -72.353226)
			(xy 11.679882 -72.37165) (xy 11.68654 -72.379078) (xy 12.071604 -72.764396) (xy 12.091731 -72.785246)
			(xy 12.125835 -72.832095) (xy 12.152189 -72.883703) (xy 12.156848 -72.898) (xy 16.000982 -72.898)
			(xy 16.005053 -72.842378) (xy 16.017179 -72.787941) (xy 16.037102 -72.73585) (xy 16.064398 -72.687215)
			(xy 16.098484 -72.643072) (xy 16.138633 -72.604363) (xy 16.183991 -72.571912) (xy 16.233591 -72.546411)
			(xy 16.286375 -72.528404) (xy 16.341218 -72.518274) (xy 16.396952 -72.516237) (xy 16.452389 -72.522337)
			(xy 16.506346 -72.536443) (xy 16.557675 -72.558255) (xy 16.605281 -72.587309) (xy 16.648149 -72.622984)
			(xy 16.685366 -72.664521) (xy 16.716139 -72.711034) (xy 16.739811 -72.761531) (xy 16.755879 -72.814938)
			(xy 16.763999 -72.870114) (xy 16.764508 -72.898) (xy 16.763999 -72.925886) (xy 16.755879 -72.981062)
			(xy 16.739811 -73.034469) (xy 16.716139 -73.084966) (xy 16.685366 -73.131479) (xy 16.648149 -73.173016)
			(xy 16.605281 -73.208691) (xy 16.557675 -73.237745) (xy 16.506346 -73.259557) (xy 16.452389 -73.273663)
			(xy 16.396952 -73.279763) (xy 16.341218 -73.277726) (xy 16.286375 -73.267596) (xy 16.233591 -73.249589)
			(xy 16.183991 -73.224088) (xy 16.138633 -73.191637) (xy 16.098484 -73.152928) (xy 16.064398 -73.108785)
			(xy 16.037102 -73.06015) (xy 16.017179 -73.008059) (xy 16.005053 -72.953622) (xy 16.000982 -72.898)
			(xy 12.156848 -72.898) (xy 12.170144 -72.938799) (xy 12.179258 -72.996026) (xy 12.179808 -73.025)
			(xy 12.179808 -75.322167) (xy 13.570172 -75.322167) (xy 13.577926 -75.26822) (xy 13.593278 -75.215925)
			(xy 13.615916 -75.166347) (xy 13.645379 -75.120495) (xy 13.681068 -75.079303) (xy 13.722255 -75.043609)
			(xy 13.768103 -75.01414) (xy 13.817678 -74.991496) (xy 13.869971 -74.976137) (xy 13.923917 -74.968376)
			(xy 13.978419 -74.968371) (xy 14.032367 -74.976123) (xy 14.084662 -74.991473) (xy 14.134241 -75.01411)
			(xy 14.180094 -75.043571) (xy 14.221287 -75.079258) (xy 14.256982 -75.120444) (xy 14.286453 -75.166291)
			(xy 14.309099 -75.215865) (xy 14.32446 -75.268157) (xy 14.332223 -75.322103) (xy 14.332712 -75.349354)
			(xy 14.332458 -75.362308) (xy 14.332392 -75.376353) (xy 14.339071 -75.403625) (xy 14.352915 -75.428051)
			(xy 14.372883 -75.447791) (xy 14.397466 -75.461355) (xy 14.424812 -75.467721) (xy 14.452859 -75.466408)
			(xy 14.466316 -75.462384) (xy 14.495696 -75.453191) (xy 14.556443 -75.443236) (xy 14.58722 -75.442572)
			(xy 14.614471 -75.443077) (xy 14.668419 -75.450836) (xy 14.720713 -75.466194) (xy 14.77029 -75.488838)
			(xy 14.816139 -75.518307) (xy 14.857328 -75.554001) (xy 14.893017 -75.595193) (xy 14.922481 -75.641045)
			(xy 14.94512 -75.690624) (xy 14.960472 -75.74292) (xy 14.968226 -75.796869) (xy 14.968223 -75.851371)
			(xy 14.960464 -75.905319) (xy 14.945106 -75.957613) (xy 14.922462 -76.00719) (xy 14.893667 -76.051991)
			(xy 15.219658 -76.051991) (xy 15.219658 -75.997489) (xy 15.227414 -75.943541) (xy 15.242769 -75.891246)
			(xy 15.265411 -75.841669) (xy 15.294877 -75.795819) (xy 15.330568 -75.754628) (xy 15.371759 -75.718937)
			(xy 15.417609 -75.689471) (xy 15.467186 -75.666829) (xy 15.519481 -75.651474) (xy 15.573429 -75.643718)
			(xy 15.60068 -75.643232) (xy 15.629692 -75.643767) (xy 15.68705 -75.652534) (xy 15.74242 -75.669885)
			(xy 15.794524 -75.695419) (xy 15.842161 -75.728547) (xy 15.86357 -75.748134) (xy 15.874813 -75.757991)
			(xy 15.901511 -75.77141) (xy 15.930951 -75.776522) (xy 15.96061 -75.772887) (xy 15.987944 -75.760818)
			(xy 16.010612 -75.741349) (xy 16.026668 -75.716149) (xy 16.03121 -75.701906) (xy 16.039098 -75.675566)
			(xy 16.061452 -75.625329) (xy 16.090784 -75.578822) (xy 16.126487 -75.537005) (xy 16.167823 -75.500745)
			(xy 16.213934 -75.470793) (xy 16.263866 -75.447768) (xy 16.316586 -75.432148) (xy 16.371001 -75.424256)
			(xy 16.398494 -75.423776) (xy 16.425746 -75.424271) (xy 16.479695 -75.432027) (xy 16.531992 -75.447382)
			(xy 16.58157 -75.470023) (xy 16.627422 -75.49949) (xy 16.668614 -75.535182) (xy 16.704307 -75.576373)
			(xy 16.733774 -75.622224) (xy 16.756416 -75.671803) (xy 16.771772 -75.724099) (xy 16.779529 -75.778048)
			(xy 16.779529 -75.832552) (xy 16.771772 -75.886501) (xy 16.756416 -75.938797) (xy 16.733774 -75.988376)
			(xy 16.704307 -76.034227) (xy 16.668614 -76.075418) (xy 16.627422 -76.11111) (xy 16.58157 -76.140577)
			(xy 16.531992 -76.163218) (xy 16.479695 -76.178573) (xy 16.425746 -76.186329) (xy 16.398494 -76.186792)
			(xy 16.369481 -76.186266) (xy 16.312123 -76.177496) (xy 16.256754 -76.160143) (xy 16.20465 -76.134607)
			(xy 16.157013 -76.101477) (xy 16.135604 -76.08189) (xy 16.124394 -76.071991) (xy 16.097687 -76.058569)
			(xy 16.068237 -76.053459) (xy 16.03857 -76.057099) (xy 16.011229 -76.069177) (xy 15.988559 -76.088657)
			(xy 15.972503 -76.113869) (xy 15.967964 -76.128118) (xy 15.960025 -76.154441) (xy 15.937674 -76.204673)
			(xy 15.908346 -76.251178) (xy 15.872649 -76.292993) (xy 15.83132 -76.329253) (xy 15.785217 -76.359207)
			(xy 15.735292 -76.382236) (xy 15.682579 -76.397862) (xy 15.62817 -76.405763) (xy 15.60068 -76.406248)
			(xy 15.573429 -76.405762) (xy 15.519481 -76.398006) (xy 15.467186 -76.382651) (xy 15.417609 -76.360009)
			(xy 15.371759 -76.330543) (xy 15.330568 -76.294852) (xy 15.294877 -76.253661) (xy 15.265411 -76.207811)
			(xy 15.242769 -76.158234) (xy 15.227414 -76.105939) (xy 15.219658 -76.051991) (xy 14.893667 -76.051991)
			(xy 14.892993 -76.053039) (xy 14.857299 -76.094228) (xy 14.816107 -76.129917) (xy 14.770255 -76.159381)
			(xy 14.720676 -76.18202) (xy 14.66838 -76.197372) (xy 14.614431 -76.205126) (xy 14.559929 -76.205123)
			(xy 14.505981 -76.197364) (xy 14.453687 -76.182006) (xy 14.40411 -76.159362) (xy 14.358261 -76.129893)
			(xy 14.317072 -76.094199) (xy 14.281383 -76.053007) (xy 14.251919 -76.007155) (xy 14.22928 -75.957576)
			(xy 14.213928 -75.90528) (xy 14.206174 -75.851331) (xy 14.205712 -75.82408) (xy 14.205966 -75.811126)
			(xy 14.205971 -75.797083) (xy 14.199303 -75.769817) (xy 14.185468 -75.745393) (xy 14.165512 -75.725655)
			(xy 14.140938 -75.712089) (xy 14.113601 -75.705721) (xy 14.085562 -75.707029) (xy 14.072108 -75.71105)
			(xy 14.042726 -75.720236) (xy 13.981981 -75.730196) (xy 13.951204 -75.730862) (xy 13.923953 -75.730427)
			(xy 13.870006 -75.722671) (xy 13.817712 -75.707317) (xy 13.768135 -75.684677) (xy 13.722284 -75.655212)
			(xy 13.681093 -75.619522) (xy 13.645401 -75.578334) (xy 13.615934 -75.532485) (xy 13.593291 -75.482909)
			(xy 13.577934 -75.430616) (xy 13.570175 -75.376669) (xy 13.570172 -75.322167) (xy 12.179808 -75.322167)
			(xy 12.179808 -75.899264) (xy 12.180294 -75.909226) (xy 12.187882 -75.92765) (xy 12.19454 -75.935078)
			(xy 12.414758 -76.155296) (xy 12.422165 -76.161987) (xy 12.440601 -76.169585) (xy 12.450572 -76.170028)
			(xy 12.79017 -76.170028) (xy 12.799061 -76.169692) (xy 12.815767 -76.163605) (xy 12.829374 -76.152159)
			(xy 12.834112 -76.144628) (xy 12.884912 -76.05649) (xy 12.884912 -76.029566) (xy 12.878054 -76.017628)
			(xy 12.865805 -75.995728) (xy 12.846525 -75.949401) (xy 12.833484 -75.900947) (xy 12.826905 -75.851201)
			(xy 12.826492 -75.826112) (xy 12.826978 -75.798861) (xy 12.834734 -75.744913) (xy 12.850089 -75.692618)
			(xy 12.872731 -75.643041) (xy 12.902197 -75.597191) (xy 12.937888 -75.556) (xy 12.979079 -75.520309)
			(xy 13.024929 -75.490843) (xy 13.074506 -75.468201) (xy 13.126801 -75.452846) (xy 13.180749 -75.44509)
			(xy 13.235251 -75.44509) (xy 13.289199 -75.452846) (xy 13.341494 -75.468201) (xy 13.391071 -75.490843)
			(xy 13.436921 -75.520309) (xy 13.478112 -75.556) (xy 13.513803 -75.597191) (xy 13.543269 -75.643041)
			(xy 13.565911 -75.692618) (xy 13.581266 -75.744913) (xy 13.589022 -75.798861) (xy 13.589508 -75.826112)
			(xy 13.589121 -75.850504) (xy 13.582904 -75.89889) (xy 13.570572 -75.94609) (xy 13.552327 -75.991334)
			(xy 13.54074 -76.012802) (xy 13.534644 -76.023724) (xy 13.533882 -76.048108) (xy 13.580618 -76.145898)
			(xy 13.599922 -76.16063) (xy 13.612368 -76.162662) (xy 13.638717 -76.167553) (xy 13.689802 -76.183748)
			(xy 13.738119 -76.206933) (xy 13.782715 -76.236651) (xy 13.822713 -76.272318) (xy 13.857327 -76.313231)
			(xy 13.885874 -76.358586) (xy 13.907794 -76.407489) (xy 13.922654 -76.458978) (xy 13.930163 -76.512041)
			(xy 13.93063 -76.538836) (xy 13.930142 -76.566086) (xy 13.922381 -76.620031) (xy 13.907023 -76.672323)
			(xy 13.88438 -76.721897) (xy 13.854913 -76.767744) (xy 13.819222 -76.808932) (xy 13.778033 -76.844622)
			(xy 13.732185 -76.874087) (xy 13.68261 -76.896728) (xy 13.630317 -76.912084) (xy 13.576372 -76.919843)
			(xy 13.549122 -76.920344) (xy 13.525831 -76.919962) (xy 13.479601 -76.914226) (xy 13.45692 -76.908914)
			(xy 13.450824 -76.907644) (xy 12.276836 -76.907644) (xy 12.247863 -76.907084) (xy 12.190636 -76.897975)
			(xy 12.13554 -76.880022) (xy 12.083932 -76.853668) (xy 12.037085 -76.819563) (xy 12.016232 -76.79944)
			(xy 11.843512 -76.62672) (xy 11.836897 -76.620657) (xy 11.820599 -76.613178) (xy 11.802725 -76.611741)
			(xy 11.793982 -76.613766) (xy 11.69543 -76.640944) (xy 11.67638 -76.660502) (xy 11.673078 -76.673964)
			(xy 11.665753 -76.701093) (xy 11.644226 -76.752999) (xy 11.615316 -76.801184) (xy 11.57965 -76.844607)
			(xy 11.538 -76.882327) (xy 11.491266 -76.913529) (xy 11.440461 -76.937538) (xy 11.386683 -76.953833)
			(xy 11.331096 -76.962062) (xy 11.303 -76.962508) (xy 11.275749 -76.962022) (xy 11.221801 -76.954266)
			(xy 11.169506 -76.938911) (xy 11.119929 -76.916269) (xy 11.074079 -76.886803) (xy 11.032888 -76.851112)
			(xy 10.997197 -76.809921) (xy 10.967731 -76.764071) (xy 10.945089 -76.714494) (xy 10.929734 -76.662199)
			(xy 10.921978 -76.608251) (xy 10.921978 -76.553749) (xy 10.929734 -76.499801) (xy 10.945089 -76.447506)
			(xy 10.967731 -76.397929) (xy 10.997197 -76.352079) (xy 11.032888 -76.310888) (xy 11.074079 -76.275197)
			(xy 11.119929 -76.245731) (xy 11.169506 -76.223089) (xy 11.221801 -76.207734) (xy 11.275749 -76.199978)
			(xy 11.303 -76.199492) (xy 11.33348 -76.200762) (xy 11.344402 -76.201524) (xy 11.364976 -76.194158)
			(xy 11.435588 -76.12507) (xy 11.443462 -76.10475) (xy 11.442954 -76.093828) (xy 11.442192 -76.073)
			(xy 11.442192 -73.198736) (xy 11.441706 -73.188774) (xy 11.434118 -73.17035) (xy 11.42746 -73.162922)
			(xy 11.042396 -72.777604) (xy 11.022269 -72.756754) (xy 10.988165 -72.709905) (xy 10.961811 -72.658297)
			(xy 10.943856 -72.603201) (xy 10.934742 -72.545974) (xy 10.934192 -72.517) (xy 10.934192 -69.381116)
			(xy 10.932922 -69.37502) (xy 10.92581 -69.339206) (xy 10.92454 -69.331078) (xy 10.917174 -69.316854)
			(xy 10.911332 -69.310758) (xy 10.903885 -69.30407) (xy 10.885389 -69.296474) (xy 10.865393 -69.296474)
			(xy 10.846897 -69.30407) (xy 10.83945 -69.310758) (xy 9.235694 -70.914514) (xy 9.214814 -70.93459)
			(xy 9.167954 -70.968633) (xy 9.116345 -70.994927) (xy 9.061258 -71.012824) (xy 9.00405 -71.021883)
			(xy 8.97509 -71.022464) (xy 4.653026 -71.022464) (xy 4.643036 -71.022996) (xy 4.624593 -71.030699)
			(xy 4.617212 -71.03745) (xy 4.504436 -71.150226) (xy 9.367264 -71.150226) (xy 9.371335 -71.094604)
			(xy 9.383461 -71.040167) (xy 9.403384 -70.988076) (xy 9.43068 -70.939441) (xy 9.464766 -70.895298)
			(xy 9.504915 -70.856589) (xy 9.550273 -70.824138) (xy 9.599873 -70.798637) (xy 9.652657 -70.78063)
			(xy 9.7075 -70.7705) (xy 9.763234 -70.768463) (xy 9.818671 -70.774563) (xy 9.872628 -70.788669) (xy 9.923957 -70.810481)
			(xy 9.971563 -70.839535) (xy 10.014431 -70.87521) (xy 10.051648 -70.916747) (xy 10.082421 -70.96326)
			(xy 10.106093 -71.013757) (xy 10.122161 -71.067164) (xy 10.130281 -71.12234) (xy 10.13079 -71.150226)
			(xy 10.130281 -71.178112) (xy 10.122161 -71.233288) (xy 10.106093 -71.286695) (xy 10.082421 -71.337192)
			(xy 10.051648 -71.383705) (xy 10.014431 -71.425242) (xy 9.971563 -71.460917) (xy 9.923957 -71.489971)
			(xy 9.872628 -71.511783) (xy 9.818671 -71.525889) (xy 9.763234 -71.531989) (xy 9.7075 -71.529952)
			(xy 9.652657 -71.519822) (xy 9.599873 -71.501815) (xy 9.550273 -71.476314) (xy 9.504915 -71.443863)
			(xy 9.464766 -71.405154) (xy 9.43068 -71.361011) (xy 9.403384 -71.312376) (xy 9.383461 -71.260285)
			(xy 9.371335 -71.205848) (xy 9.367264 -71.150226) (xy 4.504436 -71.150226) (xy 3.38074 -72.273922)
			(xy 3.373997 -72.281292) (xy 3.366406 -72.299754) (xy 3.366008 -72.309736) (xy 3.366008 -73.463912)
			(xy 4.237482 -73.463912) (xy 4.237978 -73.434994) (xy 4.246707 -73.37782) (xy 4.263967 -73.32262)
			(xy 4.289363 -73.270657) (xy 4.322312 -73.223124) (xy 4.362059 -73.18111) (xy 4.384548 -73.162922)
			(xy 4.393304 -73.155355) (xy 4.403489 -73.1346) (xy 4.404106 -73.123044) (xy 4.404106 -73.04278)
			(xy 4.403488 -73.031218) (xy 4.393327 -73.010447) (xy 4.384548 -73.002902) (xy 4.362055 -72.984723)
			(xy 4.322322 -72.942699) (xy 4.289386 -72.895161) (xy 4.264 -72.843198) (xy 4.246745 -72.787999)
			(xy 4.238017 -72.730828) (xy 4.237482 -72.701912) (xy 4.237966 -72.67466) (xy 4.245722 -72.62071)
			(xy 4.261076 -72.568413) (xy 4.283716 -72.518834) (xy 4.313182 -72.472981) (xy 4.348873 -72.431789)
			(xy 4.390064 -72.396095) (xy 4.435915 -72.366626) (xy 4.485493 -72.343983) (xy 4.537789 -72.328626)
			(xy 4.591738 -72.320868) (xy 4.61899 -72.320404) (xy 4.647907 -72.320928) (xy 4.705078 -72.329656)
			(xy 4.760276 -72.346913) (xy 4.812238 -72.372303) (xy 4.859772 -72.405246) (xy 4.90179 -72.444985)
			(xy 4.91998 -72.46747) (xy 4.927543 -72.47623) (xy 4.948301 -72.486412) (xy 4.959858 -72.487028)
			(xy 5.040122 -72.487028) (xy 5.051688 -72.486438) (xy 5.072461 -72.47626) (xy 5.08 -72.46747) (xy 5.096753 -72.446687)
			(xy 5.135107 -72.409557) (xy 5.178261 -72.378135) (xy 5.225375 -72.353036) (xy 5.275527 -72.33475)
			(xy 5.327738 -72.323633) (xy 5.38099 -72.319903) (xy 5.434242 -72.323633) (xy 5.486453 -72.33475)
			(xy 5.536605 -72.353036) (xy 5.583719 -72.378135) (xy 5.626873 -72.409557) (xy 5.665227 -72.446687)
			(xy 5.68198 -72.46747) (xy 5.689543 -72.47623) (xy 5.710301 -72.486412) (xy 5.721858 -72.487028)
			(xy 5.802122 -72.487028) (xy 5.813688 -72.486438) (xy 5.834461 -72.47626) (xy 5.842 -72.46747) (xy 5.858753 -72.446687)
			(xy 5.897107 -72.409557) (xy 5.940261 -72.378135) (xy 5.987375 -72.353036) (xy 6.037527 -72.33475)
			(xy 6.089738 -72.323633) (xy 6.14299 -72.319903) (xy 6.196242 -72.323633) (xy 6.248453 -72.33475)
			(xy 6.298605 -72.353036) (xy 6.345719 -72.378135) (xy 6.388873 -72.409557) (xy 6.427227 -72.446687)
			(xy 6.44398 -72.46747) (xy 6.451543 -72.47623) (xy 6.472301 -72.486412) (xy 6.483858 -72.487028)
			(xy 6.564122 -72.487028) (xy 6.575688 -72.486438) (xy 6.596461 -72.47626) (xy 6.604 -72.46747) (xy 6.622183 -72.44498)
			(xy 6.664206 -72.405247) (xy 6.711742 -72.372309) (xy 6.763705 -72.346922) (xy 6.818904 -72.329667)
			(xy 6.876074 -72.320939) (xy 6.90499 -72.320404) (xy 6.932243 -72.320865) (xy 6.986195 -72.328621)
			(xy 7.038493 -72.343976) (xy 7.088074 -72.366618) (xy 7.133928 -72.396086) (xy 7.175121 -72.43178)
			(xy 7.210815 -72.472974) (xy 7.240283 -72.518827) (xy 7.262925 -72.568408) (xy 7.27828 -72.620707)
			(xy 7.286035 -72.674659) (xy 7.286498 -72.701912) (xy 7.285917 -72.730827) (xy 7.277201 -72.787995)
			(xy 7.259956 -72.843193) (xy 7.234576 -72.895155) (xy 7.201643 -72.94269) (xy 7.161913 -72.98471)
			(xy 7.139432 -73.002902) (xy 7.130662 -73.010456) (xy 7.120486 -73.031221) (xy 7.119874 -73.04278)
			(xy 7.119874 -73.123044) (xy 7.120451 -73.134612) (xy 7.130638 -73.155384) (xy 7.139432 -73.162922)
			(xy 7.161933 -73.181093) (xy 7.201665 -73.223117) (xy 7.234601 -73.270657) (xy 7.259987 -73.322622)
			(xy 7.277239 -73.377823) (xy 7.285965 -73.434995) (xy 7.286498 -73.463912) (xy 7.286033 -73.491164)
			(xy 7.278275 -73.545113) (xy 7.262918 -73.597409) (xy 7.240275 -73.646987) (xy 7.210806 -73.692838)
			(xy 7.175112 -73.734028) (xy 7.13392 -73.769719) (xy 7.088067 -73.799185) (xy 7.038488 -73.821825)
			(xy 6.986191 -73.83718) (xy 6.932242 -73.844935) (xy 6.90499 -73.84542) (xy 6.876074 -73.844867)
			(xy 6.818903 -73.83615) (xy 6.763704 -73.818901) (xy 6.711741 -73.793515) (xy 6.664207 -73.760576)
			(xy 6.62219 -73.720838) (xy 6.604 -73.698354) (xy 6.596442 -73.689589) (xy 6.57568 -73.679409) (xy 6.564122 -73.678796)
			(xy 6.483858 -73.678796) (xy 6.472295 -73.679401) (xy 6.451523 -73.689572) (xy 6.44398 -73.698354)
			(xy 6.427227 -73.719137) (xy 6.388873 -73.756267) (xy 6.345719 -73.787689) (xy 6.298605 -73.812788)
			(xy 6.248453 -73.831074) (xy 6.196242 -73.842191) (xy 6.14299 -73.845921) (xy 6.089738 -73.842191)
			(xy 6.037527 -73.831074) (xy 5.987375 -73.812788) (xy 5.940261 -73.787689) (xy 5.897107 -73.756267)
			(xy 5.858753 -73.719137) (xy 5.842 -73.698354) (xy 5.834442 -73.689589) (xy 5.81368 -73.679409) (xy 5.802122 -73.678796)
			(xy 5.721858 -73.678796) (xy 5.710295 -73.679401) (xy 5.689523 -73.689572) (xy 5.68198 -73.698354)
			(xy 5.665227 -73.719137) (xy 5.626873 -73.756267) (xy 5.583719 -73.787689) (xy 5.536605 -73.812788)
			(xy 5.486453 -73.831074) (xy 5.434242 -73.842191) (xy 5.38099 -73.845921) (xy 5.327738 -73.842191)
			(xy 5.275527 -73.831074) (xy 5.225375 -73.812788) (xy 5.178261 -73.787689) (xy 5.135107 -73.756267)
			(xy 5.096753 -73.719137) (xy 5.08 -73.698354) (xy 5.072442 -73.689589) (xy 5.05168 -73.679409) (xy 5.040122 -73.678796)
			(xy 4.959858 -73.678796) (xy 4.948295 -73.679401) (xy 4.927523 -73.689572) (xy 4.91998 -73.698354)
			(xy 4.901814 -73.720858) (xy 4.859787 -73.76059) (xy 4.812247 -73.793525) (xy 4.760281 -73.818909)
			(xy 4.70508 -73.836161) (xy 4.647907 -73.844887) (xy 4.61899 -73.84542) (xy 4.591739 -73.844932)
			(xy 4.537792 -73.837174) (xy 4.485498 -73.821818) (xy 4.435922 -73.799177) (xy 4.390072 -73.769711)
			(xy 4.348882 -73.734019) (xy 4.313191 -73.69283) (xy 4.283724 -73.64698) (xy 4.261083 -73.597404)
			(xy 4.245726 -73.54511) (xy 4.237969 -73.491163) (xy 4.237482 -73.463912) (xy 3.366008 -73.463912)
			(xy 3.366008 -75.057) (xy 9.904982 -75.057) (xy 9.909053 -75.001378) (xy 9.921179 -74.946941) (xy 9.941102 -74.89485)
			(xy 9.968398 -74.846215) (xy 10.002484 -74.802072) (xy 10.042633 -74.763363) (xy 10.087991 -74.730912)
			(xy 10.137591 -74.705411) (xy 10.190375 -74.687404) (xy 10.245218 -74.677274) (xy 10.300952 -74.675237)
			(xy 10.356389 -74.681337) (xy 10.410346 -74.695443) (xy 10.461675 -74.717255) (xy 10.509281 -74.746309)
			(xy 10.552149 -74.781984) (xy 10.589366 -74.823521) (xy 10.620139 -74.870034) (xy 10.643811 -74.920531)
			(xy 10.659879 -74.973938) (xy 10.667999 -75.029114) (xy 10.668508 -75.057) (xy 10.667999 -75.084886)
			(xy 10.659879 -75.140062) (xy 10.643811 -75.193469) (xy 10.620139 -75.243966) (xy 10.589366 -75.290479)
			(xy 10.552149 -75.332016) (xy 10.509281 -75.367691) (xy 10.461675 -75.396745) (xy 10.410346 -75.418557)
			(xy 10.356389 -75.432663) (xy 10.300952 -75.438763) (xy 10.245218 -75.436726) (xy 10.190375 -75.426596)
			(xy 10.137591 -75.408589) (xy 10.087991 -75.383088) (xy 10.042633 -75.350637) (xy 10.002484 -75.311928)
			(xy 9.968398 -75.267785) (xy 9.941102 -75.21915) (xy 9.921179 -75.167059) (xy 9.909053 -75.112622)
			(xy 9.904982 -75.057) (xy 3.366008 -75.057) (xy 3.366008 -76.66615) (xy 9.06399 -76.66615) (xy 9.06399 -76.61165)
			(xy 9.071746 -76.557705) (xy 9.0871 -76.505413) (xy 9.10974 -76.455838) (xy 9.139204 -76.409989)
			(xy 9.174894 -76.368801) (xy 9.216081 -76.33311) (xy 9.261929 -76.303645) (xy 9.311503 -76.281004)
			(xy 9.363795 -76.265648) (xy 9.41774 -76.257891) (xy 9.44499 -76.257404) (xy 9.473907 -76.257928)
			(xy 9.531078 -76.266656) (xy 9.586276 -76.283913) (xy 9.638238 -76.309303) (xy 9.685772 -76.342246)
			(xy 9.72779 -76.381985) (xy 9.74598 -76.40447) (xy 9.753543 -76.41323) (xy 9.774301 -76.423412) (xy 9.785858 -76.424028)
			(xy 9.866122 -76.424028) (xy 9.877688 -76.423438) (xy 9.898461 -76.41326) (xy 9.906 -76.40447) (xy 9.924183 -76.38198)
			(xy 9.966206 -76.342247) (xy 10.013742 -76.309309) (xy 10.065705 -76.283922) (xy 10.120904 -76.266667)
			(xy 10.178074 -76.257939) (xy 10.20699 -76.257404) (xy 10.234244 -76.257842) (xy 10.288198 -76.265598)
			(xy 10.340499 -76.280954) (xy 10.390082 -76.303597) (xy 10.435938 -76.333065) (xy 10.477133 -76.36876)
			(xy 10.512829 -76.409954) (xy 10.542299 -76.455809) (xy 10.564943 -76.505392) (xy 10.5803 -76.557692)
			(xy 10.588057 -76.611646) (xy 10.588057 -76.666154) (xy 10.5803 -76.720108) (xy 10.564943 -76.772408)
			(xy 10.542299 -76.821991) (xy 10.512829 -76.867846) (xy 10.477133 -76.90904) (xy 10.435938 -76.944735)
			(xy 10.390082 -76.974203) (xy 10.340499 -76.996846) (xy 10.288198 -77.012202) (xy 10.234244 -77.019958)
			(xy 10.20699 -77.02042) (xy 10.178074 -77.019867) (xy 10.120903 -77.01115) (xy 10.065704 -76.993901)
			(xy 10.013741 -76.968515) (xy 9.966207 -76.935576) (xy 9.92419 -76.895838) (xy 9.906 -76.873354)
			(xy 9.898442 -76.864589) (xy 9.87768 -76.854409) (xy 9.866122 -76.853796) (xy 9.785858 -76.853796)
			(xy 9.774295 -76.854401) (xy 9.753523 -76.864572) (xy 9.74598 -76.873354) (xy 9.727814 -76.895858)
			(xy 9.685787 -76.93559) (xy 9.638247 -76.968525) (xy 9.586281 -76.993909) (xy 9.53108 -77.011161)
			(xy 9.473907 -77.019887) (xy 9.44499 -77.02042) (xy 9.41774 -77.019909) (xy 9.363795 -77.012152)
			(xy 9.311503 -76.996796) (xy 9.261929 -76.974155) (xy 9.216081 -76.94469) (xy 9.174894 -76.908999)
			(xy 9.139204 -76.867811) (xy 9.10974 -76.821962) (xy 9.0871 -76.772387) (xy 9.071746 -76.720095)
			(xy 9.06399 -76.66615) (xy 3.366008 -76.66615) (xy 3.366008 -80.067912) (xy 3.729482 -80.067912)
			(xy 3.73007 -80.021517) (xy 3.739714 -79.929228) (xy 3.758908 -79.838445) (xy 3.787445 -79.750151)
			(xy 3.805682 -79.707486) (xy 3.80958 -79.697562) (xy 3.809585 -79.67626) (xy 3.805682 -79.666338)
			(xy 3.787441 -79.623674) (xy 3.758896 -79.535383) (xy 3.739702 -79.444598) (xy 3.730067 -79.352308)
			(xy 3.729482 -79.305912) (xy 3.729964 -79.264809) (xy 3.737547 -79.182955) (xy 3.752652 -79.102149)
			(xy 3.775147 -79.023081) (xy 3.804842 -78.946427) (xy 3.841483 -78.872839) (xy 3.884758 -78.802946)
			(xy 3.934297 -78.737344) (xy 3.989677 -78.676593) (xy 4.050427 -78.621211) (xy 4.116028 -78.57167)
			(xy 4.18592 -78.528394) (xy 4.259507 -78.491751) (xy 4.33616 -78.462054) (xy 4.415227 -78.439557)
			(xy 4.496033 -78.42445) (xy 4.577887 -78.416865) (xy 4.61899 -78.416404) (xy 4.665386 -78.416989)
			(xy 4.757674 -78.426634) (xy 4.848458 -78.445829) (xy 4.936751 -78.474366) (xy 4.979416 -78.492604)
			(xy 4.989356 -78.496424) (xy 5.010624 -78.496424) (xy 5.020564 -78.492604) (xy 5.063228 -78.474363)
			(xy 5.15152 -78.445818) (xy 5.242304 -78.426624) (xy 5.334594 -78.416989) (xy 5.38099 -78.416404)
			(xy 5.427386 -78.416989) (xy 5.519674 -78.426634) (xy 5.610458 -78.445829) (xy 5.698751 -78.474366)
			(xy 5.741416 -78.492604) (xy 5.751356 -78.496424) (xy 5.772624 -78.496424) (xy 5.782564 -78.492604)
			(xy 5.825228 -78.474363) (xy 5.91352 -78.445818) (xy 6.004304 -78.426624) (xy 6.096594 -78.416989)
			(xy 6.14299 -78.416404) (xy 6.189386 -78.416989) (xy 6.281674 -78.426634) (xy 6.372458 -78.445829)
			(xy 6.460751 -78.474366) (xy 6.503416 -78.492604) (xy 6.513356 -78.496424) (xy 6.534624 -78.496424)
			(xy 6.544564 -78.492604) (xy 6.587228 -78.474363) (xy 6.67552 -78.445818) (xy 6.766304 -78.426624)
			(xy 6.858594 -78.416989) (xy 6.90499 -78.416404) (xy 6.946093 -78.416862) (xy 7.027949 -78.424447)
			(xy 7.108756 -78.439553) (xy 7.187824 -78.46205) (xy 7.264479 -78.491746) (xy 7.338067 -78.528389)
			(xy 7.407961 -78.571665) (xy 7.473563 -78.621205) (xy 7.534314 -78.676587) (xy 7.589696 -78.737339)
			(xy 7.639236 -78.802941) (xy 7.682512 -78.872834) (xy 7.719155 -78.946423) (xy 7.748851 -79.023078)
			(xy 7.771348 -79.102146) (xy 7.786453 -79.182953) (xy 7.794038 -79.264809) (xy 7.794498 -79.305912)
			(xy 7.79392 -79.352308) (xy 7.784274 -79.444596) (xy 7.765076 -79.53538) (xy 7.736537 -79.623673)
			(xy 7.718298 -79.666338) (xy 7.714386 -79.676258) (xy 7.714391 -79.697564) (xy 7.718298 -79.707486)
			(xy 7.736546 -79.750147) (xy 7.765089 -79.83844) (xy 7.784282 -79.929225) (xy 7.793914 -80.021516)
			(xy 7.794498 -80.067912) (xy 7.794045 -80.109015) (xy 7.786459 -80.19087) (xy 7.771352 -80.271676)
			(xy 7.757059 -80.32191) (xy 8.55498 -80.32191) (xy 8.55901 -80.237309) (xy 8.571063 -80.153474) (xy 8.591031 -80.071165)
			(xy 8.618733 -79.991127) (xy 8.653917 -79.914084) (xy 8.696266 -79.840734) (xy 8.745394 -79.771742)
			(xy 8.800859 -79.707732) (xy 8.862157 -79.649285) (xy 8.928733 -79.596929) (xy 8.999985 -79.551138)
			(xy 9.075266 -79.512328) (xy 9.153896 -79.480849) (xy 9.235162 -79.456988) (xy 9.318328 -79.440959)
			(xy 9.402642 -79.432908) (xy 9.44499 -79.432404) (xy 9.491386 -79.432989) (xy 9.583674 -79.442634)
			(xy 9.674458 -79.461829) (xy 9.762751 -79.490366) (xy 9.805416 -79.508604) (xy 9.815356 -79.512424)
			(xy 9.836624 -79.512424) (xy 9.846564 -79.508604) (xy 9.889228 -79.490363) (xy 9.97752 -79.461818)
			(xy 10.068304 -79.442624) (xy 10.160594 -79.432989) (xy 10.20699 -79.432404) (xy 10.249339 -79.432904)
			(xy 10.333652 -79.440955) (xy 10.416819 -79.456984) (xy 10.498085 -79.480846) (xy 10.576715 -79.512324)
			(xy 10.651997 -79.551135) (xy 10.723249 -79.596926) (xy 10.789826 -79.649282) (xy 10.851124 -79.70773)
			(xy 10.862798 -79.721202) (xy 11.170666 -79.721202) (xy 11.171114 -79.682914) (xy 11.177732 -79.606624)
			(xy 11.190876 -79.531185) (xy 11.210448 -79.457152) (xy 11.22299 -79.420974) (xy 11.225631 -79.412536)
			(xy 11.225632 -79.394868) (xy 11.22299 -79.38643) (xy 11.210433 -79.350256) (xy 11.190837 -79.276226)
			(xy 11.177686 -79.200785) (xy 11.171077 -79.124491) (xy 11.170666 -79.086202) (xy 11.171169 -79.0451)
			(xy 11.178753 -78.963248) (xy 11.193857 -78.882444) (xy 11.216353 -78.803378) (xy 11.246047 -78.726726)
			(xy 11.282688 -78.65314) (xy 11.325962 -78.583249) (xy 11.375499 -78.517648) (xy 11.430878 -78.456898)
			(xy 11.491627 -78.401517) (xy 11.557225 -78.351977) (xy 11.627115 -78.308702) (xy 11.7007 -78.272059)
			(xy 11.777352 -78.242362) (xy 11.856416 -78.219864) (xy 11.93722 -78.204757) (xy 12.019072 -78.19717)
			(xy 12.060174 -78.196694) (xy 12.099744 -78.197098) (xy 12.178572 -78.20411) (xy 12.256466 -78.218097)
			(xy 12.332809 -78.238949) (xy 12.370054 -78.25232) (xy 12.378721 -78.25516) (xy 12.396947 -78.25516)
			(xy 12.405614 -78.25232) (xy 12.442854 -78.238937) (xy 12.5192 -78.218094) (xy 12.597095 -78.204116)
			(xy 12.675924 -78.197112) (xy 12.715494 -78.196694) (xy 12.753782 -78.197142) (xy 12.830072 -78.203759)
			(xy 12.905511 -78.216903) (xy 12.979544 -78.236476) (xy 13.015722 -78.249018) (xy 13.02416 -78.25166)
			(xy 13.041828 -78.25166) (xy 13.050266 -78.249018) (xy 13.086441 -78.236463) (xy 13.16047 -78.216866)
			(xy 13.235911 -78.203714) (xy 13.312205 -78.197105) (xy 13.350494 -78.196694) (xy 13.391597 -78.197158)
			(xy 13.473453 -78.204742) (xy 13.554259 -78.219847) (xy 13.633328 -78.242344) (xy 13.709983 -78.27204)
			(xy 13.783571 -78.308682) (xy 13.853464 -78.351958) (xy 13.919066 -78.401498) (xy 13.979818 -78.45688)
			(xy 14.0352 -78.517631) (xy 14.08474 -78.583233) (xy 14.128016 -78.653126) (xy 14.164659 -78.726714)
			(xy 14.194355 -78.803369) (xy 14.216852 -78.882437) (xy 14.231957 -78.963243) (xy 14.239542 -79.045099)
			(xy 14.240002 -79.086202) (xy 14.239557 -79.12449) (xy 14.232938 -79.20078) (xy 14.219794 -79.27622)
			(xy 14.200221 -79.350252) (xy 14.187678 -79.38643) (xy 14.185036 -79.394868) (xy 14.185037 -79.412536)
			(xy 14.187678 -79.420974) (xy 14.19479 -79.44104) (xy 14.199616 -79.455518) (xy 14.223238 -79.474314)
			(xy 14.346174 -79.48549) (xy 14.372844 -79.471266) (xy 14.38021 -79.458058) (xy 14.401447 -79.420407)
			(xy 14.450201 -79.349018) (xy 14.50565 -79.282695) (xy 14.567272 -79.222063) (xy 14.634484 -79.167696)
			(xy 14.706654 -79.120104) (xy 14.7831 -79.079739) (xy 14.863101 -79.04698) (xy 14.945903 -79.022136)
			(xy 15.030725 -79.005441) (xy 15.116766 -78.997054) (xy 15.15999 -78.99654) (xy 15.199559 -78.996973)
			(xy 15.278387 -79.003976) (xy 15.356281 -79.017955) (xy 15.432625 -79.038799) (xy 15.46987 -79.052166)
			(xy 15.478537 -79.055006) (xy 15.496763 -79.055006) (xy 15.50543 -79.052166) (xy 15.542679 -79.038809)
			(xy 15.619021 -79.017959) (xy 15.696914 -79.003973) (xy 15.775741 -78.996962) (xy 15.81531 -78.99654)
			(xy 15.853598 -78.996981) (xy 15.929888 -79.0036) (xy 16.005328 -79.016746) (xy 16.07936 -79.036321)
			(xy 16.115538 -79.048864) (xy 16.123976 -79.051506) (xy 16.141644 -79.051506) (xy 16.150082 -79.048864)
			(xy 16.186255 -79.036302) (xy 16.260285 -79.016708) (xy 16.335727 -79.003558) (xy 16.41202 -78.99695)
			(xy 16.45031 -78.99654) (xy 16.491412 -78.997017) (xy 16.573267 -79.004602) (xy 16.654072 -79.019707)
			(xy 16.733139 -79.042203) (xy 16.809792 -79.071899) (xy 16.883379 -79.108541) (xy 16.953271 -79.151816)
			(xy 17.018872 -79.201355) (xy 17.079622 -79.256736) (xy 17.135003 -79.317486) (xy 17.184543 -79.383087)
			(xy 17.227818 -79.452979) (xy 17.26446 -79.526566) (xy 17.294156 -79.60322) (xy 17.316653 -79.682286)
			(xy 17.331758 -79.763091) (xy 17.339343 -79.844946) (xy 17.339818 -79.886048) (xy 17.339385 -79.924336)
			(xy 17.332763 -80.000626) (xy 17.319615 -80.076066) (xy 17.300038 -80.150098) (xy 17.287494 -80.186276)
			(xy 17.284829 -80.194708) (xy 17.284844 -80.212382) (xy 17.287494 -80.22082) (xy 17.300064 -80.25699)
			(xy 17.319657 -80.331021) (xy 17.332805 -80.406464) (xy 17.339409 -80.482758) (xy 17.339818 -80.521048)
			(xy 17.339379 -80.562151) (xy 17.33179 -80.644006) (xy 17.316681 -80.724812) (xy 17.294181 -80.803878)
			(xy 17.264482 -80.880532) (xy 17.227837 -80.954119) (xy 17.184559 -81.02401) (xy 17.135017 -81.089611)
			(xy 17.079634 -81.15036) (xy 17.018881 -81.205741) (xy 16.953279 -81.25528) (xy 16.883385 -81.298555)
			(xy 16.809797 -81.335197) (xy 16.733142 -81.364893) (xy 16.654075 -81.38739) (xy 16.573268 -81.402495)
			(xy 16.491413 -81.410081) (xy 16.45031 -81.410556) (xy 16.411378 -81.410129) (xy 16.333814 -81.403291)
			(xy 16.257146 -81.389693) (xy 16.181961 -81.369439) (xy 16.145256 -81.356454) (xy 16.136707 -81.35369)
			(xy 16.118753 -81.35369) (xy 16.110204 -81.356454) (xy 16.073499 -81.369437) (xy 15.998311 -81.389675)
			(xy 15.921643 -81.403269) (xy 15.844082 -81.410117) (xy 15.80515 -81.410556) (xy 15.766218 -81.410117)
			(xy 15.688654 -81.403283) (xy 15.611986 -81.389688) (xy 15.536802 -81.369438) (xy 15.500096 -81.356454)
			(xy 15.491547 -81.35369) (xy 15.473593 -81.35369) (xy 15.465044 -81.356454) (xy 15.428335 -81.369426)
			(xy 15.353149 -81.389667) (xy 15.276482 -81.403264) (xy 15.198921 -81.410115) (xy 15.15999 -81.410556)
			(xy 15.118887 -81.410098) (xy 15.037031 -81.402513) (xy 14.956224 -81.387407) (xy 14.877156 -81.36491)
			(xy 14.800501 -81.335214) (xy 14.726913 -81.298571) (xy 14.657019 -81.255295) (xy 14.591417 -81.205755)
			(xy 14.530666 -81.150373) (xy 14.475284 -81.089621) (xy 14.425744 -81.024019) (xy 14.382468 -80.954126)
			(xy 14.345825 -80.880537) (xy 14.316129 -80.803882) (xy 14.293632 -80.724814) (xy 14.278527 -80.644007)
			(xy 14.270942 -80.562151) (xy 14.270482 -80.521048) (xy 14.270914 -80.48276) (xy 14.277536 -80.40647)
			(xy 14.290684 -80.33103) (xy 14.310262 -80.256998) (xy 14.322806 -80.22082) (xy 14.325424 -80.212376)
			(xy 14.325439 -80.194714) (xy 14.322806 -80.186276) (xy 14.315694 -80.16621) (xy 14.310868 -80.151732)
			(xy 14.287246 -80.132936) (xy 14.16431 -80.12176) (xy 14.13764 -80.135984) (xy 14.130274 -80.149192)
			(xy 14.109028 -80.186838) (xy 14.060277 -80.258229) (xy 14.00483 -80.324554) (xy 13.94321 -80.385186)
			(xy 13.875998 -80.439555) (xy 13.803829 -80.487147) (xy 13.727384 -80.527514) (xy 13.647382 -80.560273)
			(xy 13.564581 -80.585117) (xy 13.479759 -80.60181) (xy 13.393718 -80.610197) (xy 13.350494 -80.61071)
			(xy 13.311562 -80.610285) (xy 13.233998 -80.603446) (xy 13.15733 -80.589847) (xy 13.082145 -80.569593)
			(xy 13.04544 -80.556608) (xy 13.036891 -80.553844) (xy 13.018937 -80.553844) (xy 13.010388 -80.556608)
			(xy 12.973684 -80.569594) (xy 12.898496 -80.589831) (xy 12.821828 -80.603425) (xy 12.744266 -80.610271)
			(xy 12.705334 -80.61071) (xy 12.666402 -80.610273) (xy 12.588839 -80.603437) (xy 12.51217 -80.589842)
			(xy 12.436986 -80.569592) (xy 12.40028 -80.556608) (xy 12.391731 -80.553844) (xy 12.373777 -80.553844)
			(xy 12.365228 -80.556608) (xy 12.32852 -80.569583) (xy 12.253333 -80.589823) (xy 12.176667 -80.60342)
			(xy 12.099105 -80.61027) (xy 12.060174 -80.61071) (xy 12.019071 -80.610258) (xy 11.937216 -80.602671)
			(xy 11.856411 -80.587564) (xy 11.777344 -80.565065) (xy 11.70069 -80.535367) (xy 11.627103 -80.498724)
			(xy 11.557211 -80.455447) (xy 11.49161 -80.405905) (xy 11.43086 -80.350523) (xy 11.375479 -80.289771)
			(xy 11.32594 -80.224169) (xy 11.282665 -80.154276) (xy 11.246023 -80.080688) (xy 11.216327 -80.004034)
			(xy 11.193831 -79.924966) (xy 11.178726 -79.84416) (xy 11.171141 -79.762305) (xy 11.170666 -79.721202)
			(xy 10.862798 -79.721202) (xy 10.906589 -79.77174) (xy 10.955718 -79.840732) (xy 10.998066 -79.914082)
			(xy 11.033251 -79.991125) (xy 11.060953 -80.071164) (xy 11.080921 -80.153474) (xy 11.092974 -80.237309)
			(xy 11.097005 -80.32191) (xy 11.092974 -80.406511) (xy 11.080921 -80.490346) (xy 11.060953 -80.572656)
			(xy 11.033251 -80.652695) (xy 10.998066 -80.729738) (xy 10.955718 -80.803088) (xy 10.906589 -80.87208)
			(xy 10.851124 -80.93609) (xy 10.789826 -80.994538) (xy 10.723249 -81.046894) (xy 10.651997 -81.092685)
			(xy 10.576715 -81.131496) (xy 10.498085 -81.162974) (xy 10.416819 -81.186836) (xy 10.333652 -81.202865)
			(xy 10.249339 -81.210916) (xy 10.20699 -81.21142) (xy 10.160594 -81.21084) (xy 10.068306 -81.201194)
			(xy 9.977522 -81.181997) (xy 9.889229 -81.153458) (xy 9.846564 -81.13522) (xy 9.836624 -81.1314)
			(xy 9.815356 -81.1314) (xy 9.805416 -81.13522) (xy 9.762755 -81.153469) (xy 9.674462 -81.182012)
			(xy 9.583677 -81.201204) (xy 9.491386 -81.210836) (xy 9.44499 -81.21142) (xy 9.402642 -81.210912)
			(xy 9.318328 -81.202861) (xy 9.235162 -81.186832) (xy 9.153896 -81.162971) (xy 9.075266 -81.131492)
			(xy 8.999985 -81.092682) (xy 8.928733 -81.046891) (xy 8.862157 -80.994535) (xy 8.800859 -80.936088)
			(xy 8.745394 -80.872078) (xy 8.696266 -80.803086) (xy 8.653917 -80.729736) (xy 8.618733 -80.652693)
			(xy 8.591031 -80.572655) (xy 8.571063 -80.490346) (xy 8.55901 -80.406511) (xy 8.55498 -80.32191)
			(xy 7.757059 -80.32191) (xy 7.748855 -80.350744) (xy 7.719157 -80.427398) (xy 7.682514 -80.500985)
			(xy 7.639237 -80.570878) (xy 7.589696 -80.636479) (xy 7.534314 -80.697229) (xy 7.473562 -80.75261)
			(xy 7.40796 -80.80215) (xy 7.338066 -80.845425) (xy 7.264478 -80.882066) (xy 7.187823 -80.911762)
			(xy 7.108755 -80.934257) (xy 7.027948 -80.949362) (xy 6.946093 -80.956946) (xy 6.90499 -80.95742)
			(xy 6.858594 -80.95684) (xy 6.766306 -80.947194) (xy 6.675522 -80.927997) (xy 6.587229 -80.899458)
			(xy 6.544564 -80.88122) (xy 6.534624 -80.8774) (xy 6.513356 -80.8774) (xy 6.503416 -80.88122) (xy 6.460755 -80.899469)
			(xy 6.372462 -80.928012) (xy 6.281677 -80.947204) (xy 6.189386 -80.956836) (xy 6.14299 -80.95742)
			(xy 6.096594 -80.95684) (xy 6.004306 -80.947194) (xy 5.913522 -80.927997) (xy 5.825229 -80.899458)
			(xy 5.782564 -80.88122) (xy 5.772624 -80.8774) (xy 5.751356 -80.8774) (xy 5.741416 -80.88122) (xy 5.698755 -80.899469)
			(xy 5.610462 -80.928012) (xy 5.519677 -80.947204) (xy 5.427386 -80.956836) (xy 5.38099 -80.95742)
			(xy 5.334594 -80.95684) (xy 5.242306 -80.947194) (xy 5.151522 -80.927997) (xy 5.063229 -80.899458)
			(xy 5.020564 -80.88122) (xy 5.010624 -80.8774) (xy 4.989356 -80.8774) (xy 4.979416 -80.88122) (xy 4.936755 -80.899469)
			(xy 4.848462 -80.928012) (xy 4.757677 -80.947204) (xy 4.665386 -80.956836) (xy 4.61899 -80.95742)
			(xy 4.577888 -80.956943) (xy 4.496033 -80.949358) (xy 4.415228 -80.934253) (xy 4.336161 -80.911757)
			(xy 4.259508 -80.882061) (xy 4.185921 -80.845419) (xy 4.116029 -80.802144) (xy 4.050428 -80.752605)
			(xy 3.989678 -80.697224) (xy 3.934297 -80.636474) (xy 3.884757 -80.570873) (xy 3.841482 -80.500981)
			(xy 3.80484 -80.427394) (xy 3.775144 -80.35074) (xy 3.752647 -80.271674) (xy 3.737542 -80.190869)
			(xy 3.729957 -80.109014) (xy 3.729482 -80.067912) (xy 3.366008 -80.067912) (xy 3.366008 -84.850732)
			(xy 3.366585 -84.861933) (xy 3.376066 -84.88223) (xy 3.384296 -84.889848) (xy 3.45313 -84.946998)
			(xy 3.474974 -84.95284) (xy 3.48615 -84.950554) (xy 3.503456 -84.94756) (xy 3.538437 -84.944382)
			(xy 3.556 -84.944204) (xy 3.584917 -84.944738) (xy 3.642088 -84.953465) (xy 3.697287 -84.970719)
			(xy 3.749251 -84.996106) (xy 3.796789 -85.029042) (xy 3.838812 -85.068775) (xy 3.85699 -85.09127)
			(xy 3.864528 -85.100062) (xy 3.885301 -85.110244) (xy 3.896868 -85.110828) (xy 3.977132 -85.110828)
			(xy 3.98869 -85.110214) (xy 4.009451 -85.100035) (xy 4.01701 -85.09127) (xy 4.033763 -85.070487)
			(xy 4.072117 -85.033357) (xy 4.115271 -85.001935) (xy 4.162385 -84.976836) (xy 4.212537 -84.95855)
			(xy 4.264748 -84.947433) (xy 4.318 -84.943703) (xy 4.371252 -84.947433) (xy 4.423463 -84.95855) (xy 4.473615 -84.976836)
			(xy 4.520729 -85.001935) (xy 4.563883 -85.033357) (xy 4.602237 -85.070487) (xy 4.61899 -85.09127)
			(xy 4.626528 -85.100062) (xy 4.647301 -85.110244) (xy 4.658868 -85.110828) (xy 4.739132 -85.110828)
			(xy 4.75069 -85.110214) (xy 4.771451 -85.100035) (xy 4.77901 -85.09127) (xy 4.795763 -85.070487)
			(xy 4.834117 -85.033357) (xy 4.877271 -85.001935) (xy 4.924385 -84.976836) (xy 4.974537 -84.95855)
			(xy 5.026748 -84.947433) (xy 5.08 -84.943703) (xy 5.133252 -84.947433) (xy 5.185463 -84.95855) (xy 5.235615 -84.976836)
			(xy 5.282729 -85.001935) (xy 5.325883 -85.033357) (xy 5.364237 -85.070487) (xy 5.38099 -85.09127)
			(xy 5.388528 -85.100062) (xy 5.409301 -85.110244) (xy 5.420868 -85.110828) (xy 5.501132 -85.110828)
			(xy 5.51269 -85.110214) (xy 5.533451 -85.100035) (xy 5.54101 -85.09127) (xy 5.557763 -85.070487)
			(xy 5.596117 -85.033357) (xy 5.639271 -85.001935) (xy 5.686385 -84.976836) (xy 5.736537 -84.95855)
			(xy 5.788748 -84.947433) (xy 5.842 -84.943703) (xy 5.895252 -84.947433) (xy 5.947463 -84.95855) (xy 5.997615 -84.976836)
			(xy 6.044729 -85.001935) (xy 6.087883 -85.033357) (xy 6.126237 -85.070487) (xy 6.14299 -85.09127)
			(xy 6.150528 -85.100062) (xy 6.171301 -85.110244) (xy 6.182868 -85.110828) (xy 6.263132 -85.110828)
			(xy 6.27469 -85.110214) (xy 6.295451 -85.100035) (xy 6.30301 -85.09127) (xy 6.3212 -85.068785) (xy 6.363217 -85.029044)
			(xy 6.410751 -84.9961) (xy 6.462713 -84.970708) (xy 6.517912 -84.95345) (xy 6.575083 -84.944721)
			(xy 6.604 -84.944204) (xy 6.63125 -84.94469) (xy 6.685196 -84.952447) (xy 6.737489 -84.967801) (xy 6.787065 -84.990442)
			(xy 6.832914 -85.019907) (xy 6.874103 -85.055597) (xy 6.909793 -85.096786) (xy 6.939258 -85.142635)
			(xy 6.961899 -85.192211) (xy 6.977253 -85.244504) (xy 6.98501 -85.29845) (xy 6.98501 -85.35295) (xy 6.977253 -85.406896)
			(xy 6.961899 -85.459189) (xy 6.939258 -85.508765) (xy 6.909793 -85.554614) (xy 6.874103 -85.595803)
			(xy 6.832914 -85.631493) (xy 6.787065 -85.660958) (xy 6.737489 -85.683599) (xy 6.685196 -85.698953)
			(xy 6.63125 -85.70671) (xy 6.604 -85.70722) (xy 6.575083 -85.706686) (xy 6.517912 -85.697959) (xy 6.462711 -85.680706)
			(xy 6.410747 -85.655321) (xy 6.363207 -85.622385) (xy 6.321182 -85.582654) (xy 6.30301 -85.560154)
			(xy 6.295466 -85.551373) (xy 6.274695 -85.541207) (xy 6.263132 -85.540596) (xy 6.182868 -85.540596)
			(xy 6.171311 -85.541211) (xy 6.150553 -85.551394) (xy 6.14299 -85.560154) (xy 6.126237 -85.580937)
			(xy 6.087883 -85.618067) (xy 6.044729 -85.649489) (xy 5.997615 -85.674588) (xy 5.947463 -85.692874)
			(xy 5.895252 -85.703991) (xy 5.842 -85.707721) (xy 5.788748 -85.703991) (xy 5.736537 -85.692874)
			(xy 5.686385 -85.674588) (xy 5.639271 -85.649489) (xy 5.596117 -85.618067) (xy 5.557763 -85.580937)
			(xy 5.54101 -85.560154) (xy 5.533466 -85.551373) (xy 5.512695 -85.541207) (xy 5.501132 -85.540596)
			(xy 5.420868 -85.540596) (xy 5.409311 -85.541211) (xy 5.388553 -85.551394) (xy 5.38099 -85.560154)
			(xy 5.364237 -85.580937) (xy 5.325883 -85.618067) (xy 5.282729 -85.649489) (xy 5.235615 -85.674588)
			(xy 5.185463 -85.692874) (xy 5.133252 -85.703991) (xy 5.08 -85.707721) (xy 5.026748 -85.703991) (xy 4.974537 -85.692874)
			(xy 4.924385 -85.674588) (xy 4.877271 -85.649489) (xy 4.834117 -85.618067) (xy 4.795763 -85.580937)
			(xy 4.77901 -85.560154) (xy 4.771466 -85.551373) (xy 4.750695 -85.541207) (xy 4.739132 -85.540596)
			(xy 4.658868 -85.540596) (xy 4.647311 -85.541211) (xy 4.626553 -85.551394) (xy 4.61899 -85.560154)
			(xy 4.602237 -85.580937) (xy 4.563883 -85.618067) (xy 4.520729 -85.649489) (xy 4.473615 -85.674588)
			(xy 4.423463 -85.692874) (xy 4.371252 -85.703991) (xy 4.318 -85.707721) (xy 4.264748 -85.703991)
			(xy 4.212537 -85.692874) (xy 4.162385 -85.674588) (xy 4.115271 -85.649489) (xy 4.072117 -85.618067)
			(xy 4.033763 -85.580937) (xy 4.01701 -85.560154) (xy 4.009466 -85.551373) (xy 3.988695 -85.541207)
			(xy 3.977132 -85.540596) (xy 3.896868 -85.540596) (xy 3.885311 -85.541211) (xy 3.864553 -85.551394)
			(xy 3.85699 -85.560154) (xy 3.838802 -85.582643) (xy 3.796788 -85.622391) (xy 3.749255 -85.655342)
			(xy 3.697293 -85.680739) (xy 3.642092 -85.698001) (xy 3.584918 -85.706732) (xy 3.556 -85.70722) (xy 3.538437 -85.707043)
			(xy 3.503456 -85.703866) (xy 3.48615 -85.70087) (xy 3.474974 -85.698584) (xy 3.45313 -85.704426)
			(xy 3.384296 -85.761576) (xy 3.376038 -85.769178) (xy 3.366532 -85.789481) (xy 3.366008 -85.800692)
			(xy 3.366008 -89.153238) (xy 12.572492 -89.153238) (xy 12.57292 -89.11495) (xy 12.579543 -89.038659)
			(xy 12.592693 -88.96322) (xy 12.612271 -88.889187) (xy 12.624816 -88.85301) (xy 12.627438 -88.844567)
			(xy 12.627451 -88.826904) (xy 12.624816 -88.818466) (xy 12.612242 -88.782297) (xy 12.59265 -88.708266)
			(xy 12.579504 -88.632823) (xy 12.5729 -88.556528) (xy 12.572492 -88.518238) (xy 12.57292 -88.47995)
			(xy 12.579543 -88.403659) (xy 12.592693 -88.32822) (xy 12.612271 -88.254187) (xy 12.624816 -88.21801)
			(xy 12.627438 -88.209567) (xy 12.627451 -88.191904) (xy 12.624816 -88.183466) (xy 12.612242 -88.147297)
			(xy 12.59265 -88.073266) (xy 12.579504 -87.997823) (xy 12.5729 -87.921528) (xy 12.572492 -87.883238)
			(xy 12.572994 -87.842031) (xy 12.580608 -87.759969) (xy 12.595782 -87.678965) (xy 12.618388 -87.599711)
			(xy 12.64823 -87.52289) (xy 12.685053 -87.44916) (xy 12.728541 -87.379154) (xy 12.77832 -87.313472)
			(xy 12.833963 -87.252678) (xy 12.894994 -87.197295) (xy 12.960888 -87.147796) (xy 13.031079 -87.104608)
			(xy 13.104965 -87.0681) (xy 13.181913 -87.038586) (xy 13.221462 -87.027004) (xy 13.231796 -87.023552)
			(xy 13.248429 -87.00951) (xy 13.25781 -86.989868) (xy 13.258546 -86.978998) (xy 13.259811 -86.935841)
			(xy 13.269705 -86.850066) (xy 13.287866 -86.765653) (xy 13.314122 -86.683398) (xy 13.348227 -86.604074)
			(xy 13.38986 -86.52843) (xy 13.438627 -86.457176) (xy 13.494071 -86.390985) (xy 13.555669 -86.330479)
			(xy 13.622842 -86.276227) (xy 13.694956 -86.228741) (xy 13.771333 -86.188468) (xy 13.851253 -86.155787)
			(xy 13.933965 -86.131006) (xy 14.018689 -86.114357) (xy 14.104628 -86.105999) (xy 14.1478 -86.105492)
			(xy 14.188902 -86.105967) (xy 14.270757 -86.113552) (xy 14.351562 -86.128657) (xy 14.430629 -86.151153)
			(xy 14.507283 -86.180849) (xy 14.58087 -86.217491) (xy 14.650762 -86.260766) (xy 14.716363 -86.310306)
			(xy 14.777113 -86.365687) (xy 14.832494 -86.426437) (xy 14.882034 -86.492038) (xy 14.925309 -86.56193)
			(xy 14.961951 -86.635517) (xy 14.991647 -86.712171) (xy 15.014143 -86.791238) (xy 15.029248 -86.872043)
			(xy 15.036833 -86.953898) (xy 15.037308 -86.995) (xy 15.036841 -87.036208) (xy 15.029224 -87.11827)
			(xy 15.014046 -87.199276) (xy 14.991437 -87.27853) (xy 14.961592 -87.355351) (xy 14.924766 -87.429082)
			(xy 14.881275 -87.499088) (xy 14.831493 -87.564769) (xy 14.775847 -87.625562) (xy 14.714815 -87.680946)
			(xy 14.648919 -87.730444) (xy 14.578726 -87.773631) (xy 14.504837 -87.810139) (xy 14.427887 -87.839652)
			(xy 14.388338 -87.851234) (xy 14.377991 -87.854656) (xy 14.361357 -87.86871) (xy 14.351983 -87.888365)
			(xy 14.351254 -87.89924) (xy 14.349729 -87.947607) (xy 14.337494 -88.043602) (xy 14.314912 -88.137703)
			(xy 14.299184 -88.183466) (xy 14.296524 -88.191899) (xy 14.296536 -88.209572) (xy 14.299184 -88.21801)
			(xy 14.311751 -88.254181) (xy 14.331345 -88.328212) (xy 14.344493 -88.403654) (xy 14.351099 -88.479948)
			(xy 14.351508 -88.518238) (xy 14.351073 -88.556526) (xy 14.344452 -88.632816) (xy 14.331304 -88.708256)
			(xy 14.311728 -88.782288) (xy 14.299184 -88.818466) (xy 14.296524 -88.826899) (xy 14.296536 -88.844572)
			(xy 14.299184 -88.85301) (xy 14.311751 -88.889181) (xy 14.331345 -88.963212) (xy 14.344493 -89.038654)
			(xy 14.351099 -89.114948) (xy 14.351508 -89.153238) (xy 14.351004 -89.195586) (xy 14.342953 -89.2799)
			(xy 14.326924 -89.363066) (xy 14.303063 -89.444333) (xy 14.271584 -89.522963) (xy 14.232773 -89.598244)
			(xy 14.186983 -89.669496) (xy 14.134627 -89.736072) (xy 14.076179 -89.79737) (xy 14.012169 -89.852835)
			(xy 13.943177 -89.901964) (xy 13.869827 -89.944313) (xy 13.792784 -89.979497) (xy 13.712745 -90.007199)
			(xy 13.630436 -90.027167) (xy 13.546601 -90.03922) (xy 13.462 -90.043251) (xy 13.377399 -90.03922)
			(xy 13.293564 -90.027167) (xy 13.211255 -90.007199) (xy 13.131216 -89.979497) (xy 13.054173 -89.944313)
			(xy 12.980823 -89.901964) (xy 12.911831 -89.852835) (xy 12.847821 -89.79737) (xy 12.789373 -89.736072)
			(xy 12.737017 -89.669496) (xy 12.691227 -89.598244) (xy 12.652416 -89.522963) (xy 12.620937 -89.444333)
			(xy 12.597076 -89.363066) (xy 12.581047 -89.2799) (xy 12.572996 -89.195586) (xy 12.572492 -89.153238)
			(xy 3.366008 -89.153238) (xy 3.366008 -91.878912) (xy 3.555492 -91.878912) (xy 3.556079 -91.832517)
			(xy 3.565723 -91.740228) (xy 3.584918 -91.649445) (xy 3.613455 -91.561151) (xy 3.631692 -91.518486)
			(xy 3.63559 -91.508562) (xy 3.635594 -91.48726) (xy 3.631692 -91.477338) (xy 3.613451 -91.434674)
			(xy 3.584906 -91.346382) (xy 3.565712 -91.255598) (xy 3.556077 -91.163308) (xy 3.555492 -91.116912)
			(xy 3.555964 -91.075809) (xy 3.563548 -90.993954) (xy 3.578652 -90.913147) (xy 3.601148 -90.834079)
			(xy 3.630843 -90.757424) (xy 3.667485 -90.683836) (xy 3.71076 -90.613943) (xy 3.7603 -90.548341)
			(xy 3.815681 -90.487589) (xy 3.876432 -90.432207) (xy 3.942033 -90.382667) (xy 4.011926 -90.339391)
			(xy 4.085513 -90.302748) (xy 4.162168 -90.273052) (xy 4.241236 -90.250555) (xy 4.322042 -90.235449)
			(xy 4.403897 -90.227864) (xy 4.445 -90.227404) (xy 4.491396 -90.227986) (xy 4.583684 -90.237631)
			(xy 4.674468 -90.256827) (xy 4.762761 -90.285366) (xy 4.805426 -90.303604) (xy 4.815366 -90.307424)
			(xy 4.836634 -90.307424) (xy 4.846574 -90.303604) (xy 4.889236 -90.28536) (xy 4.977529 -90.256816)
			(xy 5.068314 -90.237622) (xy 5.160604 -90.227989) (xy 5.207 -90.227404) (xy 5.253396 -90.227986)
			(xy 5.345684 -90.237631) (xy 5.436468 -90.256827) (xy 5.524761 -90.285366) (xy 5.567426 -90.303604)
			(xy 5.577366 -90.307424) (xy 5.598634 -90.307424) (xy 5.608574 -90.303604) (xy 5.651236 -90.28536)
			(xy 5.739529 -90.256816) (xy 5.830314 -90.237622) (xy 5.922604 -90.227989) (xy 5.969 -90.227404)
			(xy 6.015396 -90.227986) (xy 6.107684 -90.237631) (xy 6.198468 -90.256827) (xy 6.286761 -90.285366)
			(xy 6.329426 -90.303604) (xy 6.339366 -90.307424) (xy 6.360634 -90.307424) (xy 6.370574 -90.303604)
			(xy 6.413236 -90.28536) (xy 6.501529 -90.256816) (xy 6.592314 -90.237622) (xy 6.684604 -90.227989)
			(xy 6.731 -90.227404) (xy 6.772103 -90.227862) (xy 6.853959 -90.235447) (xy 6.934766 -90.250553)
			(xy 7.013834 -90.27305) (xy 7.090489 -90.302746) (xy 7.164077 -90.339389) (xy 7.233971 -90.382665)
			(xy 7.299573 -90.432205) (xy 7.360324 -90.487587) (xy 7.415706 -90.548339) (xy 7.465246 -90.613941)
			(xy 7.508522 -90.683834) (xy 7.545165 -90.757423) (xy 7.574861 -90.834078) (xy 7.597358 -90.913146)
			(xy 7.612463 -90.993953) (xy 7.620048 -91.075809) (xy 7.620508 -91.116912) (xy 7.619929 -91.163308)
			(xy 7.610283 -91.255596) (xy 7.591086 -91.34638) (xy 7.562546 -91.434673) (xy 7.544308 -91.477338)
			(xy 7.540396 -91.487258) (xy 7.5404 -91.508564) (xy 7.544308 -91.518486) (xy 7.562557 -91.561147)
			(xy 7.5911 -91.64944) (xy 7.610292 -91.740225) (xy 7.619924 -91.832516) (xy 7.620508 -91.878912)
			(xy 7.620045 -91.920015) (xy 7.612459 -92.001869) (xy 7.597353 -92.082675) (xy 7.574855 -92.161742)
			(xy 7.545158 -92.238396) (xy 7.508516 -92.311983) (xy 7.465239 -92.381875) (xy 7.415699 -92.447476)
			(xy 7.360317 -92.508226) (xy 7.299566 -92.563607) (xy 7.233965 -92.613146) (xy 7.164072 -92.656421)
			(xy 7.090485 -92.693063) (xy 7.01383 -92.722759) (xy 6.934763 -92.745255) (xy 6.853957 -92.76036)
			(xy 6.772103 -92.767945) (xy 6.731 -92.76842) (xy 6.684604 -92.767836) (xy 6.592316 -92.758191) (xy 6.501532 -92.738996)
			(xy 6.413239 -92.710458) (xy 6.370574 -92.69222) (xy 6.360634 -92.6884) (xy 6.339366 -92.6884) (xy 6.329426 -92.69222)
			(xy 6.286764 -92.710466) (xy 6.198472 -92.739009) (xy 6.107686 -92.758202) (xy 6.015396 -92.767835)
			(xy 5.969 -92.76842) (xy 5.922604 -92.767836) (xy 5.830316 -92.758191) (xy 5.739532 -92.738996) (xy 5.651239 -92.710458)
			(xy 5.608574 -92.69222) (xy 5.598634 -92.6884) (xy 5.577366 -92.6884) (xy 5.567426 -92.69222) (xy 5.524764 -92.710466)
			(xy 5.436472 -92.739009) (xy 5.345686 -92.758202) (xy 5.253396 -92.767835) (xy 5.207 -92.76842) (xy 5.160604 -92.767836)
			(xy 5.068316 -92.758191) (xy 4.977532 -92.738996) (xy 4.889239 -92.710458) (xy 4.846574 -92.69222)
			(xy 4.836634 -92.6884) (xy 4.815366 -92.6884) (xy 4.805426 -92.69222) (xy 4.762764 -92.710466) (xy 4.674472 -92.739009)
			(xy 4.583686 -92.758202) (xy 4.491396 -92.767835) (xy 4.445 -92.76842) (xy 4.403898 -92.767943) (xy 4.322043 -92.760358)
			(xy 4.241238 -92.745253) (xy 4.162171 -92.722757) (xy 4.085518 -92.693061) (xy 4.011931 -92.656419)
			(xy 3.942039 -92.613144) (xy 3.876438 -92.563605) (xy 3.815688 -92.508224) (xy 3.760307 -92.447474)
			(xy 3.710767 -92.381873) (xy 3.667492 -92.311981) (xy 3.63085 -92.238394) (xy 3.601154 -92.16174)
			(xy 3.578657 -92.082674) (xy 3.563552 -92.001869) (xy 3.555967 -91.920014) (xy 3.555492 -91.878912)
			(xy 3.366008 -91.878912) (xy 3.366008 -93.979238) (xy 12.572492 -93.979238) (xy 12.57292 -93.94095)
			(xy 12.579543 -93.864659) (xy 12.592693 -93.78922) (xy 12.612271 -93.715187) (xy 12.624816 -93.67901)
			(xy 12.627438 -93.670567) (xy 12.627451 -93.652904) (xy 12.624816 -93.644466) (xy 12.612242 -93.608297)
			(xy 12.59265 -93.534266) (xy 12.579504 -93.458823) (xy 12.5729 -93.382528) (xy 12.572492 -93.344238)
			(xy 12.57292 -93.30595) (xy 12.579543 -93.229659) (xy 12.592693 -93.15422) (xy 12.612271 -93.080187)
			(xy 12.624816 -93.04401) (xy 12.627438 -93.035567) (xy 12.627451 -93.017904) (xy 12.624816 -93.009466)
			(xy 12.612242 -92.973297) (xy 12.59265 -92.899266) (xy 12.579504 -92.823823) (xy 12.5729 -92.747528)
			(xy 12.572492 -92.709238) (xy 12.572996 -92.66689) (xy 12.581047 -92.582576) (xy 12.597076 -92.49941)
			(xy 12.620937 -92.418143) (xy 12.652416 -92.339513) (xy 12.691227 -92.264232) (xy 12.737017 -92.19298)
			(xy 12.789373 -92.126404) (xy 12.847821 -92.065106) (xy 12.911831 -92.009641) (xy 12.980823 -91.960512)
			(xy 13.054173 -91.918163) (xy 13.131216 -91.882979) (xy 13.211255 -91.855277) (xy 13.293564 -91.835309)
			(xy 13.377399 -91.823256) (xy 13.462 -91.819226) (xy 13.546601 -91.823256) (xy 13.630436 -91.835309)
			(xy 13.712745 -91.855277) (xy 13.792784 -91.882979) (xy 13.869827 -91.918163) (xy 13.943177 -91.960512)
			(xy 14.012169 -92.009641) (xy 14.076179 -92.065106) (xy 14.134627 -92.126404) (xy 14.186983 -92.19298)
			(xy 14.232773 -92.264232) (xy 14.271584 -92.339513) (xy 14.303063 -92.418143) (xy 14.326924 -92.49941)
			(xy 14.342953 -92.582576) (xy 14.351004 -92.66689) (xy 14.351508 -92.709238) (xy 14.351073 -92.747526)
			(xy 14.344452 -92.823816) (xy 14.331304 -92.899256) (xy 14.311728 -92.973288) (xy 14.299184 -93.009466)
			(xy 14.296524 -93.017899) (xy 14.296536 -93.035572) (xy 14.299184 -93.04401) (xy 14.311751 -93.080181)
			(xy 14.331345 -93.154212) (xy 14.344493 -93.229654) (xy 14.351099 -93.305948) (xy 14.351508 -93.344238)
			(xy 14.351073 -93.382526) (xy 14.344452 -93.458816) (xy 14.331304 -93.534256) (xy 14.311728 -93.608288)
			(xy 14.299184 -93.644466) (xy 14.296524 -93.652899) (xy 14.296536 -93.670572) (xy 14.299184 -93.67901)
			(xy 14.311751 -93.715181) (xy 14.331345 -93.789212) (xy 14.344493 -93.864654) (xy 14.351099 -93.940948)
			(xy 14.351508 -93.979238) (xy 14.351004 -94.021586) (xy 14.342953 -94.1059) (xy 14.342741 -94.107)
			(xy 18.523204 -94.107) (xy 18.523669 -94.07963) (xy 18.531487 -94.025451) (xy 18.546976 -93.972947)
			(xy 18.569818 -93.923201) (xy 18.599543 -93.877234) (xy 18.617184 -93.856302) (xy 18.62328 -93.84919)
			(xy 18.62963 -93.832172) (xy 18.62963 -93.746828) (xy 18.62328 -93.72981) (xy 18.617184 -93.722698)
			(xy 18.599545 -93.701764) (xy 18.569824 -93.655796) (xy 18.546981 -93.606049) (xy 18.531486 -93.553548)
			(xy 18.523659 -93.49937) (xy 18.523659 -93.44463) (xy 18.531486 -93.390452) (xy 18.546981 -93.337951)
			(xy 18.569824 -93.288204) (xy 18.599545 -93.242236) (xy 18.617184 -93.221302) (xy 18.62328 -93.21419)
			(xy 18.62963 -93.197172) (xy 18.62963 -93.111828) (xy 18.62328 -93.09481) (xy 18.617184 -93.087698)
			(xy 18.599528 -93.06678) (xy 18.569819 -93.020803) (xy 18.546987 -92.971052) (xy 18.5315 -92.918548)
			(xy 18.523676 -92.86437) (xy 18.523204 -92.837) (xy 18.52369 -92.809749) (xy 18.531446 -92.755801)
			(xy 18.546801 -92.703506) (xy 18.569443 -92.653929) (xy 18.598909 -92.608079) (xy 18.6346 -92.566888)
			(xy 18.675791 -92.531197) (xy 18.721641 -92.501731) (xy 18.771218 -92.479089) (xy 18.823513 -92.463734)
			(xy 18.877461 -92.455978) (xy 18.931963 -92.455978) (xy 18.985911 -92.463734) (xy 19.038206 -92.479089)
			(xy 19.087783 -92.501731) (xy 19.133633 -92.531197) (xy 19.174824 -92.566888) (xy 19.210515 -92.608079)
			(xy 19.239981 -92.653929) (xy 19.262623 -92.703506) (xy 19.277978 -92.755801) (xy 19.285734 -92.809749)
			(xy 19.28622 -92.837) (xy 19.285773 -92.864371) (xy 19.277954 -92.918552) (xy 19.262461 -92.971056)
			(xy 19.239615 -93.020803) (xy 19.209884 -93.066768) (xy 19.19224 -93.087698) (xy 19.186144 -93.09481)
			(xy 19.179794 -93.111828) (xy 19.179794 -93.197172) (xy 19.186144 -93.21419) (xy 19.19224 -93.221302)
			(xy 19.209882 -93.242234) (xy 19.239609 -93.288201) (xy 19.262457 -93.337947) (xy 19.277954 -93.39045)
			(xy 19.285784 -93.444629) (xy 19.285784 -93.499371) (xy 19.277954 -93.55355) (xy 19.262457 -93.606053)
			(xy 19.239609 -93.655799) (xy 19.209882 -93.701766) (xy 19.19224 -93.722698) (xy 19.186144 -93.72981)
			(xy 19.179794 -93.746828) (xy 19.179794 -93.832172) (xy 19.186144 -93.84919) (xy 19.19224 -93.856302)
			(xy 19.2099 -93.877217) (xy 19.239608 -93.923195) (xy 19.262439 -93.972947) (xy 19.277925 -94.025451)
			(xy 19.285749 -94.07963) (xy 19.28622 -94.107) (xy 19.285734 -94.134251) (xy 19.277978 -94.188199)
			(xy 19.262623 -94.240494) (xy 19.239981 -94.290071) (xy 19.210515 -94.335921) (xy 19.174824 -94.377112)
			(xy 19.133633 -94.412803) (xy 19.087783 -94.442269) (xy 19.038206 -94.464911) (xy 18.985911 -94.480266)
			(xy 18.931963 -94.488022) (xy 18.877461 -94.488022) (xy 18.823513 -94.480266) (xy 18.771218 -94.464911)
			(xy 18.721641 -94.442269) (xy 18.675791 -94.412803) (xy 18.6346 -94.377112) (xy 18.598909 -94.335921)
			(xy 18.569443 -94.290071) (xy 18.546801 -94.240494) (xy 18.531446 -94.188199) (xy 18.52369 -94.134251)
			(xy 18.523204 -94.107) (xy 14.342741 -94.107) (xy 14.326924 -94.189066) (xy 14.303063 -94.270333)
			(xy 14.271584 -94.348963) (xy 14.232773 -94.424244) (xy 14.186983 -94.495496) (xy 14.134627 -94.562072)
			(xy 14.076179 -94.62337) (xy 14.012169 -94.678835) (xy 13.943177 -94.727964) (xy 13.869827 -94.770313)
			(xy 13.792784 -94.805497) (xy 13.712745 -94.833199) (xy 13.630436 -94.853167) (xy 13.546601 -94.86522)
			(xy 13.462 -94.869251) (xy 13.377399 -94.86522) (xy 13.293564 -94.853167) (xy 13.211255 -94.833199)
			(xy 13.131216 -94.805497) (xy 13.054173 -94.770313) (xy 12.980823 -94.727964) (xy 12.911831 -94.678835)
			(xy 12.847821 -94.62337) (xy 12.789373 -94.562072) (xy 12.737017 -94.495496) (xy 12.691227 -94.424244)
			(xy 12.652416 -94.348963) (xy 12.620937 -94.270333) (xy 12.597076 -94.189066) (xy 12.581047 -94.1059)
			(xy 12.572996 -94.021586) (xy 12.572492 -93.979238) (xy 3.366008 -93.979238) (xy 3.366008 -104.749912)
			(xy 5.887172 -104.749912) (xy 5.887172 -104.670048) (xy 5.895 -104.590568) (xy 5.910581 -104.512238)
			(xy 5.933765 -104.435813) (xy 5.964327 -104.362027) (xy 6.001975 -104.291593) (xy 6.046346 -104.225189)
			(xy 6.097011 -104.163453) (xy 6.153484 -104.10698) (xy 6.21522 -104.056315) (xy 6.281625 -104.011944)
			(xy 6.352059 -103.974297) (xy 6.425844 -103.943734) (xy 6.50227 -103.920551) (xy 6.5806 -103.90497)
			(xy 6.66008 -103.897142) (xy 6.700012 -103.896668) (xy 6.714566 -103.896723) (xy 6.743656 -103.897739)
			(xy 6.758178 -103.8987) (xy 6.774434 -103.89997) (xy 6.801866 -103.88346) (xy 6.853428 -103.766112)
			(xy 6.847078 -103.73487) (xy 6.835394 -103.723694) (xy 6.799432 -103.688979) (xy 6.732509 -103.614723)
			(xy 6.671691 -103.535388) (xy 6.617362 -103.451477) (xy 6.569865 -103.363518) (xy 6.5295 -103.272067)
			(xy 6.496521 -103.1777) (xy 6.471137 -103.081013) (xy 6.453507 -102.982617) (xy 6.443743 -102.883131)
			(xy 6.441906 -102.783184) (xy 6.448009 -102.683407) (xy 6.462012 -102.584429) (xy 6.483827 -102.486875)
			(xy 6.513317 -102.391361) (xy 6.550295 -102.298488) (xy 6.594528 -102.208843) (xy 6.645737 -102.122993)
			(xy 6.703599 -102.041478) (xy 6.767749 -101.964813) (xy 6.837781 -101.893482) (xy 6.913255 -101.827934)
			(xy 6.993693 -101.768584) (xy 7.078588 -101.715806) (xy 7.167405 -101.669934) (xy 7.259583 -101.631255)
			(xy 7.354539 -101.600016) (xy 7.451676 -101.576412) (xy 7.55038 -101.560593) (xy 7.650028 -101.552658)
			(xy 7.749992 -101.552658) (xy 7.84964 -101.560593) (xy 7.948344 -101.576412) (xy 8.045481 -101.600016)
			(xy 8.140437 -101.631255) (xy 8.232615 -101.669934) (xy 8.321432 -101.715806) (xy 8.406327 -101.768584)
			(xy 8.486765 -101.827934) (xy 8.562239 -101.893482) (xy 8.632271 -101.964813) (xy 8.696421 -102.041478)
			(xy 8.754283 -102.122993) (xy 8.805492 -102.208843) (xy 8.849725 -102.298488) (xy 8.886703 -102.391361)
			(xy 8.916193 -102.486875) (xy 8.938008 -102.584429) (xy 8.952011 -102.683407) (xy 8.958114 -102.783184)
			(xy 8.956277 -102.883131) (xy 8.946513 -102.982617) (xy 8.928883 -103.081013) (xy 8.903499 -103.1777)
			(xy 8.87052 -103.272067) (xy 8.830155 -103.363518) (xy 8.782658 -103.451477) (xy 8.728329 -103.535388)
			(xy 8.667511 -103.614723) (xy 8.600588 -103.688979) (xy 8.564626 -103.723694) (xy 8.552942 -103.73487)
			(xy 8.546592 -103.766112) (xy 8.598154 -103.88346) (xy 8.625586 -103.89997) (xy 8.641842 -103.8987)
			(xy 8.656364 -103.897734) (xy 8.685454 -103.896719) (xy 8.700008 -103.896668) (xy 8.73994 -103.897175)
			(xy 8.819419 -103.905003) (xy 8.897747 -103.920585) (xy 8.974172 -103.943769) (xy 9.047955 -103.974332)
			(xy 9.118388 -104.01198) (xy 9.184792 -104.056351) (xy 9.246526 -104.107017) (xy 9.302998 -104.163489)
			(xy 9.353662 -104.225225) (xy 9.398031 -104.29163) (xy 9.435677 -104.362064) (xy 9.466238 -104.435848)
			(xy 9.48942 -104.512273) (xy 9.505 -104.590603) (xy 9.512826 -104.670082) (xy 9.512825 -104.749945)
			(xy 9.504996 -104.829424) (xy 9.489414 -104.907752) (xy 9.466229 -104.984177) (xy 9.435666 -105.05796)
			(xy 9.398017 -105.128393) (xy 9.353646 -105.194796) (xy 9.30298 -105.25653) (xy 9.246507 -105.313001)
			(xy 9.18477 -105.363665) (xy 9.118365 -105.408033) (xy 9.047931 -105.445679) (xy 8.974146 -105.47624)
			(xy 8.897721 -105.499422) (xy 8.819392 -105.515) (xy 8.739913 -105.522827) (xy 8.66005 -105.522825)
			(xy 8.580571 -105.514995) (xy 8.502242 -105.499413) (xy 8.425818 -105.476228) (xy 8.352035 -105.445663)
			(xy 8.281603 -105.408014) (xy 8.2152 -105.363643) (xy 8.153466 -105.312976) (xy 8.096995 -105.256503)
			(xy 8.046332 -105.194766) (xy 8.001964 -105.128361) (xy 7.964318 -105.057927) (xy 7.933758 -104.984141)
			(xy 7.910577 -104.907716) (xy 7.894999 -104.829387) (xy 7.887173 -104.749908) (xy 7.8867 -104.709976)
			(xy 7.887178 -104.670847) (xy 7.894689 -104.592949) (xy 7.909648 -104.516134) (xy 7.931919 -104.441111)
			(xy 7.961294 -104.368574) (xy 7.997501 -104.299195) (xy 8.040206 -104.233615) (xy 8.064246 -104.202738)
			(xy 8.074406 -104.190038) (xy 8.076438 -104.158034) (xy 8.008874 -104.049068) (xy 7.97941 -104.036622)
			(xy 7.963662 -104.039924) (xy 7.911593 -104.050518) (xy 7.80618 -104.063947) (xy 7.70001 -104.068434)
			(xy 7.59384 -104.063947) (xy 7.488427 -104.050518) (xy 7.436358 -104.039924) (xy 7.42061 -104.036622)
			(xy 7.391146 -104.049068) (xy 7.323582 -104.158034) (xy 7.325614 -104.190038) (xy 7.335774 -104.202738)
			(xy 7.359812 -104.233616) (xy 7.402515 -104.299198) (xy 7.438721 -104.368577) (xy 7.468097 -104.441113)
			(xy 7.49037 -104.516136) (xy 7.505335 -104.59295) (xy 7.512853 -104.670847) (xy 7.51332 -104.709976)
			(xy 7.512848 -104.749908) (xy 7.50502 -104.829388) (xy 7.48944 -104.907718) (xy 7.466257 -104.984144)
			(xy 7.435694 -105.057929) (xy 7.398047 -105.128363) (xy 7.353677 -105.194768) (xy 7.303011 -105.256504)
			(xy 7.246539 -105.312977) (xy 7.184803 -105.363643) (xy 7.118398 -105.408014) (xy 7.047964 -105.445662)
			(xy 6.974179 -105.476225) (xy 6.897754 -105.499408) (xy 6.819424 -105.514989) (xy 6.739944 -105.522818)
			(xy 6.66008 -105.522818) (xy 6.5806 -105.51499) (xy 6.50227 -105.499409) (xy 6.425844 -105.476226)
			(xy 6.352059 -105.445663) (xy 6.281625 -105.408016) (xy 6.21522 -105.363645) (xy 6.153484 -105.31298)
			(xy 6.097011 -105.256507) (xy 6.046346 -105.194771) (xy 6.001975 -105.128367) (xy 5.964327 -105.057933)
			(xy 5.933765 -104.984147) (xy 5.910581 -104.907722) (xy 5.895 -104.829392) (xy 5.887172 -104.749912)
			(xy 3.366008 -104.749912) (xy 3.366008 -108.709969) (xy 5.378132 -108.709969) (xy 5.382265 -108.605536)
			(xy 5.394637 -108.501755) (xy 5.41517 -108.399277) (xy 5.443738 -108.298742) (xy 5.48016 -108.200779)
			(xy 5.524209 -108.105999) (xy 5.57561 -108.014997) (xy 5.634041 -107.928341) (xy 5.699136 -107.846574)
			(xy 5.77049 -107.770205) (xy 5.847655 -107.699714) (xy 5.930148 -107.635541) (xy 6.017455 -107.578087)
			(xy 6.109028 -107.527711) (xy 6.156452 -107.505754) (xy 6.16839 -107.500166) (xy 6.184138 -107.479338)
			(xy 6.199124 -107.367832) (xy 6.189726 -107.343448) (xy 6.179566 -107.335066) (xy 6.149428 -107.309353)
			(xy 6.09377 -107.25297) (xy 6.043857 -107.191443) (xy 6.000161 -107.125355) (xy 5.963098 -107.055333)
			(xy 5.933017 -106.982038) (xy 5.910205 -106.906167) (xy 5.894876 -106.828437) (xy 5.887177 -106.749585)
			(xy 5.886704 -106.709972) (xy 5.887194 -106.670041) (xy 5.895022 -106.590563) (xy 5.910602 -106.512235)
			(xy 5.933785 -106.435812) (xy 5.964347 -106.362028) (xy 6.001994 -106.291596) (xy 6.046363 -106.225193)
			(xy 6.097027 -106.163458) (xy 6.153498 -106.106987) (xy 6.215233 -106.056323) (xy 6.281636 -106.011954)
			(xy 6.352068 -105.974307) (xy 6.425852 -105.943745) (xy 6.502275 -105.920562) (xy 6.580603 -105.904982)
			(xy 6.660081 -105.897154) (xy 6.739943 -105.897154) (xy 6.819421 -105.904982) (xy 6.897749 -105.920562)
			(xy 6.974172 -105.943745) (xy 7.047956 -105.974307) (xy 7.118388 -106.011954) (xy 7.184791 -106.056323)
			(xy 7.246526 -106.106987) (xy 7.302997 -106.163458) (xy 7.353661 -106.225193) (xy 7.39803 -106.291596)
			(xy 7.435677 -106.362028) (xy 7.466239 -106.435812) (xy 7.489422 -106.512235) (xy 7.505002 -106.590563)
			(xy 7.51283 -106.670041) (xy 7.51332 -106.709972) (xy 7.51287 -106.749585) (xy 7.505162 -106.828437)
			(xy 7.489826 -106.906165) (xy 7.467009 -106.982035) (xy 7.436924 -107.055328) (xy 7.399858 -107.125349)
			(xy 7.356162 -107.191437) (xy 7.306249 -107.252964) (xy 7.250592 -107.309348) (xy 7.220458 -107.335066)
			(xy 7.210298 -107.343448) (xy 7.2009 -107.367832) (xy 7.215886 -107.479338) (xy 7.231634 -107.500166)
			(xy 7.243572 -107.505754) (xy 7.291716 -107.528066) (xy 7.384626 -107.579344) (xy 7.473123 -107.637911)
			(xy 7.556635 -107.703388) (xy 7.634626 -107.775354) (xy 7.706592 -107.853345) (xy 7.772069 -107.936857)
			(xy 7.830636 -108.025354) (xy 7.881914 -108.118264) (xy 7.904226 -108.166408) (xy 7.909814 -108.178346)
			(xy 7.930642 -108.194094) (xy 8.042148 -108.20908) (xy 8.066532 -108.199682) (xy 8.074914 -108.189522)
			(xy 8.100627 -108.159384) (xy 8.157011 -108.103728) (xy 8.218539 -108.053816) (xy 8.284627 -108.010121)
			(xy 8.354649 -107.973058) (xy 8.427943 -107.942977) (xy 8.503814 -107.920164) (xy 8.581543 -107.904834)
			(xy 8.660395 -107.897134) (xy 8.700008 -107.89666) (xy 8.73994 -107.897138) (xy 8.819419 -107.904966)
			(xy 8.897749 -107.920547) (xy 8.974174 -107.94373) (xy 9.047958 -107.974292) (xy 9.118392 -108.011939)
			(xy 9.184796 -108.056309) (xy 9.246532 -108.106974) (xy 9.303004 -108.163447) (xy 9.353669 -108.225182)
			(xy 9.398039 -108.291586) (xy 9.435687 -108.36202) (xy 9.46625 -108.435805) (xy 9.489433 -108.51223)
			(xy 9.505014 -108.590559) (xy 9.512842 -108.670038) (xy 9.512842 -108.749902) (xy 9.505014 -108.829381)
			(xy 9.489433 -108.90771) (xy 9.46625 -108.984135) (xy 9.435687 -109.05792) (xy 9.398039 -109.128354)
			(xy 9.353669 -109.194758) (xy 9.303004 -109.256493) (xy 9.246532 -109.312966) (xy 9.184796 -109.363631)
			(xy 9.118392 -109.408001) (xy 9.047958 -109.445648) (xy 8.974174 -109.47621) (xy 8.897749 -109.499393)
			(xy 8.819419 -109.514974) (xy 8.73994 -109.522802) (xy 8.700008 -109.523276) (xy 8.660395 -109.522784)
			(xy 8.581545 -109.515083) (xy 8.503817 -109.499755) (xy 8.427947 -109.476943) (xy 8.354654 -109.446864)
			(xy 8.284632 -109.409803) (xy 8.218544 -109.36611) (xy 8.157017 -109.316201) (xy 8.100632 -109.260546)
			(xy 8.074914 -109.230414) (xy 8.066532 -109.220254) (xy 8.042148 -109.210856) (xy 7.930642 -109.225842)
			(xy 7.909814 -109.24159) (xy 7.904226 -109.253528) (xy 7.881895 -109.301663) (xy 7.83062 -109.394573)
			(xy 7.772056 -109.483071) (xy 7.706581 -109.566584) (xy 7.634617 -109.644576) (xy 7.556629 -109.716543)
			(xy 7.473118 -109.782022) (xy 7.384623 -109.840589) (xy 7.291715 -109.891869) (xy 7.243572 -109.914182)
			(xy 7.231634 -109.91977) (xy 7.215886 -109.940598) (xy 7.2009 -110.052104) (xy 7.210298 -110.076488)
			(xy 7.220458 -110.08487) (xy 7.250594 -110.110585) (xy 7.306252 -110.166968) (xy 7.356164 -110.228495)
			(xy 7.399859 -110.294583) (xy 7.436923 -110.364605) (xy 7.467004 -110.437899) (xy 7.489817 -110.51377)
			(xy 7.505146 -110.591499) (xy 7.512847 -110.670351) (xy 7.51332 -110.709964) (xy 7.51283 -110.749895)
			(xy 7.505002 -110.829373) (xy 7.489422 -110.907701) (xy 7.466239 -110.984124) (xy 7.435677 -111.057908)
			(xy 7.39803 -111.12834) (xy 7.353661 -111.194743) (xy 7.302997 -111.256478) (xy 7.246526 -111.312949)
			(xy 7.184791 -111.363613) (xy 7.118388 -111.407982) (xy 7.047956 -111.445629) (xy 6.974172 -111.476191)
			(xy 6.897749 -111.499374) (xy 6.819421 -111.514954) (xy 6.739943 -111.522782) (xy 6.660081 -111.522782)
			(xy 6.580603 -111.514954) (xy 6.502275 -111.499374) (xy 6.425852 -111.476191) (xy 6.352068 -111.445629)
			(xy 6.281636 -111.407982) (xy 6.215233 -111.363613) (xy 6.153498 -111.312949) (xy 6.097027 -111.256478)
			(xy 6.046363 -111.194743) (xy 6.001994 -111.12834) (xy 5.964347 -111.057908) (xy 5.933785 -110.984124)
			(xy 5.910602 -110.907701) (xy 5.895022 -110.829373) (xy 5.887194 -110.749895) (xy 5.886704 -110.709964)
			(xy 5.887172 -110.670351) (xy 5.894876 -110.5915) (xy 5.910209 -110.513772) (xy 5.933024 -110.437902)
			(xy 5.963106 -110.364609) (xy 6.00017 -110.294587) (xy 6.043865 -110.228499) (xy 6.093777 -110.166972)
			(xy 6.149433 -110.110588) (xy 6.179566 -110.08487) (xy 6.189726 -110.076488) (xy 6.199124 -110.052104)
			(xy 6.184138 -109.940598) (xy 6.16839 -109.91977) (xy 6.156452 -109.914182) (xy 6.109027 -109.892228)
			(xy 6.017453 -109.841853) (xy 5.930147 -109.784398) (xy 5.847653 -109.720225) (xy 5.770489 -109.649733)
			(xy 5.699135 -109.573365) (xy 5.63404 -109.491597) (xy 5.575609 -109.404941) (xy 5.524208 -109.313939)
			(xy 5.480159 -109.21916) (xy 5.443737 -109.121196) (xy 5.41517 -109.020661) (xy 5.394636 -108.918183)
			(xy 5.382264 -108.814403) (xy 5.378132 -108.709969) (xy 3.366008 -108.709969) (xy 3.366008 -114.709956)
			(xy 5.378133 -114.709956) (xy 5.382265 -114.605523) (xy 5.394637 -114.501742) (xy 5.415171 -114.399264)
			(xy 5.443738 -114.298729) (xy 5.48016 -114.200766) (xy 5.524209 -114.105987) (xy 5.57561 -114.014985)
			(xy 5.634041 -113.928329) (xy 5.699137 -113.846561) (xy 5.77049 -113.770193) (xy 5.847655 -113.699702)
			(xy 5.930148 -113.635528) (xy 6.017455 -113.578074) (xy 6.109028 -113.527699) (xy 6.156452 -113.505742)
			(xy 6.16839 -113.500154) (xy 6.184138 -113.479326) (xy 6.199124 -113.36782) (xy 6.189726 -113.343436)
			(xy 6.179566 -113.335054) (xy 6.149433 -113.309336) (xy 6.093775 -113.252953) (xy 6.043862 -113.191427)
			(xy 6.000167 -113.12534) (xy 5.963103 -113.055317) (xy 5.933022 -112.982024) (xy 5.910208 -112.906153)
			(xy 5.894878 -112.828424) (xy 5.887177 -112.749573) (xy 5.886704 -112.70996) (xy 5.887144 -112.670028)
			(xy 5.894976 -112.590548) (xy 5.91056 -112.512219) (xy 5.933747 -112.435794) (xy 5.964312 -112.36201)
			(xy 6.001963 -112.291577) (xy 6.046336 -112.225174) (xy 6.097004 -112.16344) (xy 6.153478 -112.106969)
			(xy 6.215216 -112.056305) (xy 6.281622 -112.011936) (xy 6.352057 -111.97429) (xy 6.425843 -111.943729)
			(xy 6.502269 -111.920547) (xy 6.5806 -111.904968) (xy 6.66008 -111.897141) (xy 6.700012 -111.896652)
			(xy 6.739625 -111.89712) (xy 6.818476 -111.904822) (xy 6.896205 -111.920154) (xy 6.972076 -111.942968)
			(xy 7.045369 -111.97305) (xy 7.115391 -112.010114) (xy 7.181479 -112.05381) (xy 7.243005 -112.103723)
			(xy 7.299389 -112.15938) (xy 7.325106 -112.189514) (xy 7.333488 -112.199674) (xy 7.357872 -112.209072)
			(xy 7.469378 -112.194086) (xy 7.490206 -112.178338) (xy 7.495794 -112.1664) (xy 7.518086 -112.118246)
			(xy 7.569367 -112.025337) (xy 7.627937 -111.936842) (xy 7.693417 -111.85333) (xy 7.765385 -111.77534)
			(xy 7.843378 -111.703376) (xy 7.926893 -111.6379) (xy 8.015392 -111.579334) (xy 8.108303 -111.528058)
			(xy 8.156448 -111.505746) (xy 8.168386 -111.500158) (xy 8.184134 -111.47933) (xy 8.19912 -111.367824)
			(xy 8.189722 -111.34344) (xy 8.179562 -111.335058) (xy 8.14943 -111.309339) (xy 8.093772 -111.252956)
			(xy 8.043859 -111.19143) (xy 8.000164 -111.125343) (xy 7.9631 -111.055321) (xy 7.933019 -110.982027)
			(xy 7.910205 -110.906157) (xy 7.894875 -110.828428) (xy 7.887174 -110.749577) (xy 7.8867 -110.709964)
			(xy 7.88719 -110.670033) (xy 7.895018 -110.590555) (xy 7.910598 -110.512227) (xy 7.933781 -110.435804)
			(xy 7.964343 -110.36202) (xy 8.00199 -110.291588) (xy 8.046359 -110.225185) (xy 8.097023 -110.16345)
			(xy 8.153494 -110.106979) (xy 8.215229 -110.056315) (xy 8.281632 -110.011946) (xy 8.352064 -109.974299)
			(xy 8.425848 -109.943737) (xy 8.502271 -109.920554) (xy 8.580599 -109.904974) (xy 8.660077 -109.897146)
			(xy 8.739939 -109.897146) (xy 8.819417 -109.904974) (xy 8.897745 -109.920554) (xy 8.974168 -109.943737)
			(xy 9.047952 -109.974299) (xy 9.118384 -110.011946) (xy 9.184787 -110.056315) (xy 9.246522 -110.106979)
			(xy 9.302993 -110.16345) (xy 9.353657 -110.225185) (xy 9.398026 -110.291588) (xy 9.435673 -110.36202)
			(xy 9.466235 -110.435804) (xy 9.489418 -110.512227) (xy 9.504998 -110.590555) (xy 9.512826 -110.670033)
			(xy 9.513316 -110.709964) (xy 9.512861 -110.749577) (xy 9.505154 -110.828428) (xy 9.48982 -110.906157)
			(xy 9.467002 -110.982027) (xy 9.436918 -111.05532) (xy 9.399853 -111.125341) (xy 9.356157 -111.191429)
			(xy 9.306244 -111.252956) (xy 9.250588 -111.30934) (xy 9.220454 -111.335058) (xy 9.210294 -111.34344)
			(xy 9.200896 -111.367824) (xy 9.215882 -111.47933) (xy 9.23163 -111.500158) (xy 9.243568 -111.505746)
			(xy 9.290992 -111.527703) (xy 9.382565 -111.578079) (xy 9.469871 -111.635533) (xy 9.552365 -111.699706)
			(xy 9.629529 -111.770197) (xy 9.700883 -111.846566) (xy 9.765978 -111.928333) (xy 9.824409 -112.014989)
			(xy 9.87581 -112.105991) (xy 9.919859 -112.20077) (xy 9.956281 -112.298733) (xy 9.984848 -112.399268)
			(xy 10.005382 -112.501747) (xy 10.017754 -112.605527) (xy 10.021886 -112.70996) (xy 10.017754 -112.814393)
			(xy 10.005382 -112.918173) (xy 9.984848 -113.020652) (xy 9.956281 -113.121187) (xy 9.919859 -113.21915)
			(xy 9.87581 -113.313929) (xy 9.824409 -113.404931) (xy 9.765978 -113.491587) (xy 9.700883 -113.573354)
			(xy 9.629529 -113.649723) (xy 9.552365 -113.720214) (xy 9.469871 -113.784387) (xy 9.382565 -113.841841)
			(xy 9.290992 -113.892217) (xy 9.243568 -113.914174) (xy 9.23163 -113.919762) (xy 9.215882 -113.94059)
			(xy 9.200896 -114.052096) (xy 9.210294 -114.07648) (xy 9.220454 -114.084862) (xy 9.250585 -114.110582)
			(xy 9.306243 -114.166965) (xy 9.356156 -114.228491) (xy 9.399852 -114.294578) (xy 9.436916 -114.3646)
			(xy 9.466997 -114.437893) (xy 9.489811 -114.513763) (xy 9.505141 -114.591492) (xy 9.512842 -114.670343)
			(xy 9.513316 -114.709956) (xy 9.512792 -114.749887) (xy 9.504968 -114.829365) (xy 9.489392 -114.907693)
			(xy 9.466212 -114.984117) (xy 9.435654 -115.057901) (xy 9.39801 -115.128334) (xy 9.353644 -115.194739)
			(xy 9.302982 -115.256474) (xy 9.246513 -115.312947) (xy 9.18478 -115.363613) (xy 9.118379 -115.407983)
			(xy 9.047948 -115.445632) (xy 8.974166 -115.476195) (xy 8.897743 -115.499379) (xy 8.819416 -115.51496)
			(xy 8.739939 -115.522789) (xy 8.700008 -115.523264) (xy 8.660395 -115.522776) (xy 8.581545 -115.515076)
			(xy 8.503817 -115.499747) (xy 8.427947 -115.476934) (xy 8.354653 -115.446855) (xy 8.284631 -115.409793)
			(xy 8.218544 -115.3661) (xy 8.157016 -115.31619) (xy 8.100632 -115.260535) (xy 8.074914 -115.230402)
			(xy 8.066532 -115.220242) (xy 8.042148 -115.210844) (xy 7.930642 -115.22583) (xy 7.909814 -115.241578)
			(xy 7.904226 -115.253516) (xy 7.88189 -115.301649) (xy 7.830615 -115.394559) (xy 7.772052 -115.483057)
			(xy 7.706578 -115.566571) (xy 7.634615 -115.644563) (xy 7.556627 -115.71653) (xy 7.473117 -115.782009)
			(xy 7.384623 -115.840577) (xy 7.291715 -115.891857) (xy 7.243572 -115.91417) (xy 7.231634 -115.919758)
			(xy 7.215886 -115.940586) (xy 7.2009 -116.052092) (xy 7.210298 -116.076476) (xy 7.220458 -116.084858)
			(xy 7.250593 -116.110574) (xy 7.306251 -116.166957) (xy 7.356163 -116.228484) (xy 7.399859 -116.294571)
			(xy 7.436922 -116.364594) (xy 7.467003 -116.437887) (xy 7.489816 -116.513758) (xy 7.505146 -116.591487)
			(xy 7.512847 -116.670339) (xy 7.51332 -116.709952) (xy 7.886194 -116.709952) (xy 7.890238 -116.628922)
			(xy 7.90233 -116.548698) (xy 7.922349 -116.470076) (xy 7.950098 -116.393838) (xy 7.985299 -116.320742)
			(xy 8.027603 -116.251514) (xy 8.07659 -116.186842) (xy 8.131773 -116.12737) (xy 8.192603 -116.073687)
			(xy 8.258476 -116.026327) (xy 8.328737 -115.985762) (xy 8.402688 -115.952394) (xy 8.479594 -115.926555)
			(xy 8.558691 -115.908502) (xy 8.639192 -115.898414) (xy 8.720297 -115.896391) (xy 8.801201 -115.902454)
			(xy 8.881099 -115.916542) (xy 8.959197 -115.938515) (xy 9.034719 -115.968156) (xy 9.106915 -116.005168)
			(xy 9.175067 -116.049185) (xy 9.238497 -116.09977) (xy 9.296576 -116.156418) (xy 9.348726 -116.218568)
			(xy 9.394428 -116.285601) (xy 9.433229 -116.356851) (xy 9.464743 -116.431611) (xy 9.488657 -116.509137)
			(xy 9.504732 -116.588659) (xy 9.51281 -116.669387) (xy 9.513316 -116.709952) (xy 9.51281 -116.750517)
			(xy 9.504732 -116.831245) (xy 9.488657 -116.910767) (xy 9.464743 -116.988293) (xy 9.433229 -117.063053)
			(xy 9.394428 -117.134303) (xy 9.348726 -117.201336) (xy 9.296576 -117.263486) (xy 9.238497 -117.320134)
			(xy 9.175067 -117.370719) (xy 9.106915 -117.414736) (xy 9.034719 -117.451748) (xy 8.959197 -117.481389)
			(xy 8.881099 -117.503362) (xy 8.801201 -117.51745) (xy 8.720297 -117.523513) (xy 8.639192 -117.52149)
			(xy 8.558691 -117.511402) (xy 8.479594 -117.493349) (xy 8.402688 -117.46751) (xy 8.328737 -117.434142)
			(xy 8.258476 -117.393577) (xy 8.192603 -117.346217) (xy 8.131773 -117.292534) (xy 8.07659 -117.233062)
			(xy 8.027603 -117.16839) (xy 7.985299 -117.099162) (xy 7.950098 -117.026066) (xy 7.922349 -116.949828)
			(xy 7.90233 -116.871206) (xy 7.890238 -116.790982) (xy 7.886194 -116.709952) (xy 7.51332 -116.709952)
			(xy 7.51283 -116.749883) (xy 7.505002 -116.829361) (xy 7.489422 -116.907689) (xy 7.466239 -116.984112)
			(xy 7.435677 -117.057896) (xy 7.39803 -117.128328) (xy 7.353661 -117.194731) (xy 7.302997 -117.256466)
			(xy 7.246526 -117.312937) (xy 7.184791 -117.363601) (xy 7.118388 -117.40797) (xy 7.047956 -117.445617)
			(xy 6.974172 -117.476179) (xy 6.897749 -117.499362) (xy 6.819421 -117.514942) (xy 6.739943 -117.52277)
			(xy 6.660081 -117.52277) (xy 6.580603 -117.514942) (xy 6.502275 -117.499362) (xy 6.425852 -117.476179)
			(xy 6.352068 -117.445617) (xy 6.281636 -117.40797) (xy 6.215233 -117.363601) (xy 6.153498 -117.312937)
			(xy 6.097027 -117.256466) (xy 6.046363 -117.194731) (xy 6.001994 -117.128328) (xy 5.964347 -117.057896)
			(xy 5.933785 -116.984112) (xy 5.910602 -116.907689) (xy 5.895022 -116.829361) (xy 5.887194 -116.749883)
			(xy 5.886704 -116.709952) (xy 5.887163 -116.670339) (xy 5.894869 -116.591488) (xy 5.910202 -116.513759)
			(xy 5.933019 -116.437889) (xy 5.963102 -116.364596) (xy 6.000167 -116.294574) (xy 6.043863 -116.228487)
			(xy 6.093775 -116.16696) (xy 6.149432 -116.110576) (xy 6.179566 -116.084858) (xy 6.189726 -116.076476)
			(xy 6.199124 -116.052092) (xy 6.184138 -115.940586) (xy 6.16839 -115.919758) (xy 6.156452 -115.91417)
			(xy 6.109028 -115.892213) (xy 6.017455 -115.841838) (xy 5.930148 -115.784384) (xy 5.847655 -115.72021)
			(xy 5.77049 -115.649719) (xy 5.699137 -115.573351) (xy 5.634041 -115.491583) (xy 5.57561 -115.404927)
			(xy 5.524209 -115.313925) (xy 5.48016 -115.219146) (xy 5.443738 -115.121183) (xy 5.415171 -115.020648)
			(xy 5.394637 -114.91817) (xy 5.382265 -114.814389) (xy 5.378133 -114.709956) (xy 3.366008 -114.709956)
			(xy 3.366008 -118.709948) (xy 5.886198 -118.709948) (xy 5.890242 -118.628918) (xy 5.902334 -118.548694)
			(xy 5.922353 -118.470072) (xy 5.950102 -118.393834) (xy 5.985303 -118.320738) (xy 6.027607 -118.25151)
			(xy 6.076594 -118.186838) (xy 6.131777 -118.127366) (xy 6.192607 -118.073683) (xy 6.25848 -118.026323)
			(xy 6.328741 -117.985758) (xy 6.402692 -117.95239) (xy 6.479598 -117.926551) (xy 6.558695 -117.908498)
			(xy 6.639196 -117.89841) (xy 6.720301 -117.896387) (xy 6.801205 -117.90245) (xy 6.881103 -117.916538)
			(xy 6.959201 -117.938511) (xy 7.034723 -117.968152) (xy 7.106919 -118.005164) (xy 7.175071 -118.049181)
			(xy 7.238501 -118.099766) (xy 7.29658 -118.156414) (xy 7.34873 -118.218564) (xy 7.394432 -118.285597)
			(xy 7.433233 -118.356847) (xy 7.464747 -118.431607) (xy 7.488661 -118.509133) (xy 7.504736 -118.588655)
			(xy 7.512814 -118.669383) (xy 7.51332 -118.709948) (xy 7.886194 -118.709948) (xy 7.890238 -118.628918)
			(xy 7.90233 -118.548694) (xy 7.922349 -118.470072) (xy 7.950098 -118.393834) (xy 7.985299 -118.320738)
			(xy 8.027603 -118.25151) (xy 8.07659 -118.186838) (xy 8.131773 -118.127366) (xy 8.192603 -118.073683)
			(xy 8.258476 -118.026323) (xy 8.328737 -117.985758) (xy 8.402688 -117.95239) (xy 8.479594 -117.926551)
			(xy 8.558691 -117.908498) (xy 8.639192 -117.89841) (xy 8.720297 -117.896387) (xy 8.801201 -117.90245)
			(xy 8.881099 -117.916538) (xy 8.959197 -117.938511) (xy 9.034719 -117.968152) (xy 9.106915 -118.005164)
			(xy 9.175067 -118.049181) (xy 9.238497 -118.099766) (xy 9.296576 -118.156414) (xy 9.348726 -118.218564)
			(xy 9.394428 -118.285597) (xy 9.433229 -118.356847) (xy 9.464743 -118.431607) (xy 9.488657 -118.509133)
			(xy 9.504732 -118.588655) (xy 9.51281 -118.669383) (xy 9.513316 -118.709948) (xy 9.51281 -118.750513)
			(xy 9.504732 -118.831241) (xy 9.488657 -118.910763) (xy 9.464743 -118.988289) (xy 9.433229 -119.063049)
			(xy 9.394428 -119.134299) (xy 9.348726 -119.201332) (xy 9.296576 -119.263482) (xy 9.238497 -119.32013)
			(xy 9.175067 -119.370715) (xy 9.106915 -119.414732) (xy 9.034719 -119.451744) (xy 8.959197 -119.481385)
			(xy 8.881099 -119.503358) (xy 8.801201 -119.517446) (xy 8.720297 -119.523509) (xy 8.639192 -119.521486)
			(xy 8.558691 -119.511398) (xy 8.479594 -119.493345) (xy 8.402688 -119.467506) (xy 8.328737 -119.434138)
			(xy 8.258476 -119.393573) (xy 8.192603 -119.346213) (xy 8.131773 -119.29253) (xy 8.07659 -119.233058)
			(xy 8.027603 -119.168386) (xy 7.985299 -119.099158) (xy 7.950098 -119.026062) (xy 7.922349 -118.949824)
			(xy 7.90233 -118.871202) (xy 7.890238 -118.790978) (xy 7.886194 -118.709948) (xy 7.51332 -118.709948)
			(xy 7.512814 -118.750513) (xy 7.504736 -118.831241) (xy 7.488661 -118.910763) (xy 7.464747 -118.988289)
			(xy 7.433233 -119.063049) (xy 7.394432 -119.134299) (xy 7.34873 -119.201332) (xy 7.29658 -119.263482)
			(xy 7.238501 -119.32013) (xy 7.175071 -119.370715) (xy 7.106919 -119.414732) (xy 7.034723 -119.451744)
			(xy 6.959201 -119.481385) (xy 6.881103 -119.503358) (xy 6.801205 -119.517446) (xy 6.720301 -119.523509)
			(xy 6.639196 -119.521486) (xy 6.558695 -119.511398) (xy 6.479598 -119.493345) (xy 6.402692 -119.467506)
			(xy 6.328741 -119.434138) (xy 6.25848 -119.393573) (xy 6.192607 -119.346213) (xy 6.131777 -119.29253)
			(xy 6.076594 -119.233058) (xy 6.027607 -119.168386) (xy 5.985303 -119.099158) (xy 5.950102 -119.026062)
			(xy 5.922353 -118.949824) (xy 5.902334 -118.871202) (xy 5.890242 -118.790978) (xy 5.886198 -118.709948)
			(xy 3.366008 -118.709948) (xy 3.366008 -124.841) (xy 4.189982 -124.841) (xy 4.194053 -124.785378)
			(xy 4.206179 -124.730941) (xy 4.226102 -124.67885) (xy 4.253398 -124.630215) (xy 4.287484 -124.586072)
			(xy 4.327633 -124.547363) (xy 4.372991 -124.514912) (xy 4.422591 -124.489411) (xy 4.475375 -124.471404)
			(xy 4.530218 -124.461274) (xy 4.585952 -124.459237) (xy 4.641389 -124.465337) (xy 4.695346 -124.479443)
			(xy 4.746675 -124.501255) (xy 4.794281 -124.530309) (xy 4.837149 -124.565984) (xy 4.874366 -124.607521)
			(xy 4.905139 -124.654034) (xy 4.928811 -124.704531) (xy 4.944879 -124.757938) (xy 4.952999 -124.813114)
			(xy 4.953508 -124.841) (xy 4.952999 -124.868886) (xy 4.944879 -124.924062) (xy 4.928811 -124.977469)
			(xy 4.905139 -125.027966) (xy 4.874366 -125.074479) (xy 4.837149 -125.116016) (xy 4.794281 -125.151691)
			(xy 4.746675 -125.180745) (xy 4.695346 -125.202557) (xy 4.641389 -125.216663) (xy 4.585952 -125.222763)
			(xy 4.530218 -125.220726) (xy 4.475375 -125.210596) (xy 4.422591 -125.192589) (xy 4.372991 -125.167088)
			(xy 4.327633 -125.134637) (xy 4.287484 -125.095928) (xy 4.253398 -125.051785) (xy 4.226102 -125.00315)
			(xy 4.206179 -124.951059) (xy 4.194053 -124.896622) (xy 4.189982 -124.841) (xy 3.366008 -124.841)
			(xy 3.366008 -125.855984) (xy 3.366498 -125.865945) (xy 3.374091 -125.884364) (xy 3.38074 -125.891798)
			(xy 3.85383 -126.365) (xy 4.825492 -126.365) (xy 4.82596 -126.33763) (xy 4.833778 -126.283451) (xy 4.849266 -126.230948)
			(xy 4.872108 -126.181201) (xy 4.901831 -126.135234) (xy 4.919472 -126.114302) (xy 4.925568 -126.10719)
			(xy 4.931918 -126.090172) (xy 4.931918 -126.004828) (xy 4.925568 -125.98781) (xy 4.919472 -125.980698)
			(xy 4.901838 -125.959762) (xy 4.872125 -125.91379) (xy 4.849288 -125.864044) (xy 4.833796 -125.811544)
			(xy 4.825967 -125.757369) (xy 4.825492 -125.73) (xy 4.825978 -125.702749) (xy 4.833734 -125.648801)
			(xy 4.849089 -125.596506) (xy 4.871731 -125.546929) (xy 4.901197 -125.501079) (xy 4.936888 -125.459888)
			(xy 4.978079 -125.424197) (xy 5.023929 -125.394731) (xy 5.073506 -125.372089) (xy 5.125801 -125.356734)
			(xy 5.179749 -125.348978) (xy 5.234251 -125.348978) (xy 5.288199 -125.356734) (xy 5.340494 -125.372089)
			(xy 5.390071 -125.394731) (xy 5.435921 -125.424197) (xy 5.477112 -125.459888) (xy 5.512803 -125.501079)
			(xy 5.542269 -125.546929) (xy 5.564911 -125.596506) (xy 5.580266 -125.648801) (xy 5.588022 -125.702749)
			(xy 5.588508 -125.73) (xy 5.58804 -125.75737) (xy 5.580222 -125.811549) (xy 5.564734 -125.864052)
			(xy 5.541892 -125.913799) (xy 5.512169 -125.959766) (xy 5.494528 -125.980698) (xy 5.488432 -125.98781)
			(xy 5.482082 -126.004828) (xy 5.482082 -126.090172) (xy 5.488432 -126.10719) (xy 5.494528 -126.114302)
			(xy 5.512186 -126.135219) (xy 5.541894 -126.181196) (xy 5.564726 -126.230948) (xy 5.580213 -126.283452)
			(xy 5.588036 -126.33763) (xy 5.588508 -126.365) (xy 5.588022 -126.392251) (xy 5.580266 -126.446199)
			(xy 5.564911 -126.498494) (xy 5.542269 -126.548071) (xy 5.512803 -126.593921) (xy 5.477112 -126.635112)
			(xy 5.435921 -126.670803) (xy 5.390071 -126.700269) (xy 5.340494 -126.722911) (xy 5.288199 -126.738266)
			(xy 5.234251 -126.746022) (xy 5.179749 -126.746022) (xy 5.125801 -126.738266) (xy 5.073506 -126.722911)
			(xy 5.023929 -126.700269) (xy 4.978079 -126.670803) (xy 4.936888 -126.635112) (xy 4.901197 -126.593921)
			(xy 4.871731 -126.548071) (xy 4.849089 -126.498494) (xy 4.833734 -126.446199) (xy 4.825978 -126.392251)
			(xy 4.825492 -126.365) (xy 3.85383 -126.365) (xy 4.451604 -126.962916) (xy 4.471729 -126.983766)
			(xy 4.505831 -127.030616) (xy 4.532183 -127.082224) (xy 4.550135 -127.137321) (xy 4.559245 -127.194547)
			(xy 4.559808 -127.22352) (xy 4.559808 -130.440938) (xy 4.81279 -130.440938) (xy 4.816861 -130.385316)
			(xy 4.828987 -130.330879) (xy 4.84891 -130.278788) (xy 4.876206 -130.230153) (xy 4.910292 -130.18601)
			(xy 4.950441 -130.147301) (xy 4.995799 -130.11485) (xy 5.045399 -130.089349) (xy 5.098183 -130.071342)
			(xy 5.153026 -130.061212) (xy 5.20876 -130.059175) (xy 5.264197 -130.065275) (xy 5.318154 -130.079381)
			(xy 5.369483 -130.101193) (xy 5.417089 -130.130247) (xy 5.459957 -130.165922) (xy 5.468091 -130.175)
			(xy 7.110982 -130.175) (xy 7.115053 -130.119378) (xy 7.127179 -130.064941) (xy 7.147102 -130.01285)
			(xy 7.174398 -129.964215) (xy 7.208484 -129.920072) (xy 7.248633 -129.881363) (xy 7.293991 -129.848912)
			(xy 7.343591 -129.823411) (xy 7.396375 -129.805404) (xy 7.451218 -129.795274) (xy 7.506952 -129.793237)
			(xy 7.562389 -129.799337) (xy 7.616346 -129.813443) (xy 7.667675 -129.835255) (xy 7.715281 -129.864309)
			(xy 7.758149 -129.899984) (xy 7.795366 -129.941521) (xy 7.826139 -129.988034) (xy 7.849811 -130.038531)
			(xy 7.865879 -130.091938) (xy 7.873999 -130.147114) (xy 7.874508 -130.175) (xy 7.873999 -130.202886)
			(xy 7.865879 -130.258062) (xy 7.849811 -130.311469) (xy 7.826139 -130.361966) (xy 7.795366 -130.408479)
			(xy 7.758149 -130.450016) (xy 7.715281 -130.485691) (xy 7.667675 -130.514745) (xy 7.616346 -130.536557)
			(xy 7.562389 -130.550663) (xy 7.506952 -130.556763) (xy 7.451218 -130.554726) (xy 7.396375 -130.544596)
			(xy 7.343591 -130.526589) (xy 7.293991 -130.501088) (xy 7.248633 -130.468637) (xy 7.208484 -130.429928)
			(xy 7.174398 -130.385785) (xy 7.147102 -130.33715) (xy 7.127179 -130.285059) (xy 7.115053 -130.230622)
			(xy 7.110982 -130.175) (xy 5.468091 -130.175) (xy 5.497174 -130.207459) (xy 5.527947 -130.253972)
			(xy 5.551619 -130.304469) (xy 5.567687 -130.357876) (xy 5.575807 -130.413052) (xy 5.576316 -130.440938)
			(xy 5.575807 -130.468824) (xy 5.567687 -130.524) (xy 5.551619 -130.577407) (xy 5.527947 -130.627904)
			(xy 5.497174 -130.674417) (xy 5.459957 -130.715954) (xy 5.417089 -130.751629) (xy 5.369483 -130.780683)
			(xy 5.318154 -130.802495) (xy 5.264197 -130.816601) (xy 5.20876 -130.822701) (xy 5.153026 -130.820664)
			(xy 5.098183 -130.810534) (xy 5.045399 -130.792527) (xy 4.995799 -130.767026) (xy 4.950441 -130.734575)
			(xy 4.910292 -130.695866) (xy 4.876206 -130.651723) (xy 4.84891 -130.603088) (xy 4.828987 -130.550997)
			(xy 4.816861 -130.49656) (xy 4.81279 -130.440938) (xy 4.559808 -130.440938) (xy 4.559808 -132.207)
			(xy 7.110982 -132.207) (xy 7.115053 -132.151378) (xy 7.127179 -132.096941) (xy 7.147102 -132.04485)
			(xy 7.174398 -131.996215) (xy 7.208484 -131.952072) (xy 7.248633 -131.913363) (xy 7.293991 -131.880912)
			(xy 7.343591 -131.855411) (xy 7.396375 -131.837404) (xy 7.451218 -131.827274) (xy 7.506952 -131.825237)
			(xy 7.562389 -131.831337) (xy 7.616346 -131.845443) (xy 7.667675 -131.867255) (xy 7.715281 -131.896309)
			(xy 7.758149 -131.931984) (xy 7.795366 -131.973521) (xy 7.826139 -132.020034) (xy 7.849811 -132.070531)
			(xy 7.865879 -132.123938) (xy 7.873999 -132.179114) (xy 7.874508 -132.207) (xy 7.873999 -132.234886)
			(xy 7.865879 -132.290062) (xy 7.849811 -132.343469) (xy 7.826139 -132.393966) (xy 7.795366 -132.440479)
			(xy 7.758149 -132.482016) (xy 7.715281 -132.517691) (xy 7.667675 -132.546745) (xy 7.616346 -132.568557)
			(xy 7.562389 -132.582663) (xy 7.506952 -132.588763) (xy 7.451218 -132.586726) (xy 7.396375 -132.576596)
			(xy 7.343591 -132.558589) (xy 7.293991 -132.533088) (xy 7.248633 -132.500637) (xy 7.208484 -132.461928)
			(xy 7.174398 -132.417785) (xy 7.147102 -132.36915) (xy 7.127179 -132.317059) (xy 7.115053 -132.262622)
			(xy 7.110982 -132.207) (xy 4.559808 -132.207) (xy 4.559808 -133.39572) (xy 4.559251 -133.424694)
			(xy 4.550147 -133.481924) (xy 4.532198 -133.537023) (xy 4.505847 -133.588634) (xy 4.471742 -133.635485)
			(xy 4.451604 -133.656324) (xy 4.078986 -134.029196) (xy 4.07213 -134.03659) (xy 4.06438 -134.055189)
			(xy 4.064 -134.065264) (xy 4.064 -134.198614) (xy 6.623302 -134.198614) (xy 6.627373 -134.142992)
			(xy 6.639499 -134.088555) (xy 6.659422 -134.036464) (xy 6.686718 -133.987829) (xy 6.720804 -133.943686)
			(xy 6.760953 -133.904977) (xy 6.806311 -133.872526) (xy 6.855911 -133.847025) (xy 6.908695 -133.829018)
			(xy 6.963538 -133.818888) (xy 7.019272 -133.816851) (xy 7.074709 -133.822951) (xy 7.128666 -133.837057)
			(xy 7.179995 -133.858869) (xy 7.227601 -133.887923) (xy 7.270469 -133.923598) (xy 7.307686 -133.965135)
			(xy 7.338459 -134.011648) (xy 7.362131 -134.062145) (xy 7.378199 -134.115552) (xy 7.386319 -134.170728)
			(xy 7.386828 -134.198614) (xy 7.386319 -134.2265) (xy 7.378199 -134.281676) (xy 7.362131 -134.335083)
			(xy 7.338459 -134.38558) (xy 7.307686 -134.432093) (xy 7.270469 -134.47363) (xy 7.227601 -134.509305)
			(xy 7.179995 -134.538359) (xy 7.128666 -134.560171) (xy 7.074709 -134.574277) (xy 7.019272 -134.580377)
			(xy 6.963538 -134.57834) (xy 6.908695 -134.56821) (xy 6.855911 -134.550203) (xy 6.806311 -134.524702)
			(xy 6.760953 -134.492251) (xy 6.720804 -134.453542) (xy 6.686718 -134.409399) (xy 6.659422 -134.360764)
			(xy 6.639499 -134.308673) (xy 6.627373 -134.254236) (xy 6.623302 -134.198614) (xy 4.064 -134.198614)
			(xy 4.064 -135.65505) (xy 8.630918 -135.65505) (xy 8.634989 -135.599428) (xy 8.647115 -135.544991)
			(xy 8.667038 -135.4929) (xy 8.694334 -135.444265) (xy 8.72842 -135.400122) (xy 8.768569 -135.361413)
			(xy 8.813927 -135.328962) (xy 8.863527 -135.303461) (xy 8.916311 -135.285454) (xy 8.971154 -135.275324)
			(xy 9.026888 -135.273287) (xy 9.082325 -135.279387) (xy 9.136282 -135.293493) (xy 9.187611 -135.315305)
			(xy 9.235217 -135.344359) (xy 9.278085 -135.380034) (xy 9.315302 -135.421571) (xy 9.346075 -135.468084)
			(xy 9.369747 -135.518581) (xy 9.385815 -135.571988) (xy 9.393935 -135.627164) (xy 9.394444 -135.65505)
			(xy 9.393935 -135.682936) (xy 9.385815 -135.738112) (xy 9.369747 -135.791519) (xy 9.346075 -135.842016)
			(xy 9.315302 -135.888529) (xy 9.278085 -135.930066) (xy 9.235217 -135.965741) (xy 9.187611 -135.994795)
			(xy 9.136282 -136.016607) (xy 9.082325 -136.030713) (xy 9.026888 -136.036813) (xy 8.971154 -136.034776)
			(xy 8.916311 -136.024646) (xy 8.863527 -136.006639) (xy 8.813927 -135.981138) (xy 8.768569 -135.948687)
			(xy 8.72842 -135.909978) (xy 8.694334 -135.865835) (xy 8.667038 -135.8172) (xy 8.647115 -135.765109)
			(xy 8.634989 -135.710672) (xy 8.630918 -135.65505) (xy 4.064 -135.65505) (xy 4.064 -138.281918) (xy 4.064427 -138.291987)
			(xy 4.072146 -138.310586) (xy 4.078986 -138.317986) (xy 5.954014 -140.193014) (xy 5.961409 -140.199868)
			(xy 5.980008 -140.20761) (xy 5.990082 -140.208)
		)
		(stroke
			(width 0)
			(type solid)
		)
		(fill yes)
		(layer "In2.Cu")
		(net "P3V3_AUX")
	)
	(gr_poly
		(pts
			(xy 47.69993 -335.730088) (xy 47.773866 -335.729581) (xy 47.921521 -335.721563) (xy 48.068525 -335.705564)
			(xy 48.214447 -335.68163) (xy 48.35886 -335.649831) (xy 48.501339 -335.610261) (xy 48.641467 -335.563036)
			(xy 48.778833 -335.508294) (xy 48.913035 -335.446196) (xy 49.043677 -335.376924) (xy 49.170378 -335.300681)
			(xy 49.292766 -335.21769) (xy 49.410482 -335.128196) (xy 49.52318 -335.032461) (xy 49.63053 -334.930764)
			(xy 49.732217 -334.823405) (xy 49.827943 -334.710699) (xy 49.917427 -334.592976) (xy 50.000407 -334.470581)
			(xy 50.076639 -334.343874) (xy 50.1459 -334.213225) (xy 50.207987 -334.079018) (xy 50.262717 -333.941648)
			(xy 50.30993 -333.801515) (xy 50.349488 -333.659032) (xy 50.381274 -333.514617) (xy 50.405196 -333.368693)
			(xy 50.421182 -333.221687) (xy 50.429187 -333.074032) (xy 50.429668 -333.000096) (xy 50.429668 -190.180722)
			(xy 50.429252 -190.1707) (xy 50.421584 -190.152181) (xy 50.40741 -190.13801) (xy 50.38889 -190.130346)
			(xy 50.378868 -190.129922) (xy 49.807622 -190.129922) (xy 49.797559 -190.13036) (xy 49.778977 -190.138097)
			(xy 49.771554 -190.144908) (xy 46.304454 -193.612008) (xy 46.297603 -193.619404) (xy 46.289863 -193.638003)
			(xy 46.289468 -193.648076) (xy 46.289468 -195.020946) (xy 46.289899 -195.031013) (xy 46.297621 -195.049609)
			(xy 46.304454 -195.057014) (xy 47.479204 -196.232018) (xy 47.499329 -196.252868) (xy 47.533431 -196.299718)
			(xy 47.559782 -196.351327) (xy 47.577734 -196.406423) (xy 47.586844 -196.463649) (xy 47.587408 -196.492622)
			(xy 47.587408 -206.2988) (xy 47.586853 -206.327775) (xy 47.577751 -206.385006) (xy 47.559805 -206.440107)
			(xy 47.533455 -206.491721) (xy 47.499351 -206.538574) (xy 47.479204 -206.559404) (xy 45.988986 -208.049876)
			(xy 45.982142 -208.057274) (xy 45.974422 -208.075874) (xy 45.974 -208.085944) (xy 45.974 -212.701886)
			(xy 45.973561 -212.711949) (xy 45.965825 -212.730531) (xy 45.959014 -212.737954) (xy 44.589954 -214.107014)
			(xy 44.582557 -214.113863) (xy 44.563958 -214.121594) (xy 44.553886 -214.122) (xy 44.336716 -214.122)
			(xy 44.330112 -214.123778) (xy 44.283914 -214.13588) (xy 44.190117 -214.153884) (xy 44.095226 -214.164728)
			(xy 43.999785 -214.16835) (xy 43.904344 -214.164728) (xy 43.809453 -214.153884) (xy 43.715656 -214.13588)
			(xy 43.669458 -214.123778) (xy 43.663108 -214.122) (xy 39.50208 -214.122) (xy 39.492011 -214.122427)
			(xy 39.473412 -214.130146) (xy 39.466012 -214.136986) (xy 38.862 -214.740998) (xy 38.862 -216.132918)
			(xy 38.861573 -216.142987) (xy 38.853854 -216.161586) (xy 38.847014 -216.168986) (xy 38.186868 -216.829132)
			(xy 38.181534 -216.860882) (xy 38.1889 -216.875614) (xy 38.201071 -216.901821) (xy 38.21826 -216.956986)
			(xy 38.226954 -217.014109) (xy 38.227508 -217.043) (xy 38.22701 -217.071062) (xy 38.218783 -217.126579)
			(xy 38.202507 -217.180291) (xy 38.178534 -217.231037) (xy 38.147381 -217.277721) (xy 38.109721 -217.319334)
			(xy 38.066368 -217.354977) (xy 38.042596 -217.369898) (xy 38.03269 -217.377518) (xy 36.406328 -219.004134)
			(xy 36.399588 -219.011506) (xy 36.392004 -219.029967) (xy 36.391596 -219.039948) (xy 36.391596 -227.61321)
			(xy 37.175948 -227.61321) (xy 37.17653 -227.566814) (xy 37.186174 -227.474526) (xy 37.20537 -227.383742)
			(xy 37.23391 -227.295449) (xy 37.252148 -227.252784) (xy 37.255961 -227.242842) (xy 37.255964 -227.221576)
			(xy 37.252148 -227.211636) (xy 37.23391 -227.168971) (xy 37.205363 -227.08068) (xy 37.186168 -226.989896)
			(xy 37.176533 -226.897606) (xy 37.175948 -226.85121) (xy 37.17653 -226.804814) (xy 37.186174 -226.712526)
			(xy 37.20537 -226.621742) (xy 37.23391 -226.533449) (xy 37.252148 -226.490784) (xy 37.255961 -226.480842)
			(xy 37.255964 -226.459576) (xy 37.252148 -226.449636) (xy 37.23391 -226.406971) (xy 37.205363 -226.31868)
			(xy 37.186168 -226.227896) (xy 37.176533 -226.135606) (xy 37.175948 -226.08921) (xy 37.176476 -226.048109)
			(xy 37.18406 -225.966257) (xy 37.199163 -225.885455) (xy 37.221657 -225.80639) (xy 37.25135 -225.729739)
			(xy 37.287989 -225.656154) (xy 37.331262 -225.586263) (xy 37.380798 -225.520663) (xy 37.436175 -225.459913)
			(xy 37.496921 -225.404532) (xy 37.562518 -225.354992) (xy 37.632406 -225.311716) (xy 37.705989 -225.275072)
			(xy 37.782639 -225.245374) (xy 37.861702 -225.222875) (xy 37.942504 -225.207767) (xy 38.024355 -225.200179)
			(xy 38.065456 -225.199702) (xy 38.103744 -225.200131) (xy 38.180035 -225.206754) (xy 38.255474 -225.219903)
			(xy 38.329506 -225.239481) (xy 38.365684 -225.252026) (xy 38.374122 -225.254668) (xy 38.39179 -225.254668)
			(xy 38.400228 -225.252026) (xy 38.436397 -225.239454) (xy 38.510429 -225.219862) (xy 38.585872 -225.206715)
			(xy 38.662166 -225.20011) (xy 38.700456 -225.199702) (xy 38.741559 -225.200194) (xy 38.823414 -225.207775)
			(xy 38.90422 -225.222877) (xy 38.983288 -225.245371) (xy 39.059944 -225.275064) (xy 39.133532 -225.311704)
			(xy 39.203426 -225.354977) (xy 39.269028 -225.404516) (xy 39.32978 -225.459896) (xy 39.385163 -225.520645)
			(xy 39.434703 -225.586246) (xy 39.47798 -225.656138) (xy 39.514622 -225.729725) (xy 39.544319 -225.806379)
			(xy 39.566815 -225.885447) (xy 39.58192 -225.966252) (xy 39.589504 -226.048107) (xy 39.589964 -226.08921)
			(xy 39.589388 -226.135606) (xy 39.579742 -226.227895) (xy 39.560544 -226.318678) (xy 39.532003 -226.406972)
			(xy 39.513764 -226.449636) (xy 39.509939 -226.459574) (xy 39.509943 -226.480844) (xy 39.513764 -226.490784)
			(xy 39.532009 -226.533446) (xy 39.560554 -226.621738) (xy 39.579747 -226.712523) (xy 39.58938 -226.804814)
			(xy 39.589964 -226.85121) (xy 39.589388 -226.897606) (xy 39.579742 -226.989895) (xy 39.560544 -227.080678)
			(xy 39.532003 -227.168972) (xy 39.513764 -227.211636) (xy 39.509939 -227.221574) (xy 39.509943 -227.242844)
			(xy 39.513764 -227.252784) (xy 39.532009 -227.295446) (xy 39.560554 -227.383738) (xy 39.579747 -227.474523)
			(xy 39.58892 -227.562406) (xy 45.405073 -227.562406) (xy 45.408801 -227.509157) (xy 45.419915 -227.456948)
			(xy 45.438198 -227.406797) (xy 45.463293 -227.359684) (xy 45.494709 -227.316529) (xy 45.531834 -227.278175)
			(xy 45.552614 -227.26142) (xy 45.561365 -227.253848) (xy 45.571554 -227.233097) (xy 45.572172 -227.221542)
			(xy 45.572172 -227.141278) (xy 45.571566 -227.129714) (xy 45.561398 -227.108942) (xy 45.552614 -227.1014)
			(xy 45.531843 -227.084634) (xy 45.494717 -227.04628) (xy 45.463299 -227.003126) (xy 45.438203 -226.956014)
			(xy 45.419919 -226.905864) (xy 45.408803 -226.853655) (xy 45.405073 -226.800406) (xy 45.408801 -226.747157)
			(xy 45.419915 -226.694948) (xy 45.438198 -226.644797) (xy 45.463293 -226.597684) (xy 45.494709 -226.554529)
			(xy 45.531834 -226.516175) (xy 45.552614 -226.49942) (xy 45.561365 -226.491848) (xy 45.571554 -226.471097)
			(xy 45.572172 -226.459542) (xy 45.572172 -226.379278) (xy 45.571566 -226.367714) (xy 45.561398 -226.346942)
			(xy 45.552614 -226.3394) (xy 45.530133 -226.321205) (xy 45.490397 -226.279187) (xy 45.457458 -226.231653)
			(xy 45.432069 -226.179692) (xy 45.414812 -226.124495) (xy 45.406083 -226.067326) (xy 45.405548 -226.03841)
			(xy 45.406034 -226.011159) (xy 45.41379 -225.957211) (xy 45.429145 -225.904916) (xy 45.451787 -225.855339)
			(xy 45.481253 -225.809489) (xy 45.516944 -225.768298) (xy 45.558135 -225.732607) (xy 45.603985 -225.703141)
			(xy 45.653562 -225.680499) (xy 45.705857 -225.665144) (xy 45.759805 -225.657388) (xy 45.814307 -225.657388)
			(xy 45.868255 -225.665144) (xy 45.92055 -225.680499) (xy 45.970127 -225.703141) (xy 46.015977 -225.732607)
			(xy 46.057168 -225.768298) (xy 46.092859 -225.809489) (xy 46.122325 -225.855339) (xy 46.144967 -225.904916)
			(xy 46.160322 -225.957211) (xy 46.168078 -226.011159) (xy 46.168564 -226.03841) (xy 46.167994 -226.067325)
			(xy 46.159278 -226.124495) (xy 46.142031 -226.179693) (xy 46.116649 -226.231655) (xy 46.083714 -226.27919)
			(xy 46.04398 -226.321209) (xy 46.021498 -226.3394) (xy 46.01274 -226.346966) (xy 46.002555 -226.367722)
			(xy 46.00194 -226.379278) (xy 46.00194 -226.459542) (xy 46.00253 -226.471108) (xy 46.012709 -226.49188)
			(xy 46.021498 -226.49942) (xy 46.042293 -226.51616) (xy 46.079427 -226.554513) (xy 46.110852 -226.597669)
			(xy 46.135954 -226.644783) (xy 46.154242 -226.694938) (xy 46.16536 -226.747152) (xy 46.169089 -226.800406)
			(xy 46.165358 -226.85366) (xy 46.154239 -226.905874) (xy 46.135949 -226.956028) (xy 46.110846 -227.003142)
			(xy 46.079419 -227.046296) (xy 46.042284 -227.084648) (xy 46.021498 -227.1014) (xy 46.01274 -227.108966)
			(xy 46.002555 -227.129722) (xy 46.00194 -227.141278) (xy 46.00194 -227.221542) (xy 46.00253 -227.233108)
			(xy 46.012709 -227.25388) (xy 46.021498 -227.26142) (xy 46.042293 -227.27816) (xy 46.079427 -227.316513)
			(xy 46.110852 -227.359669) (xy 46.135954 -227.406783) (xy 46.154242 -227.456938) (xy 46.16536 -227.509152)
			(xy 46.169089 -227.562406) (xy 46.167309 -227.587806) (xy 48.884873 -227.587806) (xy 48.888601 -227.534557)
			(xy 48.899715 -227.482348) (xy 48.917998 -227.432197) (xy 48.943093 -227.385084) (xy 48.974509 -227.341929)
			(xy 49.011634 -227.303575) (xy 49.032414 -227.28682) (xy 49.041165 -227.279248) (xy 49.051354 -227.258497)
			(xy 49.051972 -227.246942) (xy 49.051972 -227.166678) (xy 49.051366 -227.155114) (xy 49.041198 -227.134342)
			(xy 49.032414 -227.1268) (xy 49.011643 -227.110034) (xy 48.974517 -227.07168) (xy 48.943099 -227.028526)
			(xy 48.918003 -226.981414) (xy 48.899719 -226.931264) (xy 48.888603 -226.879055) (xy 48.884873 -226.825806)
			(xy 48.888601 -226.772557) (xy 48.899715 -226.720348) (xy 48.917998 -226.670197) (xy 48.943093 -226.623084)
			(xy 48.974509 -226.579929) (xy 49.011634 -226.541575) (xy 49.032414 -226.52482) (xy 49.041165 -226.517248)
			(xy 49.051354 -226.496497) (xy 49.051972 -226.484942) (xy 49.051972 -226.404678) (xy 49.051366 -226.393114)
			(xy 49.041198 -226.372342) (xy 49.032414 -226.3648) (xy 49.011643 -226.348034) (xy 48.974517 -226.30968)
			(xy 48.943099 -226.266526) (xy 48.918003 -226.219414) (xy 48.899719 -226.169264) (xy 48.888603 -226.117055)
			(xy 48.884873 -226.063806) (xy 48.888601 -226.010557) (xy 48.899715 -225.958348) (xy 48.917998 -225.908197)
			(xy 48.943093 -225.861084) (xy 48.974509 -225.817929) (xy 49.011634 -225.779575) (xy 49.032414 -225.76282)
			(xy 49.041165 -225.755248) (xy 49.051354 -225.734497) (xy 49.051972 -225.722942) (xy 49.051972 -225.642678)
			(xy 49.051366 -225.631114) (xy 49.041198 -225.610342) (xy 49.032414 -225.6028) (xy 49.009933 -225.584605)
			(xy 48.970197 -225.542587) (xy 48.937258 -225.495053) (xy 48.911869 -225.443092) (xy 48.894612 -225.387895)
			(xy 48.885883 -225.330726) (xy 48.885348 -225.30181) (xy 48.885834 -225.274559) (xy 48.89359 -225.220611)
			(xy 48.908945 -225.168316) (xy 48.931587 -225.118739) (xy 48.961053 -225.072889) (xy 48.996744 -225.031698)
			(xy 49.037935 -224.996007) (xy 49.083785 -224.966541) (xy 49.133362 -224.943899) (xy 49.185657 -224.928544)
			(xy 49.239605 -224.920788) (xy 49.294107 -224.920788) (xy 49.348055 -224.928544) (xy 49.40035 -224.943899)
			(xy 49.449927 -224.966541) (xy 49.495777 -224.996007) (xy 49.536968 -225.031698) (xy 49.572659 -225.072889)
			(xy 49.602125 -225.118739) (xy 49.624767 -225.168316) (xy 49.640122 -225.220611) (xy 49.647878 -225.274559)
			(xy 49.648364 -225.30181) (xy 49.647794 -225.330725) (xy 49.639078 -225.387895) (xy 49.621831 -225.443093)
			(xy 49.596449 -225.495055) (xy 49.563514 -225.54259) (xy 49.52378 -225.584609) (xy 49.501298 -225.6028)
			(xy 49.49254 -225.610366) (xy 49.482355 -225.631122) (xy 49.48174 -225.642678) (xy 49.48174 -225.722942)
			(xy 49.48233 -225.734508) (xy 49.492509 -225.75528) (xy 49.501298 -225.76282) (xy 49.522093 -225.77956)
			(xy 49.559227 -225.817913) (xy 49.590652 -225.861069) (xy 49.615754 -225.908183) (xy 49.634042 -225.958338)
			(xy 49.64516 -226.010552) (xy 49.648889 -226.063806) (xy 49.645158 -226.11706) (xy 49.634039 -226.169274)
			(xy 49.615749 -226.219428) (xy 49.590646 -226.266542) (xy 49.559219 -226.309696) (xy 49.522084 -226.348048)
			(xy 49.501298 -226.3648) (xy 49.49254 -226.372366) (xy 49.482355 -226.393122) (xy 49.48174 -226.404678)
			(xy 49.48174 -226.484942) (xy 49.48233 -226.496508) (xy 49.492509 -226.51728) (xy 49.501298 -226.52482)
			(xy 49.522093 -226.54156) (xy 49.559227 -226.579913) (xy 49.590652 -226.623069) (xy 49.615754 -226.670183)
			(xy 49.634042 -226.720338) (xy 49.64516 -226.772552) (xy 49.648889 -226.825806) (xy 49.645158 -226.87906)
			(xy 49.634039 -226.931274) (xy 49.615749 -226.981428) (xy 49.590646 -227.028542) (xy 49.559219 -227.071696)
			(xy 49.522084 -227.110048) (xy 49.501298 -227.1268) (xy 49.49254 -227.134366) (xy 49.482355 -227.155122)
			(xy 49.48174 -227.166678) (xy 49.48174 -227.246942) (xy 49.48233 -227.258508) (xy 49.492509 -227.27928)
			(xy 49.501298 -227.28682) (xy 49.522093 -227.30356) (xy 49.559227 -227.341913) (xy 49.590652 -227.385069)
			(xy 49.615754 -227.432183) (xy 49.634042 -227.482338) (xy 49.64516 -227.534552) (xy 49.648889 -227.587806)
			(xy 49.645158 -227.64106) (xy 49.634039 -227.693274) (xy 49.615749 -227.743428) (xy 49.590646 -227.790542)
			(xy 49.559219 -227.833696) (xy 49.522084 -227.872048) (xy 49.501298 -227.8888) (xy 49.49254 -227.896366)
			(xy 49.482355 -227.917122) (xy 49.48174 -227.928678) (xy 49.48174 -228.008942) (xy 49.48233 -228.020508)
			(xy 49.492509 -228.04128) (xy 49.501298 -228.04882) (xy 49.523791 -228.067) (xy 49.563525 -228.109022)
			(xy 49.596463 -228.156559) (xy 49.62185 -228.208523) (xy 49.639104 -228.263722) (xy 49.647831 -228.320893)
			(xy 49.648364 -228.34981) (xy 49.647878 -228.377061) (xy 49.640122 -228.431009) (xy 49.624767 -228.483304)
			(xy 49.602125 -228.532881) (xy 49.572659 -228.578731) (xy 49.536968 -228.619922) (xy 49.495777 -228.655613)
			(xy 49.449927 -228.685079) (xy 49.40035 -228.707721) (xy 49.348055 -228.723076) (xy 49.294107 -228.730832)
			(xy 49.239605 -228.730832) (xy 49.185657 -228.723076) (xy 49.133362 -228.707721) (xy 49.083785 -228.685079)
			(xy 49.037935 -228.655613) (xy 48.996744 -228.619922) (xy 48.961053 -228.578731) (xy 48.931587 -228.532881)
			(xy 48.908945 -228.483304) (xy 48.89359 -228.431009) (xy 48.885834 -228.377061) (xy 48.885348 -228.34981)
			(xy 48.885855 -228.320892) (xy 48.894584 -228.26372) (xy 48.911843 -228.20852) (xy 48.937237 -228.156558)
			(xy 48.970183 -228.109025) (xy 49.009927 -228.067009) (xy 49.032414 -228.04882) (xy 49.041165 -228.041248)
			(xy 49.051354 -228.020497) (xy 49.051972 -228.008942) (xy 49.051972 -227.928678) (xy 49.051366 -227.917114)
			(xy 49.041198 -227.896342) (xy 49.032414 -227.8888) (xy 49.011643 -227.872034) (xy 48.974517 -227.83368)
			(xy 48.943099 -227.790526) (xy 48.918003 -227.743414) (xy 48.899719 -227.693264) (xy 48.888603 -227.641055)
			(xy 48.884873 -227.587806) (xy 46.167309 -227.587806) (xy 46.165358 -227.61566) (xy 46.154239 -227.667874)
			(xy 46.135949 -227.718028) (xy 46.110846 -227.765142) (xy 46.079419 -227.808296) (xy 46.042284 -227.846648)
			(xy 46.021498 -227.8634) (xy 46.01274 -227.870966) (xy 46.002555 -227.891722) (xy 46.00194 -227.903278)
			(xy 46.00194 -227.983542) (xy 46.00253 -227.995108) (xy 46.012709 -228.01588) (xy 46.021498 -228.02342)
			(xy 46.043991 -228.0416) (xy 46.083725 -228.083622) (xy 46.116663 -228.131159) (xy 46.14205 -228.183123)
			(xy 46.159304 -228.238322) (xy 46.168031 -228.295493) (xy 46.168564 -228.32441) (xy 46.168078 -228.351661)
			(xy 46.160322 -228.405609) (xy 46.144967 -228.457904) (xy 46.122325 -228.507481) (xy 46.092859 -228.553331)
			(xy 46.057168 -228.594522) (xy 46.015977 -228.630213) (xy 45.970127 -228.659679) (xy 45.92055 -228.682321)
			(xy 45.868255 -228.697676) (xy 45.814307 -228.705432) (xy 45.759805 -228.705432) (xy 45.705857 -228.697676)
			(xy 45.653562 -228.682321) (xy 45.603985 -228.659679) (xy 45.558135 -228.630213) (xy 45.516944 -228.594522)
			(xy 45.481253 -228.553331) (xy 45.451787 -228.507481) (xy 45.429145 -228.457904) (xy 45.41379 -228.405609)
			(xy 45.406034 -228.351661) (xy 45.405548 -228.32441) (xy 45.406055 -228.295492) (xy 45.414784 -228.23832)
			(xy 45.432043 -228.18312) (xy 45.457437 -228.131158) (xy 45.490383 -228.083625) (xy 45.530127 -228.041609)
			(xy 45.552614 -228.02342) (xy 45.561365 -228.015848) (xy 45.571554 -227.995097) (xy 45.572172 -227.983542)
			(xy 45.572172 -227.903278) (xy 45.571566 -227.891714) (xy 45.561398 -227.870942) (xy 45.552614 -227.8634)
			(xy 45.531843 -227.846634) (xy 45.494717 -227.80828) (xy 45.463299 -227.765126) (xy 45.438203 -227.718014)
			(xy 45.419919 -227.667864) (xy 45.408803 -227.615655) (xy 45.405073 -227.562406) (xy 39.58892 -227.562406)
			(xy 39.58938 -227.566814) (xy 39.589964 -227.61321) (xy 39.589557 -227.654315) (xy 39.581971 -227.736173)
			(xy 39.566864 -227.816982) (xy 39.544365 -227.896053) (xy 39.514666 -227.97271) (xy 39.47802 -228.0463)
			(xy 39.434741 -228.116195) (xy 39.385197 -228.181798) (xy 39.329811 -228.242549) (xy 39.269056 -228.297932)
			(xy 39.20345 -228.347471) (xy 39.133553 -228.390747) (xy 39.059961 -228.427388) (xy 38.983302 -228.457082)
			(xy 38.90423 -228.479576) (xy 38.82342 -228.494678) (xy 38.741561 -228.50226) (xy 38.700456 -228.502718)
			(xy 38.662168 -228.502284) (xy 38.585878 -228.495662) (xy 38.510438 -228.482515) (xy 38.436406 -228.462938)
			(xy 38.400228 -228.450394) (xy 38.39179 -228.447752) (xy 38.374122 -228.447752) (xy 38.365684 -228.450394)
			(xy 38.329514 -228.462963) (xy 38.255483 -228.482556) (xy 38.18004 -228.495704) (xy 38.103746 -228.502309)
			(xy 38.065456 -228.502718) (xy 38.024353 -228.502275) (xy 37.942498 -228.494687) (xy 37.861693 -228.479578)
			(xy 37.782626 -228.457078) (xy 37.705972 -228.427379) (xy 37.632386 -228.390735) (xy 37.562494 -228.347457)
			(xy 37.496894 -228.297915) (xy 37.436144 -228.242532) (xy 37.380763 -228.18178) (xy 37.331224 -228.116178)
			(xy 37.287949 -228.046285) (xy 37.251307 -227.972697) (xy 37.221611 -227.896042) (xy 37.199114 -227.816974)
			(xy 37.184009 -227.736168) (xy 37.176423 -227.654313) (xy 37.175948 -227.61321) (xy 36.391596 -227.61321)
			(xy 36.391596 -232.029) (xy 40.48125 -232.029) (xy 40.481828 -231.982604) (xy 40.491474 -231.890316)
			(xy 40.510671 -231.799532) (xy 40.539211 -231.711238) (xy 40.55745 -231.668574) (xy 40.561268 -231.658634)
			(xy 40.561268 -231.637366) (xy 40.55745 -231.627426) (xy 40.539203 -231.584765) (xy 40.51066 -231.496472)
			(xy 40.491468 -231.405687) (xy 40.481835 -231.313396) (xy 40.48125 -231.267) (xy 40.481754 -231.224652)
			(xy 40.489805 -231.140338) (xy 40.505834 -231.057172) (xy 40.529695 -230.975905) (xy 40.561174 -230.897275)
			(xy 40.599985 -230.821994) (xy 40.645775 -230.750742) (xy 40.698131 -230.684166) (xy 40.756579 -230.622868)
			(xy 40.820589 -230.567403) (xy 40.889581 -230.518274) (xy 40.962931 -230.475925) (xy 41.039974 -230.440741)
			(xy 41.120013 -230.413039) (xy 41.202322 -230.393071) (xy 41.286157 -230.381018) (xy 41.370758 -230.376988)
			(xy 41.455359 -230.381018) (xy 41.539194 -230.393071) (xy 41.621503 -230.413039) (xy 41.701542 -230.440741)
			(xy 41.778585 -230.475925) (xy 41.851935 -230.518274) (xy 41.920927 -230.567403) (xy 41.984937 -230.622868)
			(xy 42.043385 -230.684166) (xy 42.095741 -230.750742) (xy 42.141531 -230.821994) (xy 42.180342 -230.897275)
			(xy 42.211821 -230.975905) (xy 42.235682 -231.057172) (xy 42.251711 -231.140338) (xy 42.259762 -231.224652)
			(xy 42.260266 -231.267) (xy 42.259687 -231.313396) (xy 42.250041 -231.405684) (xy 42.230844 -231.496468)
			(xy 42.202305 -231.584761) (xy 42.184066 -231.627426) (xy 42.180247 -231.637366) (xy 42.180247 -231.658634)
			(xy 42.184066 -231.668574) (xy 42.202308 -231.711237) (xy 42.230854 -231.799529) (xy 42.250047 -231.890314)
			(xy 42.259681 -231.982604) (xy 42.260266 -232.029) (xy 46.45025 -232.029) (xy 46.450749 -232.000082)
			(xy 46.45948 -231.942909) (xy 46.47674 -231.887709) (xy 46.502135 -231.835747) (xy 46.535083 -231.788214)
			(xy 46.574828 -231.746199) (xy 46.597316 -231.72801) (xy 46.606072 -231.720442) (xy 46.616258 -231.699688)
			(xy 46.616874 -231.688132) (xy 46.616874 -231.607868) (xy 46.616274 -231.596304) (xy 46.606101 -231.575532)
			(xy 46.597316 -231.56799) (xy 46.574831 -231.549801) (xy 46.535095 -231.507781) (xy 46.502156 -231.460246)
			(xy 46.476768 -231.408284) (xy 46.459512 -231.353086) (xy 46.450784 -231.295916) (xy 46.45025 -231.267)
			(xy 46.450736 -231.239749) (xy 46.458492 -231.185801) (xy 46.473847 -231.133506) (xy 46.496489 -231.083929)
			(xy 46.525955 -231.038079) (xy 46.561646 -230.996888) (xy 46.602837 -230.961197) (xy 46.648687 -230.931731)
			(xy 46.698264 -230.909089) (xy 46.750559 -230.893734) (xy 46.804507 -230.885978) (xy 46.859009 -230.885978)
			(xy 46.912957 -230.893734) (xy 46.965252 -230.909089) (xy 47.014829 -230.931731) (xy 47.060679 -230.961197)
			(xy 47.10187 -230.996888) (xy 47.137561 -231.038079) (xy 47.167027 -231.083929) (xy 47.189669 -231.133506)
			(xy 47.205024 -231.185801) (xy 47.21278 -231.239749) (xy 47.213266 -231.267) (xy 47.21276 -231.295918)
			(xy 47.204031 -231.35309) (xy 47.186771 -231.40829) (xy 47.161377 -231.460251) (xy 47.128431 -231.507785)
			(xy 47.088687 -231.549801) (xy 47.0662 -231.56799) (xy 47.057447 -231.575561) (xy 47.047259 -231.596313)
			(xy 47.046642 -231.607868) (xy 47.046642 -231.688132) (xy 47.047237 -231.699697) (xy 47.057413 -231.720469)
			(xy 47.0662 -231.72801) (xy 47.088688 -231.746195) (xy 47.128423 -231.788216) (xy 47.161362 -231.835752)
			(xy 47.186749 -231.887715) (xy 47.204004 -231.942913) (xy 47.212732 -232.000084) (xy 47.213266 -232.029)
			(xy 47.21278 -232.056251) (xy 47.205024 -232.110199) (xy 47.189669 -232.162494) (xy 47.167027 -232.212071)
			(xy 47.137561 -232.257921) (xy 47.10187 -232.299112) (xy 47.060679 -232.334803) (xy 47.014829 -232.364269)
			(xy 46.965252 -232.386911) (xy 46.912957 -232.402266) (xy 46.859009 -232.410022) (xy 46.804507 -232.410022)
			(xy 46.750559 -232.402266) (xy 46.698264 -232.386911) (xy 46.648687 -232.364269) (xy 46.602837 -232.334803)
			(xy 46.561646 -232.299112) (xy 46.525955 -232.257921) (xy 46.496489 -232.212071) (xy 46.473847 -232.162494)
			(xy 46.458492 -232.110199) (xy 46.450736 -232.056251) (xy 46.45025 -232.029) (xy 42.260266 -232.029)
			(xy 42.259762 -232.071348) (xy 42.251711 -232.155662) (xy 42.235682 -232.238828) (xy 42.211821 -232.320095)
			(xy 42.180342 -232.398725) (xy 42.141531 -232.474006) (xy 42.095741 -232.545258) (xy 42.043385 -232.611834)
			(xy 41.984937 -232.673132) (xy 41.920927 -232.728597) (xy 41.851935 -232.777726) (xy 41.778585 -232.820075)
			(xy 41.701542 -232.855259) (xy 41.621503 -232.882961) (xy 41.539194 -232.902929) (xy 41.455359 -232.914982)
			(xy 41.370758 -232.919013) (xy 41.286157 -232.914982) (xy 41.202322 -232.902929) (xy 41.120013 -232.882961)
			(xy 41.039974 -232.855259) (xy 40.962931 -232.820075) (xy 40.889581 -232.777726) (xy 40.820589 -232.728597)
			(xy 40.756579 -232.673132) (xy 40.698131 -232.611834) (xy 40.645775 -232.545258) (xy 40.599985 -232.474006)
			(xy 40.561174 -232.398725) (xy 40.529695 -232.320095) (xy 40.505834 -232.238828) (xy 40.489805 -232.155662)
			(xy 40.481754 -232.071348) (xy 40.48125 -232.029) (xy 36.391596 -232.029) (xy 36.391596 -234.215178)
			(xy 36.392084 -234.225139) (xy 36.399675 -234.243561) (xy 36.406328 -234.250992) (xy 39.518336 -237.363)
			(xy 40.48125 -237.363) (xy 40.481828 -237.316604) (xy 40.491474 -237.224316) (xy 40.510671 -237.133532)
			(xy 40.539211 -237.045238) (xy 40.55745 -237.002574) (xy 40.561268 -236.992634) (xy 40.561268 -236.971366)
			(xy 40.55745 -236.961426) (xy 40.539203 -236.918765) (xy 40.51066 -236.830472) (xy 40.491468 -236.739687)
			(xy 40.481835 -236.647396) (xy 40.48125 -236.601) (xy 40.481692 -236.559747) (xy 40.489349 -236.477597)
			(xy 40.50458 -236.396508) (xy 40.527253 -236.317178) (xy 40.557173 -236.240288) (xy 40.594084 -236.166498)
			(xy 40.637668 -236.096443) (xy 40.687551 -236.030724) (xy 40.743304 -235.969906) (xy 40.804449 -235.914511)
			(xy 40.87046 -235.865015) (xy 40.94077 -235.821843) (xy 40.977566 -235.803186) (xy 40.985871 -235.798618)
			(xy 40.998622 -235.784615) (xy 41.005418 -235.766937) (xy 41.00576 -235.757466) (xy 41.00576 -235.666534)
			(xy 41.005381 -235.657066) (xy 40.998598 -235.639391) (xy 40.985868 -235.625378) (xy 40.977566 -235.620814)
			(xy 40.940759 -235.602175) (xy 40.870437 -235.559016) (xy 40.804415 -235.509528) (xy 40.743262 -235.454137)
			(xy 40.687503 -235.393319) (xy 40.637617 -235.327598) (xy 40.594034 -235.257538) (xy 40.557129 -235.183742)
			(xy 40.527218 -235.106844) (xy 40.504559 -235.027507) (xy 40.489347 -234.946411) (xy 40.481713 -234.864255)
			(xy 40.48125 -234.823) (xy 40.481828 -234.776604) (xy 40.491474 -234.684316) (xy 40.510671 -234.593532)
			(xy 40.539211 -234.505238) (xy 40.55745 -234.462574) (xy 40.561268 -234.452634) (xy 40.561268 -234.431366)
			(xy 40.55745 -234.421426) (xy 40.539203 -234.378765) (xy 40.51066 -234.290472) (xy 40.491468 -234.199687)
			(xy 40.481835 -234.107396) (xy 40.48125 -234.061) (xy 40.481754 -234.018652) (xy 40.489805 -233.934338)
			(xy 40.505834 -233.851172) (xy 40.529695 -233.769905) (xy 40.561174 -233.691275) (xy 40.599985 -233.615994)
			(xy 40.645775 -233.544742) (xy 40.698131 -233.478166) (xy 40.756579 -233.416868) (xy 40.820589 -233.361403)
			(xy 40.889581 -233.312274) (xy 40.962931 -233.269925) (xy 41.039974 -233.234741) (xy 41.120013 -233.207039)
			(xy 41.202322 -233.187071) (xy 41.286157 -233.175018) (xy 41.370758 -233.170988) (xy 41.455359 -233.175018)
			(xy 41.539194 -233.187071) (xy 41.621503 -233.207039) (xy 41.701542 -233.234741) (xy 41.778585 -233.269925)
			(xy 41.851935 -233.312274) (xy 41.920927 -233.361403) (xy 41.984937 -233.416868) (xy 42.043385 -233.478166)
			(xy 42.095741 -233.544742) (xy 42.141531 -233.615994) (xy 42.180342 -233.691275) (xy 42.211821 -233.769905)
			(xy 42.235682 -233.851172) (xy 42.251711 -233.934338) (xy 42.259762 -234.018652) (xy 42.260266 -234.061)
			(xy 42.259687 -234.107396) (xy 42.250041 -234.199684) (xy 42.230844 -234.290468) (xy 42.202305 -234.378761)
			(xy 42.184066 -234.421426) (xy 42.180247 -234.431366) (xy 42.180247 -234.452634) (xy 42.184066 -234.462574)
			(xy 42.202308 -234.505237) (xy 42.230854 -234.593529) (xy 42.250047 -234.684314) (xy 42.259681 -234.776604)
			(xy 42.260266 -234.823) (xy 46.45025 -234.823) (xy 46.450749 -234.794082) (xy 46.45948 -234.736909)
			(xy 46.47674 -234.681709) (xy 46.502135 -234.629747) (xy 46.535083 -234.582214) (xy 46.574828 -234.540199)
			(xy 46.597316 -234.52201) (xy 46.606072 -234.514442) (xy 46.616258 -234.493688) (xy 46.616874 -234.482132)
			(xy 46.616874 -234.401868) (xy 46.616274 -234.390304) (xy 46.606101 -234.369532) (xy 46.597316 -234.36199)
			(xy 46.574831 -234.343801) (xy 46.535095 -234.301781) (xy 46.502156 -234.254246) (xy 46.476768 -234.202284)
			(xy 46.459512 -234.147086) (xy 46.450784 -234.089916) (xy 46.45025 -234.061) (xy 46.450736 -234.033749)
			(xy 46.458492 -233.979801) (xy 46.473847 -233.927506) (xy 46.496489 -233.877929) (xy 46.525955 -233.832079)
			(xy 46.561646 -233.790888) (xy 46.602837 -233.755197) (xy 46.648687 -233.725731) (xy 46.698264 -233.703089)
			(xy 46.750559 -233.687734) (xy 46.804507 -233.679978) (xy 46.859009 -233.679978) (xy 46.912957 -233.687734)
			(xy 46.965252 -233.703089) (xy 47.014829 -233.725731) (xy 47.060679 -233.755197) (xy 47.10187 -233.790888)
			(xy 47.137561 -233.832079) (xy 47.167027 -233.877929) (xy 47.189669 -233.927506) (xy 47.205024 -233.979801)
			(xy 47.21278 -234.033749) (xy 47.213266 -234.061) (xy 47.21276 -234.089918) (xy 47.204031 -234.14709)
			(xy 47.186771 -234.20229) (xy 47.161377 -234.254251) (xy 47.128431 -234.301785) (xy 47.088687 -234.343801)
			(xy 47.0662 -234.36199) (xy 47.057447 -234.369561) (xy 47.047259 -234.390313) (xy 47.046642 -234.401868)
			(xy 47.046642 -234.482132) (xy 47.047237 -234.493697) (xy 47.057413 -234.514469) (xy 47.0662 -234.52201)
			(xy 47.088688 -234.540195) (xy 47.128423 -234.582216) (xy 47.161362 -234.629752) (xy 47.186749 -234.681715)
			(xy 47.204004 -234.736913) (xy 47.212732 -234.794084) (xy 47.213266 -234.823) (xy 47.21278 -234.850251)
			(xy 47.205024 -234.904199) (xy 47.189669 -234.956494) (xy 47.167027 -235.006071) (xy 47.137561 -235.051921)
			(xy 47.10187 -235.093112) (xy 47.060679 -235.128803) (xy 47.014829 -235.158269) (xy 46.965252 -235.180911)
			(xy 46.912957 -235.196266) (xy 46.859009 -235.204022) (xy 46.804507 -235.204022) (xy 46.750559 -235.196266)
			(xy 46.698264 -235.180911) (xy 46.648687 -235.158269) (xy 46.602837 -235.128803) (xy 46.561646 -235.093112)
			(xy 46.525955 -235.051921) (xy 46.496489 -235.006071) (xy 46.473847 -234.956494) (xy 46.458492 -234.904199)
			(xy 46.450736 -234.850251) (xy 46.45025 -234.823) (xy 42.260266 -234.823) (xy 42.259815 -234.864253)
			(xy 42.252158 -234.946403) (xy 42.236928 -235.027491) (xy 42.214255 -235.10682) (xy 42.184336 -235.18371)
			(xy 42.147426 -235.257499) (xy 42.103843 -235.327554) (xy 42.053961 -235.393274) (xy 41.998208 -235.454092)
			(xy 41.937065 -235.509488) (xy 41.871055 -235.558984) (xy 41.800746 -235.602156) (xy 41.76395 -235.620814)
			(xy 41.755648 -235.625387) (xy 41.742895 -235.639387) (xy 41.736098 -235.657063) (xy 41.735756 -235.666534)
			(xy 41.735756 -235.757466) (xy 41.736127 -235.766935) (xy 41.742912 -235.784611) (xy 41.755646 -235.798623)
			(xy 41.76395 -235.803186) (xy 41.800761 -235.821818) (xy 41.871083 -235.864978) (xy 41.937104 -235.914467)
			(xy 41.998257 -235.969859) (xy 42.054015 -236.030677) (xy 42.1039 -236.096399) (xy 42.147483 -236.16646)
			(xy 42.184388 -236.240257) (xy 42.214299 -236.317155) (xy 42.236957 -236.396493) (xy 42.252169 -236.477589)
			(xy 42.259803 -236.559745) (xy 42.260266 -236.601) (xy 42.259687 -236.647396) (xy 42.250041 -236.739684)
			(xy 42.230844 -236.830468) (xy 42.202305 -236.918761) (xy 42.184066 -236.961426) (xy 42.180247 -236.971366)
			(xy 42.180247 -236.992634) (xy 42.184066 -237.002574) (xy 42.202308 -237.045237) (xy 42.230854 -237.133529)
			(xy 42.250047 -237.224314) (xy 42.259681 -237.316604) (xy 42.260266 -237.363) (xy 46.45025 -237.363)
			(xy 46.450749 -237.334082) (xy 46.45948 -237.276909) (xy 46.47674 -237.221709) (xy 46.502135 -237.169747)
			(xy 46.535083 -237.122214) (xy 46.574828 -237.080199) (xy 46.597316 -237.06201) (xy 46.606072 -237.054442)
			(xy 46.616258 -237.033688) (xy 46.616874 -237.022132) (xy 46.616874 -236.941868) (xy 46.616274 -236.930304)
			(xy 46.606101 -236.909532) (xy 46.597316 -236.90199) (xy 46.574831 -236.883801) (xy 46.535095 -236.841781)
			(xy 46.502156 -236.794246) (xy 46.476768 -236.742284) (xy 46.459512 -236.687086) (xy 46.450784 -236.629916)
			(xy 46.45025 -236.601) (xy 46.450736 -236.573749) (xy 46.458492 -236.519801) (xy 46.473847 -236.467506)
			(xy 46.496489 -236.417929) (xy 46.525955 -236.372079) (xy 46.561646 -236.330888) (xy 46.602837 -236.295197)
			(xy 46.648687 -236.265731) (xy 46.698264 -236.243089) (xy 46.750559 -236.227734) (xy 46.804507 -236.219978)
			(xy 46.859009 -236.219978) (xy 46.912957 -236.227734) (xy 46.965252 -236.243089) (xy 47.014829 -236.265731)
			(xy 47.060679 -236.295197) (xy 47.10187 -236.330888) (xy 47.137561 -236.372079) (xy 47.167027 -236.417929)
			(xy 47.189669 -236.467506) (xy 47.205024 -236.519801) (xy 47.21278 -236.573749) (xy 47.213266 -236.601)
			(xy 47.21276 -236.629918) (xy 47.204031 -236.68709) (xy 47.186771 -236.74229) (xy 47.161377 -236.794251)
			(xy 47.128431 -236.841785) (xy 47.088687 -236.883801) (xy 47.0662 -236.90199) (xy 47.057447 -236.909561)
			(xy 47.047259 -236.930313) (xy 47.046642 -236.941868) (xy 47.046642 -237.022132) (xy 47.047237 -237.033697)
			(xy 47.057413 -237.054469) (xy 47.0662 -237.06201) (xy 47.088688 -237.080195) (xy 47.128423 -237.122216)
			(xy 47.161362 -237.169752) (xy 47.186749 -237.221715) (xy 47.204004 -237.276913) (xy 47.212732 -237.334084)
			(xy 47.213266 -237.363) (xy 47.21278 -237.390251) (xy 47.205024 -237.444199) (xy 47.189669 -237.496494)
			(xy 47.167027 -237.546071) (xy 47.137561 -237.591921) (xy 47.10187 -237.633112) (xy 47.060679 -237.668803)
			(xy 47.014829 -237.698269) (xy 46.965252 -237.720911) (xy 46.912957 -237.736266) (xy 46.859009 -237.744022)
			(xy 46.804507 -237.744022) (xy 46.750559 -237.736266) (xy 46.698264 -237.720911) (xy 46.648687 -237.698269)
			(xy 46.602837 -237.668803) (xy 46.561646 -237.633112) (xy 46.525955 -237.591921) (xy 46.496489 -237.546071)
			(xy 46.473847 -237.496494) (xy 46.458492 -237.444199) (xy 46.450736 -237.390251) (xy 46.45025 -237.363)
			(xy 42.260266 -237.363) (xy 42.259762 -237.405348) (xy 42.251711 -237.489662) (xy 42.235682 -237.572828)
			(xy 42.211821 -237.654095) (xy 42.180342 -237.732725) (xy 42.141531 -237.808006) (xy 42.095741 -237.879258)
			(xy 42.043385 -237.945834) (xy 41.984937 -238.007132) (xy 41.920927 -238.062597) (xy 41.851935 -238.111726)
			(xy 41.778585 -238.154075) (xy 41.701542 -238.189259) (xy 41.621503 -238.216961) (xy 41.539194 -238.236929)
			(xy 41.455359 -238.248982) (xy 41.370758 -238.253013) (xy 41.286157 -238.248982) (xy 41.202322 -238.236929)
			(xy 41.120013 -238.216961) (xy 41.039974 -238.189259) (xy 40.962931 -238.154075) (xy 40.889581 -238.111726)
			(xy 40.820589 -238.062597) (xy 40.756579 -238.007132) (xy 40.698131 -237.945834) (xy 40.645775 -237.879258)
			(xy 40.599985 -237.808006) (xy 40.561174 -237.732725) (xy 40.529695 -237.654095) (xy 40.505834 -237.572828)
			(xy 40.489805 -237.489662) (xy 40.481754 -237.405348) (xy 40.48125 -237.363) (xy 39.518336 -237.363)
			(xy 41.660572 -239.505236) (xy 41.66756 -239.511714) (xy 41.684988 -239.519386) (xy 41.704014 -239.520144)
			(xy 41.71315 -239.517428) (xy 41.813734 -239.482376) (xy 41.831514 -239.460024) (xy 41.833292 -239.445038)
			(xy 41.838997 -239.40064) (xy 41.858179 -239.3132) (xy 41.886037 -239.228127) (xy 41.90365 -239.186974)
			(xy 41.907468 -239.177034) (xy 41.907468 -239.155766) (xy 41.90365 -239.145826) (xy 41.885411 -239.103162)
			(xy 41.856871 -239.014868) (xy 41.837674 -238.924084) (xy 41.828028 -238.831796) (xy 41.82745 -238.7854)
			(xy 41.827954 -238.743052) (xy 41.836005 -238.658738) (xy 41.852034 -238.575572) (xy 41.875895 -238.494305)
			(xy 41.907374 -238.415675) (xy 41.946185 -238.340394) (xy 41.991975 -238.269142) (xy 42.044331 -238.202566)
			(xy 42.102779 -238.141268) (xy 42.166789 -238.085803) (xy 42.235781 -238.036674) (xy 42.309131 -237.994325)
			(xy 42.386174 -237.959141) (xy 42.466213 -237.931439) (xy 42.548522 -237.911471) (xy 42.632357 -237.899418)
			(xy 42.716958 -237.895388) (xy 42.801559 -237.899418) (xy 42.885394 -237.911471) (xy 42.967703 -237.931439)
			(xy 43.047742 -237.959141) (xy 43.124785 -237.994325) (xy 43.198135 -238.036674) (xy 43.267127 -238.085803)
			(xy 43.331137 -238.141268) (xy 43.389585 -238.202566) (xy 43.441941 -238.269142) (xy 43.487731 -238.340394)
			(xy 43.526542 -238.415675) (xy 43.558021 -238.494305) (xy 43.581882 -238.575572) (xy 43.597911 -238.658738)
			(xy 43.605962 -238.743052) (xy 43.606466 -238.7854) (xy 43.605881 -238.831796) (xy 43.596247 -238.924086)
			(xy 43.577054 -239.014871) (xy 43.548508 -239.103163) (xy 43.530266 -239.145826) (xy 43.526447 -239.155766)
			(xy 43.526447 -239.177034) (xy 43.530266 -239.186974) (xy 43.548505 -239.229639) (xy 43.577044 -239.317932)
			(xy 43.596241 -239.408716) (xy 43.605887 -239.501004) (xy 43.606466 -239.5474) (xy 46.14545 -239.5474)
			(xy 46.145949 -239.518482) (xy 46.15468 -239.461309) (xy 46.17194 -239.406109) (xy 46.197335 -239.354147)
			(xy 46.230283 -239.306614) (xy 46.270028 -239.264599) (xy 46.292516 -239.24641) (xy 46.301272 -239.238842)
			(xy 46.311458 -239.218088) (xy 46.312074 -239.206532) (xy 46.312074 -239.126268) (xy 46.311474 -239.114704)
			(xy 46.301301 -239.093932) (xy 46.292516 -239.08639) (xy 46.270031 -239.068201) (xy 46.230295 -239.026181)
			(xy 46.197356 -238.978646) (xy 46.171968 -238.926684) (xy 46.154712 -238.871486) (xy 46.145984 -238.814316)
			(xy 46.14545 -238.7854) (xy 46.145936 -238.758149) (xy 46.153692 -238.704201) (xy 46.169047 -238.651906)
			(xy 46.191689 -238.602329) (xy 46.221155 -238.556479) (xy 46.256846 -238.515288) (xy 46.298037 -238.479597)
			(xy 46.343887 -238.450131) (xy 46.393464 -238.427489) (xy 46.445759 -238.412134) (xy 46.499707 -238.404378)
			(xy 46.554209 -238.404378) (xy 46.608157 -238.412134) (xy 46.660452 -238.427489) (xy 46.710029 -238.450131)
			(xy 46.755879 -238.479597) (xy 46.79707 -238.515288) (xy 46.832761 -238.556479) (xy 46.862227 -238.602329)
			(xy 46.884869 -238.651906) (xy 46.900224 -238.704201) (xy 46.90798 -238.758149) (xy 46.908466 -238.7854)
			(xy 46.90796 -238.814318) (xy 46.899231 -238.87149) (xy 46.881971 -238.92669) (xy 46.856577 -238.978651)
			(xy 46.823631 -239.026185) (xy 46.783887 -239.068201) (xy 46.7614 -239.08639) (xy 46.752647 -239.093961)
			(xy 46.742459 -239.114713) (xy 46.741842 -239.126268) (xy 46.741842 -239.206532) (xy 46.742437 -239.218097)
			(xy 46.752613 -239.238869) (xy 46.7614 -239.24641) (xy 46.783888 -239.264595) (xy 46.823623 -239.306616)
			(xy 46.856562 -239.354152) (xy 46.881949 -239.406115) (xy 46.899204 -239.461313) (xy 46.907932 -239.518484)
			(xy 46.908466 -239.5474) (xy 46.90798 -239.574651) (xy 46.900224 -239.628599) (xy 46.884869 -239.680894)
			(xy 46.862227 -239.730471) (xy 46.832761 -239.776321) (xy 46.79707 -239.817512) (xy 46.755879 -239.853203)
			(xy 46.710029 -239.882669) (xy 46.660452 -239.905311) (xy 46.608157 -239.920666) (xy 46.554209 -239.928422)
			(xy 46.499707 -239.928422) (xy 46.445759 -239.920666) (xy 46.393464 -239.905311) (xy 46.343887 -239.882669)
			(xy 46.298037 -239.853203) (xy 46.256846 -239.817512) (xy 46.221155 -239.776321) (xy 46.191689 -239.730471)
			(xy 46.169047 -239.680894) (xy 46.153692 -239.628599) (xy 46.145936 -239.574651) (xy 46.14545 -239.5474)
			(xy 43.606466 -239.5474) (xy 43.605955 -239.590567) (xy 43.597592 -239.676494) (xy 43.580945 -239.761207)
			(xy 43.55617 -239.843909) (xy 43.523501 -239.923823) (xy 43.483244 -240.000196) (xy 43.435778 -240.07231)
			(xy 43.381551 -240.139487) (xy 43.32107 -240.201096) (xy 43.254907 -240.256556) (xy 43.183682 -240.305346)
			(xy 43.108066 -240.347007) (xy 43.02877 -240.381148) (xy 42.94654 -240.407447) (xy 42.862149 -240.425656)
			(xy 42.81932 -240.431066) (xy 42.804334 -240.432844) (xy 42.781982 -240.450624) (xy 42.74693 -240.551208)
			(xy 42.74422 -240.560337) (xy 42.745026 -240.57935) (xy 42.75268 -240.596772) (xy 42.759122 -240.603786)
			(xy 44.850304 -242.694968) (xy 44.856941 -242.701088) (xy 44.873329 -242.708635) (xy 44.891316 -242.710053)
			(xy 44.900088 -242.707922) (xy 44.998894 -242.679982) (xy 45.017944 -242.659916) (xy 45.020992 -242.646454)
			(xy 45.032629 -242.599627) (xy 45.064707 -242.508621) (xy 45.085 -242.464844) (xy 45.089334 -242.454343)
			(xy 45.089334 -242.431657) (xy 45.085 -242.421156) (xy 45.068201 -242.385102) (xy 45.040354 -242.310589)
			(xy 45.019278 -242.233885) (xy 45.005142 -242.155604) (xy 44.998059 -242.076374) (xy 44.997624 -242.0366)
			(xy 44.998084 -241.995497) (xy 45.005669 -241.913643) (xy 45.020775 -241.832837) (xy 45.043272 -241.75377)
			(xy 45.072968 -241.677116) (xy 45.109611 -241.60353) (xy 45.152888 -241.533638) (xy 45.202428 -241.468038)
			(xy 45.257811 -241.407288) (xy 45.318562 -241.351908) (xy 45.384164 -241.30237) (xy 45.454058 -241.259096)
			(xy 45.527646 -241.222456) (xy 45.604301 -241.192762) (xy 45.683368 -241.170267) (xy 45.764175 -241.155165)
			(xy 45.846029 -241.147583) (xy 45.887132 -241.147092) (xy 45.928462 -241.147564) (xy 46.010764 -241.155232)
			(xy 46.092001 -241.170499) (xy 46.171472 -241.193234) (xy 46.248492 -241.223241) (xy 46.285658 -241.241326)
			(xy 46.295748 -241.245731) (xy 46.317732 -241.246371) (xy 46.328076 -241.242596) (xy 46.36927 -241.22578)
			(xy 46.454285 -241.199511) (xy 46.5415 -241.181869) (xy 46.630041 -241.173031) (xy 46.674532 -241.172492)
			(xy 46.715496 -241.172962) (xy 46.797078 -241.180503) (xy 46.877619 -241.195517) (xy 46.956438 -241.217877)
			(xy 46.994826 -241.232182) (xy 47.004552 -241.235375) (xy 47.024989 -241.234572) (xy 47.03445 -241.230658)
			(xy 47.06987 -241.214572) (xy 47.142966 -241.187931) (xy 47.21811 -241.167778) (xy 47.294727 -241.154265)
			(xy 47.372232 -241.147498) (xy 47.411132 -241.147092) (xy 47.452234 -241.147568) (xy 47.534086 -241.155156)
			(xy 47.614889 -241.170263) (xy 47.693953 -241.192761) (xy 47.770604 -241.222459) (xy 47.844189 -241.259101)
			(xy 47.914078 -241.302377) (xy 47.979677 -241.351917) (xy 48.040424 -241.407298) (xy 48.095803 -241.468048)
			(xy 48.145341 -241.533648) (xy 48.188614 -241.603539) (xy 48.225254 -241.677125) (xy 48.254949 -241.753777)
			(xy 48.277444 -241.832842) (xy 48.292549 -241.913646) (xy 48.300133 -241.995498) (xy 48.30064 -242.0366)
			(xy 48.300196 -242.076372) (xy 48.293091 -242.155599) (xy 48.278947 -242.233875) (xy 48.257876 -242.310578)
			(xy 48.230047 -242.385096) (xy 48.213264 -242.421156) (xy 48.208933 -242.431657) (xy 48.208933 -242.454343)
			(xy 48.213264 -242.464844) (xy 48.230062 -242.500898) (xy 48.257907 -242.575412) (xy 48.278982 -242.652116)
			(xy 48.293117 -242.730396) (xy 48.300199 -242.809627) (xy 48.30064 -242.8494) (xy 48.300165 -242.890503)
			(xy 48.292581 -242.972358) (xy 48.277476 -243.053165) (xy 48.254979 -243.132233) (xy 48.225284 -243.208888)
			(xy 48.188642 -243.282476) (xy 48.145367 -243.35237) (xy 48.095828 -243.417972) (xy 48.040447 -243.478724)
			(xy 47.979697 -243.534107) (xy 47.914096 -243.583649) (xy 47.844204 -243.626926) (xy 47.770617 -243.663571)
			(xy 47.693963 -243.693269) (xy 47.614896 -243.715768) (xy 47.53409 -243.730876) (xy 47.452235 -243.738464)
			(xy 47.411132 -243.738908) (xy 47.370167 -243.738441) (xy 47.288584 -243.730906) (xy 47.208041 -243.715897)
			(xy 47.12922 -243.693542) (xy 47.090838 -243.679218) (xy 47.081111 -243.676012) (xy 47.060663 -243.676792)
			(xy 47.051214 -243.680742) (xy 47.015794 -243.696831) (xy 46.942699 -243.723477) (xy 46.867555 -243.743636)
			(xy 46.790938 -243.757153) (xy 46.713432 -243.763926) (xy 46.674532 -243.764308) (xy 46.633202 -243.763839)
			(xy 46.550897 -243.756177) (xy 46.469658 -243.740915) (xy 46.390184 -243.718184) (xy 46.313161 -243.688182)
			(xy 46.276006 -243.670074) (xy 46.265916 -243.665655) (xy 46.243921 -243.664989) (xy 46.233588 -243.668804)
			(xy 46.192395 -243.685623) (xy 46.10738 -243.711898) (xy 46.020165 -243.729546) (xy 45.931624 -243.738391)
			(xy 45.887132 -243.738908) (xy 45.842551 -243.738364) (xy 45.753838 -243.729445) (xy 45.666461 -243.711693)
			(xy 45.5813 -243.685287) (xy 45.499209 -243.650491) (xy 45.421012 -243.607655) (xy 45.347494 -243.557209)
			(xy 45.313092 -243.52885) (xy 45.301662 -243.519198) (xy 45.272452 -243.515134) (xy 45.17517 -243.560346)
			(xy 45.166648 -243.564812) (xy 45.15349 -243.578829) (xy 45.146418 -243.596707) (xy 45.14596 -243.60632)
			(xy 45.14596 -245.36908) (xy 45.14637 -245.378698) (xy 45.153457 -245.396582) (xy 45.166639 -245.410592)
			(xy 45.17517 -245.415054) (xy 45.272452 -245.460266) (xy 45.301662 -245.456202) (xy 45.313092 -245.44655)
			(xy 45.347499 -245.4182) (xy 45.421022 -245.367768) (xy 45.499222 -245.324942) (xy 45.581312 -245.290153)
			(xy 45.666471 -245.26375) (xy 45.753843 -245.245997) (xy 45.842553 -245.237072) (xy 45.887132 -245.236492)
			(xy 45.928462 -245.236964) (xy 46.010764 -245.244632) (xy 46.092001 -245.259899) (xy 46.171472 -245.282634)
			(xy 46.248492 -245.312641) (xy 46.285658 -245.330726) (xy 46.295748 -245.335131) (xy 46.317732 -245.335771)
			(xy 46.328076 -245.331996) (xy 46.36927 -245.31518) (xy 46.454285 -245.288911) (xy 46.5415 -245.271269)
			(xy 46.630041 -245.262431) (xy 46.674532 -245.261892) (xy 46.715496 -245.262362) (xy 46.797078 -245.269903)
			(xy 46.877619 -245.284917) (xy 46.956438 -245.307277) (xy 46.994826 -245.321582) (xy 47.004552 -245.324775)
			(xy 47.024989 -245.323972) (xy 47.03445 -245.320058) (xy 47.06987 -245.303972) (xy 47.142966 -245.277331)
			(xy 47.21811 -245.257178) (xy 47.294727 -245.243665) (xy 47.372232 -245.236898) (xy 47.411132 -245.236492)
			(xy 47.45348 -245.236997) (xy 47.537791 -245.245051) (xy 47.620955 -245.261082) (xy 47.702218 -245.284946)
			(xy 47.780846 -245.316426) (xy 47.856125 -245.355237) (xy 47.927374 -245.401028) (xy 47.993947 -245.453385)
			(xy 48.055243 -245.511832) (xy 48.110705 -245.575841) (xy 48.159832 -245.644833) (xy 48.202179 -245.718181)
			(xy 48.237362 -245.795223) (xy 48.265062 -245.87526) (xy 48.28503 -245.957568) (xy 48.297083 -246.041401)
			(xy 48.301113 -246.126) (xy 48.297083 -246.210599) (xy 48.28503 -246.294432) (xy 48.265062 -246.37674)
			(xy 48.237362 -246.456777) (xy 48.202179 -246.533819) (xy 48.159832 -246.607167) (xy 48.110705 -246.676159)
			(xy 48.055243 -246.740168) (xy 47.993947 -246.798615) (xy 47.927374 -246.850972) (xy 47.856125 -246.896763)
			(xy 47.780846 -246.935574) (xy 47.702218 -246.967054) (xy 47.620955 -246.990918) (xy 47.537791 -247.006949)
			(xy 47.45348 -247.015003) (xy 47.411132 -247.015508) (xy 47.370167 -247.015041) (xy 47.288584 -247.007506)
			(xy 47.208041 -246.992497) (xy 47.12922 -246.970142) (xy 47.090838 -246.955818) (xy 47.081111 -246.952612)
			(xy 47.060663 -246.953392) (xy 47.051214 -246.957342) (xy 47.015794 -246.973431) (xy 46.942699 -247.000077)
			(xy 46.867555 -247.020236) (xy 46.790938 -247.033753) (xy 46.713432 -247.040526) (xy 46.674532 -247.040908)
			(xy 46.633202 -247.040439) (xy 46.550897 -247.032777) (xy 46.469658 -247.017515) (xy 46.390184 -246.994784)
			(xy 46.313161 -246.964782) (xy 46.276006 -246.946674) (xy 46.265916 -246.942255) (xy 46.243921 -246.941589)
			(xy 46.233588 -246.945404) (xy 46.192395 -246.962223) (xy 46.10738 -246.988498) (xy 46.020165 -247.006146)
			(xy 45.931624 -247.014991) (xy 45.887132 -247.015508) (xy 45.842551 -247.014964) (xy 45.753838 -247.006045)
			(xy 45.666461 -246.988293) (xy 45.5813 -246.961887) (xy 45.499209 -246.927091) (xy 45.421012 -246.884255)
			(xy 45.347494 -246.833809) (xy 45.313092 -246.80545) (xy 45.301662 -246.795798) (xy 45.272452 -246.791734)
			(xy 45.17517 -246.836946) (xy 45.166648 -246.841412) (xy 45.15349 -246.855429) (xy 45.146418 -246.873307)
			(xy 45.14596 -246.88292) (xy 45.14596 -249.093228) (xy 45.146401 -249.102611) (xy 45.153159 -249.120119)
			(xy 45.165734 -249.134051) (xy 45.1739 -249.138694) (xy 45.268388 -249.185684) (xy 45.296836 -249.183144)
			(xy 45.30852 -249.174254) (xy 45.33351 -249.156146) (xy 45.388112 -249.127392) (xy 45.446628 -249.107796)
			(xy 45.507535 -249.097867) (xy 45.53839 -249.097292) (xy 45.567307 -249.097825) (xy 45.624479 -249.106551)
			(xy 45.67968 -249.123804) (xy 45.731645 -249.149188) (xy 45.779185 -249.182124) (xy 45.821211 -249.221856)
			(xy 45.83938 -249.244358) (xy 45.846924 -249.253139) (xy 45.867695 -249.263307) (xy 45.879258 -249.263916)
			(xy 45.959522 -249.263916) (xy 45.97108 -249.263303) (xy 45.991844 -249.253125) (xy 45.9994 -249.244358)
			(xy 46.016153 -249.223575) (xy 46.054507 -249.186445) (xy 46.097661 -249.155023) (xy 46.144775 -249.129924)
			(xy 46.194927 -249.111638) (xy 46.247138 -249.100521) (xy 46.30039 -249.096791) (xy 46.353642 -249.100521)
			(xy 46.405853 -249.111638) (xy 46.456005 -249.129924) (xy 46.503119 -249.155023) (xy 46.546273 -249.186445)
			(xy 46.584627 -249.223575) (xy 46.60138 -249.244358) (xy 46.608924 -249.253139) (xy 46.629695 -249.263307)
			(xy 46.641258 -249.263916) (xy 46.721522 -249.263916) (xy 46.73308 -249.263303) (xy 46.753844 -249.253125)
			(xy 46.7614 -249.244358) (xy 46.778153 -249.223575) (xy 46.816507 -249.186445) (xy 46.859661 -249.155023)
			(xy 46.906775 -249.129924) (xy 46.956927 -249.111638) (xy 47.009138 -249.100521) (xy 47.06239 -249.096791)
			(xy 47.115642 -249.100521) (xy 47.167853 -249.111638) (xy 47.218005 -249.129924) (xy 47.265119 -249.155023)
			(xy 47.308273 -249.186445) (xy 47.346627 -249.223575) (xy 47.36338 -249.244358) (xy 47.370924 -249.253139)
			(xy 47.391695 -249.263307) (xy 47.403258 -249.263916) (xy 47.483522 -249.263916) (xy 47.49508 -249.263303)
			(xy 47.515844 -249.253125) (xy 47.5234 -249.244358) (xy 47.54159 -249.221873) (xy 47.583606 -249.182134)
			(xy 47.63114 -249.149194) (xy 47.683103 -249.123808) (xy 47.738302 -249.106558) (xy 47.795474 -249.09784)
			(xy 47.82439 -249.097292) (xy 47.851643 -249.097755) (xy 47.905595 -249.10551) (xy 47.957894 -249.120866)
			(xy 48.007476 -249.143508) (xy 48.05333 -249.172975) (xy 48.094524 -249.208669) (xy 48.130219 -249.249862)
			(xy 48.159688 -249.295715) (xy 48.182331 -249.345296) (xy 48.197687 -249.397595) (xy 48.205445 -249.451547)
			(xy 48.205445 -249.506053) (xy 48.197687 -249.560005) (xy 48.182331 -249.612304) (xy 48.159688 -249.661885)
			(xy 48.130219 -249.707738) (xy 48.094524 -249.748931) (xy 48.05333 -249.784625) (xy 48.007476 -249.814092)
			(xy 47.957894 -249.836734) (xy 47.905595 -249.85209) (xy 47.851643 -249.859845) (xy 47.82439 -249.860308)
			(xy 47.795474 -249.859773) (xy 47.738303 -249.851045) (xy 47.683104 -249.83379) (xy 47.631141 -249.808404)
			(xy 47.583604 -249.775467) (xy 47.54158 -249.735734) (xy 47.5234 -249.713242) (xy 47.515854 -249.704464)
			(xy 47.495083 -249.694305) (xy 47.483522 -249.693684) (xy 47.403258 -249.693684) (xy 47.391702 -249.694301)
			(xy 47.370945 -249.704484) (xy 47.36338 -249.713242) (xy 47.346627 -249.734025) (xy 47.308273 -249.771155)
			(xy 47.265119 -249.802577) (xy 47.218005 -249.827676) (xy 47.167853 -249.845962) (xy 47.115642 -249.857079)
			(xy 47.06239 -249.860809) (xy 47.009138 -249.857079) (xy 46.956927 -249.845962) (xy 46.906775 -249.827676)
			(xy 46.859661 -249.802577) (xy 46.816507 -249.771155) (xy 46.778153 -249.734025) (xy 46.7614 -249.713242)
			(xy 46.753854 -249.704464) (xy 46.733083 -249.694305) (xy 46.721522 -249.693684) (xy 46.641258 -249.693684)
			(xy 46.629702 -249.694301) (xy 46.608945 -249.704484) (xy 46.60138 -249.713242) (xy 46.584627 -249.734025)
			(xy 46.546273 -249.771155) (xy 46.503119 -249.802577) (xy 46.456005 -249.827676) (xy 46.405853 -249.845962)
			(xy 46.353642 -249.857079) (xy 46.30039 -249.860809) (xy 46.247138 -249.857079) (xy 46.194927 -249.845962)
			(xy 46.144775 -249.827676) (xy 46.097661 -249.802577) (xy 46.054507 -249.771155) (xy 46.016153 -249.734025)
			(xy 45.9994 -249.713242) (xy 45.991854 -249.704464) (xy 45.971083 -249.694305) (xy 45.959522 -249.693684)
			(xy 45.879258 -249.693684) (xy 45.867702 -249.694301) (xy 45.846945 -249.704484) (xy 45.83938 -249.713242)
			(xy 45.821192 -249.735731) (xy 45.779179 -249.77548) (xy 45.731646 -249.80843) (xy 45.679683 -249.833827)
			(xy 45.624482 -249.851088) (xy 45.567308 -249.859817) (xy 45.53839 -249.860308) (xy 45.507536 -249.859715)
			(xy 45.446631 -249.84979) (xy 45.388114 -249.830198) (xy 45.33351 -249.801452) (xy 45.30852 -249.783346)
			(xy 45.296836 -249.774456) (xy 45.268388 -249.771916) (xy 45.1739 -249.818906) (xy 45.165657 -249.823453)
			(xy 45.153023 -249.837393) (xy 45.1463 -249.854963) (xy 45.14596 -249.864372) (xy 45.14596 -253.01067)
			(xy 45.146446 -253.020633) (xy 45.15403 -253.03906) (xy 45.160692 -253.046484) (xy 45.57141 -253.457456)
			(xy 45.591489 -253.478335) (xy 45.601419 -253.492) (xy 45.759624 -253.492) (xy 45.760133 -253.463083)
			(xy 45.768863 -253.405911) (xy 45.786122 -253.350711) (xy 45.811515 -253.298749) (xy 45.844461 -253.251216)
			(xy 45.884204 -253.2092) (xy 45.90669 -253.19101) (xy 45.915441 -253.183438) (xy 45.925631 -253.162687)
			(xy 45.926248 -253.151132) (xy 45.926248 -253.070868) (xy 45.925657 -253.059302) (xy 45.915479 -253.03853)
			(xy 45.90669 -253.03099) (xy 45.8842 -253.012807) (xy 45.844465 -252.970785) (xy 45.811527 -252.923249)
			(xy 45.78614 -252.871286) (xy 45.768885 -252.816087) (xy 45.760158 -252.758916) (xy 45.759624 -252.73)
			(xy 45.760055 -252.702746) (xy 45.767813 -252.648792) (xy 45.783171 -252.596492) (xy 45.805816 -252.546909)
			(xy 45.835287 -252.501055) (xy 45.870984 -252.459861) (xy 45.91218 -252.424167) (xy 45.958037 -252.3947)
			(xy 46.007622 -252.37206) (xy 46.059923 -252.356706) (xy 46.113878 -252.348953) (xy 46.141132 -252.348492)
			(xy 46.170049 -252.349024) (xy 46.227221 -252.357746) (xy 46.282421 -252.374998) (xy 46.334384 -252.400387)
			(xy 46.381917 -252.43333) (xy 46.423933 -252.473072) (xy 46.442122 -252.495558) (xy 46.449669 -252.504335)
			(xy 46.470439 -252.514508) (xy 46.482 -252.515116) (xy 46.562264 -252.515116) (xy 46.573828 -252.514519)
			(xy 46.594599 -252.504343) (xy 46.602142 -252.495558) (xy 46.618895 -252.474775) (xy 46.657249 -252.437645)
			(xy 46.700403 -252.406223) (xy 46.747517 -252.381124) (xy 46.797669 -252.362838) (xy 46.84988 -252.351721)
			(xy 46.903132 -252.347991) (xy 46.956384 -252.351721) (xy 47.008595 -252.362838) (xy 47.058747 -252.381124)
			(xy 47.105861 -252.406223) (xy 47.149015 -252.437645) (xy 47.187369 -252.474775) (xy 47.204122 -252.495558)
			(xy 47.211669 -252.504335) (xy 47.232439 -252.514508) (xy 47.244 -252.515116) (xy 47.324264 -252.515116)
			(xy 47.335828 -252.514519) (xy 47.356599 -252.504343) (xy 47.364142 -252.495558) (xy 47.382299 -252.473046)
			(xy 47.424327 -252.433314) (xy 47.471869 -252.40038) (xy 47.523837 -252.374997) (xy 47.57904 -252.357746)
			(xy 47.636214 -252.349024) (xy 47.665132 -252.348492) (xy 47.692503 -252.348941) (xy 47.746683 -252.356763)
			(xy 47.799186 -252.372257) (xy 47.848932 -252.395102) (xy 47.894899 -252.424829) (xy 47.91583 -252.442472)
			(xy 47.922942 -252.448568) (xy 47.93996 -252.454918) (xy 48.025304 -252.454918) (xy 48.042322 -252.448568)
			(xy 48.049434 -252.442472) (xy 48.070377 -252.424846) (xy 48.116347 -252.395133) (xy 48.166092 -252.372295)
			(xy 48.21859 -252.356801) (xy 48.272764 -252.348969) (xy 48.300132 -252.348492) (xy 48.327384 -252.348948)
			(xy 48.381333 -252.356709) (xy 48.433628 -252.372068) (xy 48.483205 -252.394713) (xy 48.529056 -252.424183)
			(xy 48.570246 -252.459877) (xy 48.605937 -252.50107) (xy 48.635402 -252.546923) (xy 48.658043 -252.596502)
			(xy 48.673398 -252.648798) (xy 48.681154 -252.702748) (xy 48.68164 -252.73) (xy 48.681144 -252.758918)
			(xy 48.672414 -252.816091) (xy 48.655153 -252.871292) (xy 48.629757 -252.923254) (xy 48.596808 -252.970787)
			(xy 48.557062 -253.012802) (xy 48.534574 -253.03099) (xy 48.525817 -253.038556) (xy 48.515632 -253.059312)
			(xy 48.515016 -253.070868) (xy 48.515016 -253.151132) (xy 48.51562 -253.162696) (xy 48.52579 -253.183468)
			(xy 48.534574 -253.19101) (xy 48.557057 -253.209202) (xy 48.596793 -253.251221) (xy 48.629733 -253.298755)
			(xy 48.655122 -253.350716) (xy 48.672378 -253.405914) (xy 48.681106 -253.463084) (xy 48.68164 -253.492)
			(xy 48.681122 -253.51925) (xy 48.673367 -253.573195) (xy 48.658013 -253.625487) (xy 48.635374 -253.675062)
			(xy 48.605911 -253.720911) (xy 48.570223 -253.7621) (xy 48.529037 -253.797792) (xy 48.48319 -253.827259)
			(xy 48.433617 -253.849902) (xy 48.381326 -253.86526) (xy 48.327382 -253.87302) (xy 48.300132 -253.873508)
			(xy 48.272763 -253.873021) (xy 48.218584 -253.865208) (xy 48.166082 -253.849724) (xy 48.116334 -253.826887)
			(xy 48.070367 -253.797167) (xy 48.049434 -253.779528) (xy 48.042322 -253.773432) (xy 48.025304 -253.767082)
			(xy 47.93996 -253.767082) (xy 47.922942 -253.773432) (xy 47.91583 -253.779528) (xy 47.894901 -253.797171)
			(xy 47.848927 -253.826881) (xy 47.799179 -253.849716) (xy 47.746677 -253.865206) (xy 47.692501 -253.873034)
			(xy 47.665132 -253.873508) (xy 47.636214 -253.873001) (xy 47.579041 -253.864275) (xy 47.52384 -253.847017)
			(xy 47.471878 -253.821623) (xy 47.424345 -253.788676) (xy 47.38233 -253.74893) (xy 47.364142 -253.726442)
			(xy 47.356568 -253.717694) (xy 47.335818 -253.707505) (xy 47.324264 -253.706884) (xy 47.244 -253.706884)
			(xy 47.232433 -253.70746) (xy 47.211662 -253.717651) (xy 47.204122 -253.726442) (xy 47.187369 -253.747225)
			(xy 47.149015 -253.784355) (xy 47.105861 -253.815777) (xy 47.058747 -253.840876) (xy 47.008595 -253.859162)
			(xy 46.956384 -253.870279) (xy 46.903132 -253.874009) (xy 46.84988 -253.870279) (xy 46.797669 -253.859162)
			(xy 46.747517 -253.840876) (xy 46.700403 -253.815777) (xy 46.657249 -253.784355) (xy 46.618895 -253.747225)
			(xy 46.602142 -253.726442) (xy 46.594568 -253.717694) (xy 46.573818 -253.707505) (xy 46.562264 -253.706884)
			(xy 46.482 -253.706884) (xy 46.470433 -253.70746) (xy 46.449662 -253.717651) (xy 46.442122 -253.726442)
			(xy 46.423929 -253.748924) (xy 46.381909 -253.788657) (xy 46.334374 -253.821595) (xy 46.282413 -253.846983)
			(xy 46.227216 -253.864241) (xy 46.170048 -253.872972) (xy 46.141132 -253.873508) (xy 46.11388 -253.873015)
			(xy 46.05993 -253.865262) (xy 46.007633 -253.84991) (xy 45.958053 -253.827272) (xy 45.912199 -253.797807)
			(xy 45.871006 -253.762116) (xy 45.835312 -253.720926) (xy 45.805844 -253.675075) (xy 45.783201 -253.625497)
			(xy 45.767845 -253.573201) (xy 45.760087 -253.519252) (xy 45.759624 -253.492) (xy 45.601419 -253.492)
			(xy 45.625539 -253.525194) (xy 45.65184 -253.576802) (xy 45.669744 -253.631889) (xy 45.678811 -253.689098)
			(xy 45.67936 -253.71806) (xy 45.67936 -255.194562) (xy 45.678824 -255.223527) (xy 45.669768 -255.280744)
			(xy 45.651872 -255.335839) (xy 45.625578 -255.387457) (xy 45.591532 -255.434326) (xy 45.57141 -255.455166)
			(xy 43.975528 -257.051302) (xy 43.968841 -257.05871) (xy 43.961256 -257.077147) (xy 43.960796 -257.087116)
			(xy 43.960796 -258.017264) (xy 43.960236 -258.046237) (xy 43.951126 -258.103463) (xy 43.933171 -258.158557)
			(xy 43.906815 -258.210163) (xy 43.872707 -258.257008) (xy 43.852592 -258.277868) (xy 43.331638 -258.798822)
			(xy 43.310758 -258.8189) (xy 43.263899 -258.852948) (xy 43.212291 -258.879247) (xy 43.157204 -258.89715)
			(xy 43.099995 -258.906216) (xy 43.071034 -258.906772) (xy 40.338248 -258.906772) (xy 40.309283 -258.906237)
			(xy 40.252065 -258.897182) (xy 40.196968 -258.879288) (xy 40.145349 -258.852995) (xy 40.098478 -258.818951)
			(xy 40.077644 -258.798822) (xy 39.698422 -258.419854) (xy 39.691057 -258.413032) (xy 39.672547 -258.405298)
			(xy 39.652487 -258.405252) (xy 39.64305 -258.408678) (xy 39.628572 -258.414774) (xy 39.611808 -258.43992)
			(xy 39.611808 -260.030468) (xy 39.612295 -260.04043) (xy 39.619884 -260.058853) (xy 39.62654 -260.066282)
			(xy 39.79291 -260.232652) (xy 39.800323 -260.239329) (xy 39.818758 -260.246899) (xy 39.828724 -260.247384)
			(xy 40.137588 -260.247384) (xy 40.14711 -260.246989) (xy 40.164836 -260.240032) (xy 40.178792 -260.227075)
			(xy 40.183308 -260.218682) (xy 40.229282 -260.122416) (xy 40.225726 -260.09346) (xy 40.216328 -260.08203)
			(xy 40.200349 -260.061559) (xy 40.173486 -260.017115) (xy 40.152893 -259.969442) (xy 40.138949 -259.919418)
			(xy 40.131912 -259.867966) (xy 40.131492 -259.842) (xy 40.131978 -259.814749) (xy 40.139734 -259.760801)
			(xy 40.155089 -259.708506) (xy 40.177731 -259.658929) (xy 40.207197 -259.613079) (xy 40.242888 -259.571888)
			(xy 40.284079 -259.536197) (xy 40.329929 -259.506731) (xy 40.379506 -259.484089) (xy 40.431801 -259.468734)
			(xy 40.485749 -259.460978) (xy 40.513 -259.460492) (xy 40.541917 -259.461026) (xy 40.599088 -259.469753)
			(xy 40.654288 -259.487007) (xy 40.706252 -259.512392) (xy 40.753791 -259.545329) (xy 40.795815 -259.585061)
			(xy 40.81399 -259.607558) (xy 40.821535 -259.616337) (xy 40.842306 -259.626501) (xy 40.853868 -259.627116)
			(xy 40.934132 -259.627116) (xy 40.945689 -259.626501) (xy 40.966449 -259.616321) (xy 40.97401 -259.607558)
			(xy 40.992197 -259.585068) (xy 41.034211 -259.545319) (xy 41.081744 -259.512367) (xy 41.133706 -259.486969)
			(xy 41.188907 -259.469707) (xy 41.246081 -259.460975) (xy 41.275 -259.460492) (xy 41.302251 -259.460978)
			(xy 41.356199 -259.468734) (xy 41.408494 -259.484089) (xy 41.458071 -259.506731) (xy 41.503921 -259.536197)
			(xy 41.545112 -259.571888) (xy 41.580803 -259.613079) (xy 41.610269 -259.658929) (xy 41.632911 -259.708506)
			(xy 41.636235 -259.719826) (xy 45.860714 -259.719826) (xy 45.864785 -259.664204) (xy 45.876911 -259.609767)
			(xy 45.896834 -259.557676) (xy 45.92413 -259.509041) (xy 45.958216 -259.464898) (xy 45.998365 -259.426189)
			(xy 46.043723 -259.393738) (xy 46.093323 -259.368237) (xy 46.146107 -259.35023) (xy 46.20095 -259.3401)
			(xy 46.256684 -259.338063) (xy 46.312121 -259.344163) (xy 46.366078 -259.358269) (xy 46.417407 -259.380081)
			(xy 46.465013 -259.409135) (xy 46.507881 -259.44481) (xy 46.545098 -259.486347) (xy 46.575871 -259.53286)
			(xy 46.599543 -259.583357) (xy 46.615611 -259.636764) (xy 46.623731 -259.69194) (xy 46.62424 -259.719826)
			(xy 46.623731 -259.747712) (xy 46.615611 -259.802888) (xy 46.599543 -259.856295) (xy 46.575871 -259.906792)
			(xy 46.545098 -259.953305) (xy 46.507881 -259.994842) (xy 46.465013 -260.030517) (xy 46.417407 -260.059571)
			(xy 46.366078 -260.081383) (xy 46.312121 -260.095489) (xy 46.256684 -260.101589) (xy 46.20095 -260.099552)
			(xy 46.146107 -260.089422) (xy 46.093323 -260.071415) (xy 46.043723 -260.045914) (xy 45.998365 -260.013463)
			(xy 45.958216 -259.974754) (xy 45.92413 -259.930611) (xy 45.896834 -259.881976) (xy 45.876911 -259.829885)
			(xy 45.864785 -259.775448) (xy 45.860714 -259.719826) (xy 41.636235 -259.719826) (xy 41.648266 -259.760801)
			(xy 41.656022 -259.814749) (xy 41.656508 -259.842) (xy 41.656022 -259.869587) (xy 41.648078 -259.924185)
			(xy 41.632357 -259.977072) (xy 41.609184 -260.027143) (xy 41.579045 -260.073357) (xy 41.542566 -260.11475)
			(xy 41.500507 -260.15046) (xy 41.453745 -260.179742) (xy 41.42867 -260.19125) (xy 41.416986 -260.19633)
			(xy 41.401746 -260.21538) (xy 41.398355 -260.232252) (xy 43.034944 -260.232252) (xy 43.034944 -260.177748)
			(xy 43.0427 -260.123798) (xy 43.058055 -260.071502) (xy 43.080696 -260.021922) (xy 43.110161 -259.976069)
			(xy 43.145852 -259.934876) (xy 43.187042 -259.899182) (xy 43.232892 -259.869712) (xy 43.28247 -259.847067)
			(xy 43.334765 -259.831707) (xy 43.388714 -259.823946) (xy 43.415966 -259.823458) (xy 43.44378 -259.823988)
			(xy 43.49882 -259.83205) (xy 43.552105 -259.848021) (xy 43.602505 -259.871564) (xy 43.64895 -259.902178)
			(xy 43.690455 -259.939214) (xy 43.72614 -259.981887) (xy 43.755248 -260.029291) (xy 43.77716 -260.08042)
			(xy 43.784774 -260.107176) (xy 43.788675 -260.120621) (xy 43.802885 -260.144736) (xy 43.823116 -260.164078)
			(xy 43.847845 -260.177191) (xy 43.875207 -260.183087) (xy 43.903141 -260.18132) (xy 43.929543 -260.172025)
			(xy 43.941238 -260.164326) (xy 43.96541 -260.148072) (xy 44.017673 -260.122358) (xy 44.073236 -260.104878)
			(xy 44.130808 -260.096038) (xy 44.159932 -260.095492) (xy 44.187182 -260.09598) (xy 44.241126 -260.10374)
			(xy 44.293417 -260.119098) (xy 44.34299 -260.141741) (xy 44.388837 -260.171208) (xy 44.430023 -260.2069)
			(xy 44.465711 -260.248089) (xy 44.495174 -260.293938) (xy 44.517813 -260.343513) (xy 44.533167 -260.395805)
			(xy 44.540922 -260.44975) (xy 44.540922 -260.50425) (xy 44.533167 -260.558195) (xy 44.517813 -260.610487)
			(xy 44.495174 -260.660062) (xy 44.465711 -260.705911) (xy 44.430023 -260.7471) (xy 44.388837 -260.782792)
			(xy 44.34299 -260.812259) (xy 44.293417 -260.834902) (xy 44.241126 -260.85026) (xy 44.187182 -260.85802)
			(xy 44.159932 -260.858508) (xy 44.132117 -260.858005) (xy 44.077075 -260.849942) (xy 44.023788 -260.833969)
			(xy 43.973386 -260.810424) (xy 43.92694 -260.779806) (xy 43.885435 -260.742766) (xy 43.849751 -260.700089)
			(xy 43.820645 -260.652681) (xy 43.798736 -260.601548) (xy 43.791124 -260.57479) (xy 43.787198 -260.561351)
			(xy 43.772999 -260.53723) (xy 43.752774 -260.51788) (xy 43.728048 -260.504763) (xy 43.700686 -260.498866)
			(xy 43.672752 -260.500635) (xy 43.646353 -260.509937) (xy 43.63466 -260.51764) (xy 43.610459 -260.533848)
			(xy 43.558206 -260.559574) (xy 43.502653 -260.577066) (xy 43.445087 -260.585921) (xy 43.415966 -260.586474)
			(xy 43.388714 -260.586054) (xy 43.334765 -260.578293) (xy 43.28247 -260.562933) (xy 43.232892 -260.540288)
			(xy 43.187042 -260.510818) (xy 43.145852 -260.475124) (xy 43.110161 -260.433931) (xy 43.080696 -260.388078)
			(xy 43.058055 -260.338498) (xy 43.0427 -260.286202) (xy 43.034944 -260.232252) (xy 41.398355 -260.232252)
			(xy 41.38041 -260.321552) (xy 41.387014 -260.34492) (xy 41.39565 -260.354064) (xy 41.415148 -260.375428)
			(xy 41.448122 -260.422947) (xy 41.473538 -260.474901) (xy 41.490815 -260.530099) (xy 41.499553 -260.587273)
			(xy 41.500044 -260.616192) (xy 41.499559 -260.643445) (xy 41.491803 -260.697395) (xy 41.476449 -260.749693)
			(xy 41.453809 -260.799273) (xy 41.424344 -260.845127) (xy 41.388653 -260.886321) (xy 41.347463 -260.922017)
			(xy 41.301612 -260.951488) (xy 41.252034 -260.974134) (xy 41.199738 -260.989494) (xy 41.145789 -260.997256)
			(xy 41.118536 -260.9977) (xy 41.095244 -260.997318) (xy 41.049015 -260.991584) (xy 41.026334 -260.98627)
			(xy 41.020238 -260.985) (xy 39.654988 -260.985) (xy 39.626014 -260.984444) (xy 39.568783 -260.975341)
			(xy 39.513684 -260.957392) (xy 39.462072 -260.931041) (xy 39.415221 -260.896936) (xy 39.394384 -260.876796)
			(xy 38.982396 -260.464808) (xy 38.962269 -260.443958) (xy 38.928164 -260.397109) (xy 38.901809 -260.345501)
			(xy 38.883854 -260.290405) (xy 38.87474 -260.233178) (xy 38.874192 -260.204204) (xy 38.874192 -257.402584)
			(xy 38.873715 -257.392618) (xy 38.866139 -257.374181) (xy 38.85946 -257.36677) (xy 38.508178 -257.015234)
			(xy 38.4881 -256.994354) (xy 38.454053 -256.947495) (xy 38.427754 -256.895887) (xy 38.409852 -256.8408)
			(xy 38.400787 -256.783591) (xy 38.400228 -256.75463) (xy 38.400228 -256.638298) (xy 38.399691 -256.62831)
			(xy 38.39198 -256.609876) (xy 38.385242 -256.602484) (xy 37.765736 -255.982978) (xy 37.75644 -255.974526)
			(xy 37.732446 -255.967187) (xy 37.720016 -255.969008) (xy 37.624512 -255.988058) (xy 37.604954 -256.00406)
			(xy 37.600128 -256.015998) (xy 37.588919 -256.04179) (xy 37.56003 -256.090038) (xy 37.524372 -256.133523)
			(xy 37.482716 -256.171301) (xy 37.435965 -256.202555) (xy 37.385133 -256.226607) (xy 37.331321 -256.242936)
			(xy 37.275694 -256.251189) (xy 37.247576 -256.25171) (xy 37.220326 -256.251223) (xy 37.166381 -256.243463)
			(xy 37.114089 -256.228106) (xy 37.064514 -256.205464) (xy 37.018667 -256.175997) (xy 36.977479 -256.140305)
			(xy 36.94179 -256.099116) (xy 36.912326 -256.053266) (xy 36.889686 -256.003691) (xy 36.874332 -255.951398)
			(xy 36.866576 -255.897452) (xy 36.866068 -255.870202) (xy 36.866545 -255.842763) (xy 36.874412 -255.78845)
			(xy 36.889983 -255.735827) (xy 36.912937 -255.685979) (xy 36.942799 -255.639936) (xy 36.978953 -255.598649)
			(xy 37.020653 -255.562972) (xy 37.067036 -255.533641) (xy 37.091874 -255.521968) (xy 37.103304 -255.516888)
			(xy 37.118544 -255.49733) (xy 37.138864 -255.390904) (xy 37.131752 -255.367282) (xy 37.123116 -255.358392)
			(xy 37.102904 -255.336882) (xy 37.068688 -255.28879) (xy 37.042288 -255.236001) (xy 37.024333 -255.179776)
			(xy 37.015251 -255.121457) (xy 37.014658 -255.091946) (xy 37.015075 -255.06714) (xy 37.021532 -255.017949)
			(xy 37.034294 -254.970006) (xy 37.04336 -254.946912) (xy 37.048186 -254.935228) (xy 37.045646 -254.910082)
			(xy 36.991544 -254.82931) (xy 36.984062 -254.819207) (xy 36.961935 -254.807343) (xy 36.94938 -254.806704)
			(xy 35.01898 -254.806704) (xy 35.006796 -254.807469) (xy 34.985181 -254.818742) (xy 34.977578 -254.828294)
			(xy 34.962174 -254.849244) (xy 34.926602 -254.887173) (xy 34.886209 -254.91992) (xy 34.841742 -254.946878)
			(xy 34.794026 -254.967547) (xy 34.743946 -254.981544) (xy 34.692428 -254.98861) (xy 34.666428 -254.989076)
			(xy 34.639175 -254.988615) (xy 34.585222 -254.980861) (xy 34.532923 -254.965507) (xy 34.483341 -254.942865)
			(xy 34.437487 -254.913398) (xy 34.396294 -254.877703) (xy 34.3606 -254.83651) (xy 34.331133 -254.790655)
			(xy 34.308492 -254.741073) (xy 34.293139 -254.688774) (xy 34.285385 -254.634821) (xy 34.28492 -254.607568)
			(xy 34.285413 -254.579504) (xy 34.293632 -254.523981) (xy 34.309902 -254.470263) (xy 34.333871 -254.419511)
			(xy 34.365022 -254.372821) (xy 34.402681 -254.331203) (xy 34.446035 -254.295555) (xy 34.469832 -254.28067)
			(xy 34.475166 -254.277368) (xy 34.575242 -254.177546) (xy 34.596122 -254.157468) (xy 34.642982 -254.123421)
			(xy 34.69459 -254.097121) (xy 34.749676 -254.079217) (xy 34.806885 -254.070149) (xy 34.835846 -254.069596)
			(xy 37.805106 -254.069596) (xy 37.834069 -254.070135) (xy 37.891281 -254.079199) (xy 37.946371 -254.097102)
			(xy 37.997981 -254.123403) (xy 38.044841 -254.157455) (xy 38.06571 -254.177546) (xy 39.412926 -255.524508)
			(xy 39.42054 -255.531492) (xy 39.439681 -255.539217) (xy 39.45001 -255.539494) (xy 39.534084 -255.537462)
			(xy 39.552626 -255.528826) (xy 39.559738 -255.521206) (xy 39.577893 -255.501924) (xy 39.61861 -255.468057)
			(xy 39.663621 -255.440151) (xy 39.712061 -255.418742) (xy 39.762998 -255.404243) (xy 39.815452 -255.396932)
			(xy 39.841932 -255.396492) (xy 39.869182 -255.39698) (xy 39.923126 -255.40474) (xy 39.975417 -255.420098)
			(xy 40.02499 -255.442741) (xy 40.070837 -255.472208) (xy 40.112023 -255.5079) (xy 40.147711 -255.549089)
			(xy 40.177174 -255.594938) (xy 40.199813 -255.644513) (xy 40.215167 -255.696805) (xy 40.222922 -255.75075)
			(xy 40.222922 -255.80525) (xy 40.215167 -255.859195) (xy 40.199813 -255.911487) (xy 40.177174 -255.961062)
			(xy 40.147711 -256.006911) (xy 40.112023 -256.0481) (xy 40.070837 -256.083792) (xy 40.02499 -256.113259)
			(xy 39.975417 -256.135902) (xy 39.923126 -256.15126) (xy 39.869182 -256.15902) (xy 39.841932 -256.159508)
			(xy 39.83355 -256.159508) (xy 39.823136 -256.159254) (xy 39.80434 -256.16662) (xy 39.745158 -256.224786)
			(xy 39.738149 -256.232187) (xy 39.730171 -256.250926) (xy 39.729664 -256.261108) (xy 39.729664 -256.298954)
			(xy 39.730192 -256.308946) (xy 39.73789 -256.327394) (xy 39.74465 -256.334768) (xy 40.11295 -256.703322)
			(xy 40.133023 -256.724204) (xy 40.167061 -256.771065) (xy 40.19335 -256.822674) (xy 40.211242 -256.87776)
			(xy 40.220298 -256.934967) (xy 40.2209 -256.963926) (xy 40.2209 -257.87858) (xy 40.221434 -257.888569)
			(xy 40.229142 -257.907006) (xy 40.235886 -257.914394) (xy 40.47617 -258.154678) (xy 40.483518 -258.16148)
			(xy 40.501981 -258.16919) (xy 40.511984 -258.169664) (xy 42.897298 -258.169664) (xy 42.907285 -258.169126)
			(xy 42.925714 -258.161409) (xy 42.933112 -258.154678) (xy 43.208448 -257.879342) (xy 43.215134 -257.871932)
			(xy 43.222723 -257.853497) (xy 43.22318 -257.843528) (xy 43.22318 -257.773678) (xy 43.222712 -257.762265)
			(xy 43.212915 -257.741653) (xy 43.204384 -257.734054) (xy 43.133264 -257.677158) (xy 43.111166 -257.671824)
			(xy 43.099736 -257.674364) (xy 43.079301 -257.678632) (xy 43.037806 -257.683211) (xy 43.016932 -257.683508)
			(xy 42.989678 -257.683047) (xy 42.935723 -257.675294) (xy 42.883422 -257.65994) (xy 42.833837 -257.6373)
			(xy 42.78798 -257.607833) (xy 42.746784 -257.572139) (xy 42.711087 -257.530945) (xy 42.681616 -257.485091)
			(xy 42.658971 -257.435508) (xy 42.643613 -257.383208) (xy 42.635855 -257.329254) (xy 42.635424 -257.302)
			(xy 42.635846 -257.275629) (xy 42.643077 -257.223385) (xy 42.657457 -257.172642) (xy 42.667682 -257.14833)
			(xy 42.673016 -257.136646) (xy 42.67073 -257.111246) (xy 42.617136 -257.02895) (xy 42.609666 -257.018683)
			(xy 42.587396 -257.00656) (xy 42.574718 -257.005836) (xy 42.380662 -257.005836) (xy 42.3517 -257.005295)
			(xy 42.29449 -256.996227) (xy 42.239402 -256.978322) (xy 42.187794 -256.952019) (xy 42.140936 -256.917967)
			(xy 42.120058 -256.897886) (xy 41.635934 -256.413762) (xy 41.615857 -256.392882) (xy 41.581809 -256.346022)
			(xy 41.55551 -256.294414) (xy 41.537606 -256.239328) (xy 41.528538 -256.182119) (xy 41.527984 -256.153158)
			(xy 41.527984 -256.003298) (xy 41.52646 -255.997202) (xy 41.52114 -255.974523) (xy 41.515415 -255.928292)
			(xy 41.51503 -255.905) (xy 41.515479 -255.878667) (xy 41.522734 -255.826503) (xy 41.537092 -255.775832)
			(xy 41.558281 -255.727616) (xy 41.585898 -255.682771) (xy 41.619418 -255.64215) (xy 41.658206 -255.606523)
			(xy 41.701523 -255.576567) (xy 41.748548 -255.552852) (xy 41.798386 -255.535827) (xy 41.824148 -255.53035)
			(xy 41.835324 -255.528318) (xy 41.853612 -255.51511) (xy 41.902126 -255.426718) (xy 41.90365 -255.404366)
			(xy 41.899586 -255.393698) (xy 41.891296 -255.371527) (xy 41.879645 -255.32565) (xy 41.873774 -255.278681)
			(xy 41.873424 -255.255014) (xy 41.873938 -255.225712) (xy 41.882866 -255.167793) (xy 41.891204 -255.139698)
			(xy 41.895268 -255.127252) (xy 41.890442 -255.102106) (xy 41.81983 -255.016) (xy 41.796462 -255.006348)
			(xy 41.783254 -255.007872) (xy 41.772873 -255.008941) (xy 41.752034 -255.010087) (xy 41.741598 -255.010158)
			(xy 41.713532 -255.009667) (xy 41.658004 -255.001453) (xy 41.604281 -254.985188) (xy 41.553522 -254.961224)
			(xy 41.506823 -254.930079) (xy 41.465195 -254.892424) (xy 41.429536 -254.849074) (xy 41.4147 -254.825246)
			(xy 41.411398 -254.819912) (xy 39.998396 -253.406656) (xy 39.978041 -253.385606) (xy 39.943588 -253.338263)
			(xy 39.929816 -253.312422) (xy 39.924228 -253.301246) (xy 39.90467 -253.286768) (xy 39.79799 -253.270766)
			(xy 39.77513 -253.278386) (xy 39.76624 -253.28753) (xy 39.748208 -253.305506) (xy 39.708203 -253.337005)
			(xy 39.664364 -253.362901) (xy 39.617469 -253.382735) (xy 39.568352 -253.396153) (xy 39.517886 -253.402918)
			(xy 39.492428 -253.403354) (xy 39.465171 -253.402893) (xy 39.41121 -253.395138) (xy 39.358902 -253.379783)
			(xy 39.309313 -253.357139) (xy 39.263451 -253.327668) (xy 39.22225 -253.29197) (xy 39.186548 -253.250772)
			(xy 39.157074 -253.204912) (xy 39.134427 -253.155324) (xy 39.119068 -253.103017) (xy 39.111309 -253.049057)
			(xy 39.111309 -252.994543) (xy 39.119068 -252.940583) (xy 39.134427 -252.888276) (xy 39.157074 -252.838688)
			(xy 39.186548 -252.792828) (xy 39.22225 -252.75163) (xy 39.263451 -252.715932) (xy 39.309313 -252.686461)
			(xy 39.358902 -252.663817) (xy 39.41121 -252.648462) (xy 39.465171 -252.640707) (xy 39.492428 -252.640338)
			(xy 39.517624 -252.640763) (xy 39.567573 -252.64743) (xy 39.616212 -252.660606) (xy 39.662696 -252.680062)
			(xy 39.70622 -252.70546) (xy 39.726362 -252.720602) (xy 39.738046 -252.729492) (xy 39.766748 -252.73254)
			(xy 39.861744 -252.685804) (xy 39.870015 -252.681236) (xy 39.882789 -252.667339) (xy 39.889703 -252.649773)
			(xy 39.890192 -252.640338) (xy 39.890192 -252.13818) (xy 39.889714 -252.128214) (xy 39.882137 -252.109779)
			(xy 39.87546 -252.102366) (xy 39.319962 -251.546614) (xy 39.299886 -251.525733) (xy 39.265843 -251.478873)
			(xy 39.239548 -251.427265) (xy 39.221649 -251.372178) (xy 39.212588 -251.314971) (xy 39.212012 -251.28601)
			(xy 39.212012 -248.941336) (xy 39.211516 -248.931903) (xy 39.204599 -248.914344) (xy 39.191826 -248.90045)
			(xy 39.183564 -248.89587) (xy 39.089076 -248.849134) (xy 39.06012 -248.851928) (xy 39.04869 -248.860818)
			(xy 39.023673 -248.87914) (xy 38.968944 -248.908286) (xy 38.910225 -248.928206) (xy 38.849059 -248.938378)
			(xy 38.818058 -248.93905) (xy 38.805866 -248.93905) (xy 38.784784 -248.949718) (xy 38.721538 -249.033792)
			(xy 38.717474 -249.05716) (xy 38.720776 -249.06859) (xy 38.72767 -249.094395) (xy 38.735067 -249.147293)
			(xy 38.735508 -249.174) (xy 38.735022 -249.201251) (xy 38.727266 -249.255199) (xy 38.711911 -249.307494)
			(xy 38.689269 -249.357071) (xy 38.659803 -249.402921) (xy 38.624112 -249.444112) (xy 38.582921 -249.479803)
			(xy 38.537071 -249.509269) (xy 38.487494 -249.531911) (xy 38.435199 -249.547266) (xy 38.381251 -249.555022)
			(xy 38.326749 -249.555022) (xy 38.272801 -249.547266) (xy 38.220506 -249.531911) (xy 38.170929 -249.509269)
			(xy 38.125079 -249.479803) (xy 38.083888 -249.444112) (xy 38.048197 -249.402921) (xy 38.018731 -249.357071)
			(xy 37.996089 -249.307494) (xy 37.980734 -249.255199) (xy 37.972978 -249.201251) (xy 37.972492 -249.174)
			(xy 37.972974 -249.146795) (xy 37.980705 -249.092937) (xy 37.996009 -249.040723) (xy 38.018576 -248.991213)
			(xy 38.047948 -248.945412) (xy 38.083529 -248.904248) (xy 38.124598 -248.868557) (xy 38.170321 -248.839064)
			(xy 38.21977 -248.816365) (xy 38.271943 -248.800922) (xy 38.32578 -248.793048) (xy 38.352984 -248.792492)
			(xy 38.365176 -248.792492) (xy 38.386258 -248.781824) (xy 38.449504 -248.69775) (xy 38.453568 -248.674382)
			(xy 38.450266 -248.662952) (xy 38.443377 -248.637146) (xy 38.435989 -248.584248) (xy 38.435534 -248.557542)
			(xy 38.43608 -248.52843) (xy 38.444919 -248.47088) (xy 38.4624 -248.415342) (xy 38.488115 -248.363104)
			(xy 38.521467 -248.315379) (xy 38.561684 -248.273275) (xy 38.60783 -248.23777) (xy 38.658835 -248.209688)
			(xy 38.685978 -248.199148) (xy 38.69817 -248.19483) (xy 38.715188 -248.175272) (xy 38.736524 -248.079006)
			(xy 38.738033 -248.070601) (xy 38.73603 -248.053652) (xy 38.728607 -248.038284) (xy 38.722808 -248.032016)
			(xy 38.716204 -248.025412) (xy 38.708795 -248.018726) (xy 38.690359 -248.01114) (xy 38.68039 -248.01068)
			(xy 38.11143 -248.01068) (xy 38.105334 -248.01195) (xy 38.082655 -248.017271) (xy 38.036424 -248.023001)
			(xy 38.013132 -248.02338) (xy 37.98588 -248.022919) (xy 37.931929 -248.015166) (xy 37.879631 -247.999814)
			(xy 37.830051 -247.977175) (xy 37.784197 -247.94771) (xy 37.743004 -247.912019) (xy 37.707309 -247.870829)
			(xy 37.67784 -247.824977) (xy 37.655197 -247.775399) (xy 37.639841 -247.723102) (xy 37.632083 -247.669152)
			(xy 37.632083 -247.614648) (xy 37.639841 -247.560698) (xy 37.655197 -247.508401) (xy 37.67784 -247.458823)
			(xy 37.707309 -247.412971) (xy 37.743004 -247.371781) (xy 37.784197 -247.33609) (xy 37.830051 -247.306625)
			(xy 37.879631 -247.283986) (xy 37.931929 -247.268634) (xy 37.98588 -247.260881) (xy 38.013132 -247.260364)
			(xy 38.036424 -247.260744) (xy 38.082655 -247.266474) (xy 38.105334 -247.271794) (xy 38.11143 -247.273064)
			(xy 38.854126 -247.273064) (xy 38.8831 -247.273621) (xy 38.94033 -247.282725) (xy 38.99543 -247.300674)
			(xy 39.047041 -247.327025) (xy 39.093893 -247.361128) (xy 39.11473 -247.381268) (xy 39.84117 -248.107708)
			(xy 39.861243 -248.12859) (xy 39.895281 -248.175452) (xy 39.92157 -248.22706) (xy 39.939464 -248.282146)
			(xy 39.948521 -248.339352) (xy 39.94912 -248.368312) (xy 39.94912 -248.403364) (xy 40.44391 -248.403364)
			(xy 40.447981 -248.347742) (xy 40.460107 -248.293305) (xy 40.48003 -248.241214) (xy 40.507326 -248.192579)
			(xy 40.541412 -248.148436) (xy 40.581561 -248.109727) (xy 40.626919 -248.077276) (xy 40.676519 -248.051775)
			(xy 40.729303 -248.033768) (xy 40.784146 -248.023638) (xy 40.83988 -248.021601) (xy 40.895317 -248.027701)
			(xy 40.949274 -248.041807) (xy 40.987978 -248.058254) (xy 41.467455 -248.058254) (xy 41.467455 -248.003746)
			(xy 41.475213 -247.949792) (xy 41.490571 -247.897492) (xy 41.513216 -247.847909) (xy 41.542687 -247.802055)
			(xy 41.578384 -247.760861) (xy 41.61958 -247.725167) (xy 41.665437 -247.6957) (xy 41.715022 -247.67306)
			(xy 41.767323 -247.657706) (xy 41.821278 -247.649953) (xy 41.848532 -247.649492) (xy 41.877449 -247.650024)
			(xy 41.934621 -247.658746) (xy 41.989821 -247.675998) (xy 42.041784 -247.701387) (xy 42.089317 -247.73433)
			(xy 42.131333 -247.774072) (xy 42.149522 -247.796558) (xy 42.157069 -247.805335) (xy 42.177839 -247.815508)
			(xy 42.1894 -247.816116) (xy 42.269664 -247.816116) (xy 42.281228 -247.815519) (xy 42.301999 -247.805343)
			(xy 42.309542 -247.796558) (xy 42.327699 -247.774046) (xy 42.369727 -247.734314) (xy 42.417269 -247.70138)
			(xy 42.469237 -247.675997) (xy 42.52444 -247.658746) (xy 42.581614 -247.650024) (xy 42.610532 -247.649492)
			(xy 42.637782 -247.64998) (xy 42.691726 -247.65774) (xy 42.744017 -247.673098) (xy 42.79359 -247.695741)
			(xy 42.839437 -247.725208) (xy 42.880623 -247.7609) (xy 42.916311 -247.802089) (xy 42.945774 -247.847938)
			(xy 42.968413 -247.897513) (xy 42.983767 -247.949805) (xy 42.991522 -248.00375) (xy 42.991522 -248.05825)
			(xy 42.983767 -248.112195) (xy 42.968413 -248.164487) (xy 42.945774 -248.214062) (xy 42.916311 -248.259911)
			(xy 42.880623 -248.3011) (xy 42.839437 -248.336792) (xy 42.79359 -248.366259) (xy 42.744017 -248.388902)
			(xy 42.691726 -248.40426) (xy 42.637782 -248.41202) (xy 42.610532 -248.412508) (xy 42.581614 -248.412001)
			(xy 42.524441 -248.403275) (xy 42.46924 -248.386017) (xy 42.417278 -248.360623) (xy 42.369745 -248.327676)
			(xy 42.32773 -248.28793) (xy 42.309542 -248.265442) (xy 42.301968 -248.256694) (xy 42.281218 -248.246505)
			(xy 42.269664 -248.245884) (xy 42.1894 -248.245884) (xy 42.177833 -248.24646) (xy 42.157062 -248.256651)
			(xy 42.149522 -248.265442) (xy 42.131329 -248.287924) (xy 42.089309 -248.327657) (xy 42.041774 -248.360595)
			(xy 41.989813 -248.385983) (xy 41.934616 -248.403241) (xy 41.877448 -248.411972) (xy 41.848532 -248.412508)
			(xy 41.821278 -248.412047) (xy 41.767323 -248.404294) (xy 41.715022 -248.38894) (xy 41.665437 -248.3663)
			(xy 41.61958 -248.336833) (xy 41.578384 -248.301139) (xy 41.542687 -248.259945) (xy 41.513216 -248.214091)
			(xy 41.490571 -248.164508) (xy 41.475213 -248.112208) (xy 41.467455 -248.058254) (xy 40.987978 -248.058254)
			(xy 41.000603 -248.063619) (xy 41.048209 -248.092673) (xy 41.091077 -248.128348) (xy 41.128294 -248.169885)
			(xy 41.159067 -248.216398) (xy 41.182739 -248.266895) (xy 41.198807 -248.320302) (xy 41.206927 -248.375478)
			(xy 41.207436 -248.403364) (xy 41.206927 -248.43125) (xy 41.198807 -248.486426) (xy 41.182739 -248.539833)
			(xy 41.159067 -248.59033) (xy 41.128294 -248.636843) (xy 41.091077 -248.67838) (xy 41.048209 -248.714055)
			(xy 41.000603 -248.743109) (xy 40.949274 -248.764921) (xy 40.895317 -248.779027) (xy 40.83988 -248.785127)
			(xy 40.784146 -248.78309) (xy 40.729303 -248.77296) (xy 40.676519 -248.754953) (xy 40.626919 -248.729452)
			(xy 40.581561 -248.697001) (xy 40.541412 -248.658292) (xy 40.507326 -248.614149) (xy 40.48003 -248.565514)
			(xy 40.460107 -248.513423) (xy 40.447981 -248.458986) (xy 40.44391 -248.403364) (xy 39.94912 -248.403364)
			(xy 39.94912 -251.112274) (xy 39.949653 -251.122263) (xy 39.957362 -251.1407) (xy 39.964106 -251.148088)
			(xy 40.519604 -251.70384) (xy 40.539728 -251.724691) (xy 40.573827 -251.771541) (xy 40.600175 -251.82315)
			(xy 40.618124 -251.878246) (xy 40.62723 -251.935472) (xy 40.627808 -251.964444) (xy 40.627808 -252.972316)
			(xy 40.628285 -252.982282) (xy 40.635861 -253.000719) (xy 40.64254 -253.00813) (xy 41.263824 -253.629414)
			(xy 41.270548 -253.635554) (xy 41.287126 -253.643056) (xy 41.305279 -253.644314) (xy 41.314116 -253.642114)
			(xy 41.413176 -253.61265) (xy 41.432226 -253.592076) (xy 41.43502 -253.57836) (xy 41.44149 -253.550171)
			(xy 41.461792 -253.496016) (xy 41.490037 -253.445547) (xy 41.525578 -253.39992) (xy 41.567599 -253.360182)
			(xy 41.615138 -253.327244) (xy 41.667104 -253.301859) (xy 41.722308 -253.284611) (xy 41.779482 -253.275895)
			(xy 41.8084 -253.275338) (xy 41.835652 -253.275801) (xy 41.8896 -253.283559) (xy 41.941895 -253.298915)
			(xy 41.991473 -253.321558) (xy 42.037322 -253.351027) (xy 42.078511 -253.386721) (xy 42.114201 -253.427914)
			(xy 42.143664 -253.473768) (xy 42.166301 -253.523348) (xy 42.181651 -253.575645) (xy 42.189402 -253.629594)
			(xy 42.189908 -253.656846) (xy 42.18937 -253.685762) (xy 42.180637 -253.742932) (xy 42.163377 -253.79813)
			(xy 42.137985 -253.85009) (xy 42.105044 -253.897625) (xy 42.065307 -253.939644) (xy 42.019685 -253.975187)
			(xy 41.969222 -254.003438) (xy 41.915073 -254.023751) (xy 41.886886 -254.030226) (xy 41.87317 -254.03302)
			(xy 41.852596 -254.05207) (xy 41.823132 -254.15113) (xy 41.820895 -254.159963) (xy 41.822142 -254.178128)
			(xy 41.829677 -254.194703) (xy 41.835832 -254.201422) (xy 41.93286 -254.29845) (xy 41.938194 -254.301752)
			(xy 41.961987 -254.316641) (xy 42.005329 -254.3523) (xy 42.04298 -254.393923) (xy 42.07413 -254.440611)
			(xy 42.098105 -254.491359) (xy 42.11439 -254.54507) (xy 42.122632 -254.600587) (xy 42.123106 -254.62865)
			(xy 42.122595 -254.657952) (xy 42.113672 -254.715873) (xy 42.105326 -254.743966) (xy 42.101262 -254.756412)
			(xy 42.106088 -254.781558) (xy 42.1767 -254.867664) (xy 42.200068 -254.877316) (xy 42.213276 -254.875792)
			(xy 42.223657 -254.874724) (xy 42.244497 -254.873579) (xy 42.254932 -254.873506) (xy 42.282181 -254.873994)
			(xy 42.336125 -254.881755) (xy 42.388415 -254.897113) (xy 42.437987 -254.919756) (xy 42.483832 -254.949223)
			(xy 42.525018 -254.984915) (xy 42.560704 -255.026104) (xy 42.590166 -255.071953) (xy 42.612803 -255.121528)
			(xy 42.628155 -255.17382) (xy 42.635909 -255.227765) (xy 42.63644 -255.255014) (xy 42.636114 -255.278174)
			(xy 42.630541 -255.324159) (xy 42.619456 -255.369133) (xy 42.611548 -255.390904) (xy 42.60723 -255.401826)
			(xy 42.609262 -255.424686) (xy 42.661078 -255.513078) (xy 42.680128 -255.525778) (xy 42.691558 -255.527556)
			(xy 42.703762 -255.529468) (xy 42.727912 -255.534676) (xy 42.739818 -255.53797) (xy 42.751502 -255.541272)
			(xy 42.77487 -255.536954) (xy 42.849038 -255.48082) (xy 42.858059 -255.473174) (xy 42.868506 -255.451991)
			(xy 42.869104 -255.44018) (xy 42.869104 -253.053088) (xy 42.86966 -253.024114) (xy 42.878763 -252.966884)
			(xy 42.896712 -252.911784) (xy 42.923063 -252.860172) (xy 42.957168 -252.813322) (xy 42.977308 -252.792484)
			(xy 43.27906 -252.490478) (xy 43.285803 -252.483108) (xy 43.293394 -252.464646) (xy 43.293792 -252.454664)
			(xy 43.293792 -245.117366) (xy 43.293453 -245.10815) (xy 43.287009 -245.090887) (xy 43.274834 -245.077055)
			(xy 43.266868 -245.072408) (xy 43.17492 -245.02364) (xy 43.147234 -245.025164) (xy 43.135296 -245.033292)
			(xy 43.098417 -245.057648) (xy 43.02071 -245.099763) (xy 42.93921 -245.133965) (xy 42.854721 -245.159917)
			(xy 42.768074 -245.177362) (xy 42.680125 -245.18613) (xy 42.635932 -245.186708) (xy 42.589536 -245.186125)
			(xy 42.497244 -245.176495) (xy 42.406458 -245.157305) (xy 42.318164 -245.128763) (xy 42.275506 -245.110508)
			(xy 42.265566 -245.106688) (xy 42.244298 -245.106688) (xy 42.234358 -245.110508) (xy 42.191693 -245.128743)
			(xy 42.103398 -245.157274) (xy 42.012615 -245.176463) (xy 41.920327 -245.186101) (xy 41.873932 -245.186708)
			(xy 41.831582 -245.186221) (xy 41.747265 -245.178173) (xy 41.664094 -245.162146) (xy 41.582824 -245.138285)
			(xy 41.50419 -245.106808) (xy 41.428904 -245.067998) (xy 41.357649 -245.022207) (xy 41.291069 -244.96985)
			(xy 41.229767 -244.911401) (xy 41.174299 -244.847389) (xy 41.125167 -244.778395) (xy 41.082816 -244.705043)
			(xy 41.047629 -244.627997) (xy 41.019926 -244.547955) (xy 40.999957 -244.465643) (xy 40.987902 -244.381804)
			(xy 40.983872 -244.2972) (xy 40.987902 -244.212596) (xy 40.999957 -244.128757) (xy 41.019926 -244.046445)
			(xy 41.047629 -243.966403) (xy 41.082816 -243.889357) (xy 41.125167 -243.816005) (xy 41.174299 -243.747011)
			(xy 41.229767 -243.682999) (xy 41.291069 -243.62455) (xy 41.357649 -243.572193) (xy 41.428904 -243.526402)
			(xy 41.50419 -243.487592) (xy 41.582824 -243.456115) (xy 41.664094 -243.432254) (xy 41.747265 -243.416227)
			(xy 41.831582 -243.408179) (xy 41.873932 -243.407692) (xy 41.920328 -243.408279) (xy 42.012617 -243.417915)
			(xy 42.103401 -243.437111) (xy 42.191691 -243.465658) (xy 42.234358 -243.483892) (xy 42.244298 -243.487712)
			(xy 42.265566 -243.487712) (xy 42.275506 -243.483892) (xy 42.318171 -243.465656) (xy 42.406465 -243.437121)
			(xy 42.497249 -243.417928) (xy 42.589537 -243.408286) (xy 42.635932 -243.407692) (xy 42.655261 -243.407778)
			(xy 42.693883 -243.409429) (xy 42.713148 -243.410994) (xy 42.72915 -243.412518) (xy 42.756582 -243.396516)
			(xy 42.803826 -243.295424) (xy 42.80774 -243.285789) (xy 42.808316 -243.265021) (xy 42.800671 -243.245703)
			(xy 42.793666 -243.23802) (xy 35.104832 -235.549186) (xy 35.097434 -235.542341) (xy 35.078835 -235.534618)
			(xy 35.068764 -235.5342) (xy 34.82594 -235.5342) (xy 34.815913 -235.534613) (xy 34.797383 -235.542275)
			(xy 34.783198 -235.556449) (xy 34.77552 -235.574974) (xy 34.77514 -235.585) (xy 34.77514 -241.7953)
			(xy 34.774709 -241.819422) (xy 34.76835 -241.867246) (xy 34.755817 -241.913834) (xy 34.746946 -241.93627)
			(xy 33.762263 -244.31371) (xy 34.233104 -244.31371) (xy 34.233523 -244.275421) (xy 34.240149 -244.199131)
			(xy 34.253301 -244.123691) (xy 34.272882 -244.049659) (xy 34.285428 -244.013482) (xy 34.288064 -244.005043)
			(xy 34.288067 -243.987376) (xy 34.285428 -243.978938) (xy 34.272875 -243.942762) (xy 34.253277 -243.868733)
			(xy 34.240125 -243.793292) (xy 34.233515 -243.716999) (xy 34.233104 -243.67871) (xy 34.233562 -243.637607)
			(xy 34.241146 -243.555751) (xy 34.256251 -243.474943) (xy 34.278747 -243.395875) (xy 34.308443 -243.319219)
			(xy 34.345086 -243.245631) (xy 34.388362 -243.175737) (xy 34.437902 -243.110135) (xy 34.493285 -243.049383)
			(xy 34.554036 -242.994001) (xy 34.619639 -242.944461) (xy 34.689532 -242.901185) (xy 34.763121 -242.864542)
			(xy 34.839777 -242.834847) (xy 34.918845 -242.81235) (xy 34.999653 -242.797246) (xy 35.081509 -242.789662)
			(xy 35.122612 -242.789202) (xy 35.161544 -242.789625) (xy 35.239108 -242.796464) (xy 35.315776 -242.810064)
			(xy 35.390961 -242.830318) (xy 35.427666 -242.843304) (xy 35.436215 -242.846068) (xy 35.454169 -242.846068)
			(xy 35.462718 -242.843304) (xy 35.499432 -242.830345) (xy 35.574616 -242.810101) (xy 35.651281 -242.796499)
			(xy 35.728841 -242.789645) (xy 35.767772 -242.789202) (xy 35.806704 -242.789637) (xy 35.884268 -242.796473)
			(xy 35.960936 -242.810069) (xy 36.03612 -242.83032) (xy 36.072826 -242.843304) (xy 36.081375 -242.846068)
			(xy 36.099329 -242.846068) (xy 36.107878 -242.843304) (xy 36.144586 -242.830328) (xy 36.219772 -242.810088)
			(xy 36.296439 -242.796491) (xy 36.374001 -242.789642) (xy 36.412932 -242.789202) (xy 36.454035 -242.789636)
			(xy 36.535891 -242.797224) (xy 36.616697 -242.812332) (xy 36.695765 -242.834832) (xy 36.77242 -242.86453)
			(xy 36.846007 -242.901175) (xy 36.915899 -242.944453) (xy 36.9815 -242.993995) (xy 37.04225 -243.049379)
			(xy 37.097631 -243.110132) (xy 37.147171 -243.175735) (xy 37.190445 -243.24563) (xy 37.227087 -243.319219)
			(xy 37.256782 -243.395875) (xy 37.279278 -243.474943) (xy 37.294382 -243.555751) (xy 37.301966 -243.637607)
			(xy 37.30244 -243.67871) (xy 37.301995 -243.716998) (xy 37.295376 -243.793288) (xy 37.282232 -243.868727)
			(xy 37.262658 -243.94276) (xy 37.250116 -243.978938) (xy 37.247469 -243.987375) (xy 37.247472 -244.005044)
			(xy 37.250116 -244.013482) (xy 37.262677 -244.049655) (xy 37.282272 -244.123685) (xy 37.295422 -244.199127)
			(xy 37.30203 -244.27542) (xy 37.30244 -244.31371) (xy 37.301943 -244.354812) (xy 37.294357 -244.436664)
			(xy 37.279252 -244.517468) (xy 37.256756 -244.596533) (xy 37.227061 -244.673186) (xy 37.19042 -244.746771)
			(xy 37.147145 -244.816662) (xy 37.097607 -244.882263) (xy 37.042228 -244.943012) (xy 36.98148 -244.998393)
			(xy 36.915881 -245.047933) (xy 36.845991 -245.091209) (xy 36.801115 -245.113556) (xy 37.48532 -245.113556)
			(xy 37.485752 -245.075268) (xy 37.492374 -244.998978) (xy 37.505522 -244.923538) (xy 37.525099 -244.849506)
			(xy 37.537644 -244.813328) (xy 37.540306 -244.804895) (xy 37.540292 -244.787222) (xy 37.537644 -244.778784)
			(xy 37.525076 -244.742613) (xy 37.505483 -244.668583) (xy 37.492334 -244.59314) (xy 37.485729 -244.516846)
			(xy 37.48532 -244.478556) (xy 37.485725 -244.437452) (xy 37.493314 -244.355595) (xy 37.508423 -244.274787)
			(xy 37.530924 -244.195718) (xy 37.560625 -244.119063) (xy 37.597271 -244.045475) (xy 37.640551 -243.975582)
			(xy 37.690096 -243.909981) (xy 37.745481 -243.84923) (xy 37.806236 -243.79385) (xy 37.871841 -243.744311)
			(xy 37.941738 -243.701036) (xy 38.015329 -243.664396) (xy 38.091987 -243.634701) (xy 38.171057 -243.612207)
			(xy 38.251866 -243.597104) (xy 38.333724 -243.589521) (xy 38.374828 -243.589048) (xy 38.41376 -243.589463)
			(xy 38.491325 -243.596304) (xy 38.567993 -243.609906) (xy 38.643177 -243.630163) (xy 38.679882 -243.64315)
			(xy 38.688431 -243.645914) (xy 38.706385 -243.645914) (xy 38.714934 -243.64315) (xy 38.751645 -243.630184)
			(xy 38.826831 -243.609942) (xy 38.903496 -243.596343) (xy 38.981057 -243.58949) (xy 39.019988 -243.589048)
			(xy 39.05892 -243.589475) (xy 39.136484 -243.596313) (xy 39.213152 -243.609911) (xy 39.288337 -243.630165)
			(xy 39.325042 -243.64315) (xy 39.333591 -243.645914) (xy 39.351545 -243.645914) (xy 39.360094 -243.64315)
			(xy 39.3968 -243.630167) (xy 39.471987 -243.60993) (xy 39.548655 -243.596335) (xy 39.626216 -243.589487)
			(xy 39.665148 -243.589048) (xy 39.70625 -243.589521) (xy 39.788103 -243.59711) (xy 39.868907 -243.612218)
			(xy 39.947972 -243.634717) (xy 40.024624 -243.664415) (xy 40.098209 -243.701058) (xy 40.1681 -243.744334)
			(xy 40.233699 -243.793874) (xy 40.294448 -243.849254) (xy 40.349829 -243.910004) (xy 40.399368 -243.975604)
			(xy 40.442644 -244.045494) (xy 40.479287 -244.11908) (xy 40.508984 -244.195732) (xy 40.531483 -244.274797)
			(xy 40.546591 -244.355601) (xy 40.554179 -244.437454) (xy 40.554656 -244.478556) (xy 40.554229 -244.516844)
			(xy 40.547606 -244.593135) (xy 40.534456 -244.668575) (xy 40.514877 -244.742607) (xy 40.502332 -244.778784)
			(xy 40.499711 -244.787227) (xy 40.499697 -244.80489) (xy 40.502332 -244.813328) (xy 40.514906 -244.849497)
			(xy 40.534498 -244.923528) (xy 40.547644 -244.998971) (xy 40.554248 -245.075266) (xy 40.554656 -245.113556)
			(xy 40.554091 -245.154656) (xy 40.546511 -245.236507) (xy 40.531411 -245.317309) (xy 40.508919 -245.396372)
			(xy 40.479229 -245.473024) (xy 40.442593 -245.546609) (xy 40.399323 -245.616499) (xy 40.34979 -245.682099)
			(xy 40.294414 -245.742849) (xy 40.23367 -245.798231) (xy 40.168075 -245.847771) (xy 40.098189 -245.891048)
			(xy 40.024608 -245.927692) (xy 39.94796 -245.95739) (xy 39.868898 -245.97989) (xy 39.788098 -245.994998)
			(xy 39.706248 -246.002587) (xy 39.665148 -246.003064) (xy 39.625578 -246.00265) (xy 39.54675 -245.995641)
			(xy 39.468856 -245.981657) (xy 39.392513 -245.960808) (xy 39.355268 -245.947438) (xy 39.346601 -245.944598)
			(xy 39.328375 -245.944598) (xy 39.319708 -245.947438) (xy 39.282465 -245.960813) (xy 39.206121 -245.981658)
			(xy 39.128226 -245.995639) (xy 39.049398 -246.002645) (xy 39.009828 -246.003064) (xy 38.97154 -246.002641)
			(xy 38.895249 -245.996017) (xy 38.819809 -245.982866) (xy 38.745777 -245.963286) (xy 38.7096 -245.95074)
			(xy 38.701162 -245.948098) (xy 38.683494 -245.948098) (xy 38.675056 -245.95074) (xy 38.638889 -245.963319)
			(xy 38.564857 -245.982909) (xy 38.489413 -245.996054) (xy 38.413118 -246.002656) (xy 38.374828 -246.003064)
			(xy 38.333724 -246.002621) (xy 38.251867 -245.995038) (xy 38.171058 -245.979934) (xy 38.091988 -245.957438)
			(xy 38.015331 -245.927742) (xy 37.941741 -245.8911) (xy 37.871846 -245.847823) (xy 37.806243 -245.798281)
			(xy 37.745491 -245.742898) (xy 37.690108 -245.682145) (xy 37.640568 -245.616541) (xy 37.597293 -245.546645)
			(xy 37.560651 -245.473055) (xy 37.530957 -245.396397) (xy 37.508462 -245.317326) (xy 37.49336 -245.236518)
			(xy 37.485778 -245.15466) (xy 37.48532 -245.113556) (xy 36.801115 -245.113556) (xy 36.772406 -245.127852)
			(xy 36.695754 -245.157549) (xy 36.61669 -245.180047) (xy 36.535886 -245.195154) (xy 36.454034 -245.202742)
			(xy 36.412932 -245.203218) (xy 36.373362 -245.202812) (xy 36.294534 -245.195801) (xy 36.21664 -245.181815)
			(xy 36.140297 -245.160963) (xy 36.103052 -245.147592) (xy 36.094385 -245.144752) (xy 36.076159 -245.144752)
			(xy 36.067492 -245.147592) (xy 36.030252 -245.160974) (xy 35.953906 -245.181817) (xy 35.876011 -245.195795)
			(xy 35.797182 -245.202799) (xy 35.757612 -245.203218) (xy 35.719323 -245.202797) (xy 35.643033 -245.196172)
			(xy 35.567593 -245.18302) (xy 35.493561 -245.16344) (xy 35.457384 -245.150894) (xy 35.448946 -245.148252)
			(xy 35.431278 -245.148252) (xy 35.42284 -245.150894) (xy 35.386664 -245.163448) (xy 35.312636 -245.183045)
			(xy 35.237195 -245.196197) (xy 35.160901 -245.202807) (xy 35.122612 -245.203218) (xy 35.081509 -245.202736)
			(xy 34.999655 -245.195153) (xy 34.918849 -245.180048) (xy 34.839781 -245.157553) (xy 34.763127 -245.127858)
			(xy 34.689539 -245.091217) (xy 34.619646 -245.047942) (xy 34.554044 -244.998403) (xy 34.493293 -244.943023)
			(xy 34.437911 -244.882273) (xy 34.38837 -244.816672) (xy 34.345094 -244.74678) (xy 34.308451 -244.673193)
			(xy 34.278754 -244.59654) (xy 34.256257 -244.517473) (xy 34.24115 -244.436667) (xy 34.233565 -244.354813)
			(xy 34.233104 -244.31371) (xy 33.762263 -244.31371) (xy 32.643449 -247.015) (xy 40.003982 -247.015)
			(xy 40.008053 -246.959378) (xy 40.020179 -246.904941) (xy 40.040102 -246.85285) (xy 40.067398 -246.804215)
			(xy 40.101484 -246.760072) (xy 40.141633 -246.721363) (xy 40.186991 -246.688912) (xy 40.236591 -246.663411)
			(xy 40.289375 -246.645404) (xy 40.344218 -246.635274) (xy 40.399952 -246.633237) (xy 40.455389 -246.639337)
			(xy 40.509346 -246.653443) (xy 40.560675 -246.675255) (xy 40.608281 -246.704309) (xy 40.651149 -246.739984)
			(xy 40.688366 -246.781521) (xy 40.719139 -246.828034) (xy 40.742811 -246.878531) (xy 40.758879 -246.931938)
			(xy 40.766999 -246.987114) (xy 40.767508 -247.015) (xy 40.766999 -247.042886) (xy 40.758879 -247.098062)
			(xy 40.742811 -247.151469) (xy 40.719139 -247.201966) (xy 40.688366 -247.248479) (xy 40.651149 -247.290016)
			(xy 40.608281 -247.325691) (xy 40.560675 -247.354745) (xy 40.509346 -247.376557) (xy 40.455389 -247.390663)
			(xy 40.399952 -247.396763) (xy 40.344218 -247.394726) (xy 40.289375 -247.384596) (xy 40.236591 -247.366589)
			(xy 40.186991 -247.341088) (xy 40.141633 -247.308637) (xy 40.101484 -247.269928) (xy 40.067398 -247.225785)
			(xy 40.040102 -247.17715) (xy 40.020179 -247.125059) (xy 40.008053 -247.070622) (xy 40.003982 -247.015)
			(xy 32.643449 -247.015) (xy 31.983943 -248.607326) (xy 32.41243 -248.607326) (xy 32.416501 -248.551704)
			(xy 32.428627 -248.497267) (xy 32.44855 -248.445176) (xy 32.475846 -248.396541) (xy 32.509932 -248.352398)
			(xy 32.550081 -248.313689) (xy 32.595439 -248.281238) (xy 32.645039 -248.255737) (xy 32.697823 -248.23773)
			(xy 32.752666 -248.2276) (xy 32.8084 -248.225563) (xy 32.863837 -248.231663) (xy 32.917794 -248.245769)
			(xy 32.969123 -248.267581) (xy 33.016729 -248.296635) (xy 33.059597 -248.33231) (xy 33.075489 -248.350047)
			(xy 34.824724 -248.350047) (xy 34.824724 -248.295553) (xy 34.832479 -248.241615) (xy 34.847831 -248.189329)
			(xy 34.870467 -248.13976) (xy 34.899927 -248.093916) (xy 34.935611 -248.052732) (xy 34.976792 -248.017045)
			(xy 35.022633 -247.987581) (xy 35.072201 -247.964941) (xy 35.124486 -247.949585) (xy 35.178423 -247.941826)
			(xy 35.20567 -247.941338) (xy 35.234598 -247.941873) (xy 35.29179 -247.950605) (xy 35.347008 -247.967874)
			(xy 35.398984 -247.993283) (xy 35.446528 -248.02625) (xy 35.488548 -248.066018) (xy 35.524081 -248.111675)
			(xy 35.538664 -248.136664) (xy 35.545956 -248.148693) (xy 35.565827 -248.168583) (xy 35.59037 -248.182296)
			(xy 35.617725 -248.188792) (xy 35.645813 -248.187576) (xy 35.672504 -248.178743) (xy 35.695772 -248.162961)
			(xy 35.71385 -248.141429) (xy 35.72002 -248.12879) (xy 35.731625 -248.103957) (xy 35.760986 -248.057669)
			(xy 35.796672 -248.016062) (xy 35.837948 -247.979994) (xy 35.883963 -247.950207) (xy 35.93377 -247.927317)
			(xy 35.986341 -247.911795) (xy 36.040593 -247.90396) (xy 36.068 -247.903492) (xy 36.095251 -247.903978)
			(xy 36.149199 -247.911734) (xy 36.201494 -247.927089) (xy 36.251071 -247.949731) (xy 36.296921 -247.979197)
			(xy 36.338112 -248.014888) (xy 36.373803 -248.056079) (xy 36.403269 -248.101929) (xy 36.425911 -248.151506)
			(xy 36.441266 -248.203801) (xy 36.449022 -248.257749) (xy 36.449022 -248.312251) (xy 36.441266 -248.366199)
			(xy 36.425911 -248.418494) (xy 36.403269 -248.468071) (xy 36.373803 -248.513921) (xy 36.338112 -248.555112)
			(xy 36.296921 -248.590803) (xy 36.251071 -248.620269) (xy 36.201494 -248.642911) (xy 36.149199 -248.658266)
			(xy 36.095251 -248.666022) (xy 36.068 -248.666508) (xy 36.039073 -248.665973) (xy 35.981882 -248.657238)
			(xy 35.926665 -248.639967) (xy 35.874689 -248.614558) (xy 35.827146 -248.581592) (xy 35.785125 -248.541825)
			(xy 35.74959 -248.49617) (xy 35.735006 -248.471182) (xy 35.727763 -248.459118) (xy 35.707887 -248.439217)
			(xy 35.683333 -248.425496) (xy 35.655967 -248.418999) (xy 35.627866 -248.420219) (xy 35.601165 -248.429063)
			(xy 35.577893 -248.444859) (xy 35.559816 -248.466408) (xy 35.55365 -248.479056) (xy 35.541964 -248.503849)
			(xy 35.512617 -248.550137) (xy 35.476943 -248.591746) (xy 35.435679 -248.627818) (xy 35.389675 -248.65761)
			(xy 35.339879 -248.680507) (xy 35.287318 -248.696037) (xy 35.233074 -248.703881) (xy 35.20567 -248.704354)
			(xy 35.178423 -248.703774) (xy 35.124486 -248.696015) (xy 35.072201 -248.680659) (xy 35.022633 -248.658019)
			(xy 34.976792 -248.628555) (xy 34.935611 -248.592868) (xy 34.899927 -248.551684) (xy 34.870467 -248.50584)
			(xy 34.847831 -248.456271) (xy 34.832479 -248.403985) (xy 34.824724 -248.350047) (xy 33.075489 -248.350047)
			(xy 33.096814 -248.373847) (xy 33.127587 -248.42036) (xy 33.151259 -248.470857) (xy 33.167327 -248.524264)
			(xy 33.175447 -248.57944) (xy 33.175956 -248.607326) (xy 33.175447 -248.635212) (xy 33.167327 -248.690388)
			(xy 33.151259 -248.743795) (xy 33.127587 -248.794292) (xy 33.096814 -248.840805) (xy 33.059597 -248.882342)
			(xy 33.016729 -248.918017) (xy 32.969123 -248.947071) (xy 32.917794 -248.968883) (xy 32.863837 -248.982989)
			(xy 32.8084 -248.989089) (xy 32.752666 -248.987052) (xy 32.697823 -248.976922) (xy 32.645039 -248.958915)
			(xy 32.595439 -248.933414) (xy 32.550081 -248.900963) (xy 32.509932 -248.862254) (xy 32.475846 -248.818111)
			(xy 32.44855 -248.769476) (xy 32.428627 -248.717385) (xy 32.416501 -248.662948) (xy 32.41243 -248.607326)
			(xy 31.983943 -248.607326) (xy 31.682436 -249.33529) (xy 31.678118 -249.345196) (xy 31.6738 -249.355102)
			(xy 31.6738 -251.362718) (xy 31.674227 -251.372787) (xy 31.681946 -251.391386) (xy 31.688786 -251.398786)
			(xy 31.990538 -251.700538) (xy 31.997882 -251.707349) (xy 32.016346 -251.715078) (xy 32.026352 -251.715524)
			(xy 35.023298 -251.715524) (xy 35.032622 -251.715107) (xy 35.050031 -251.708425) (xy 35.063889 -251.695948)
			(xy 35.06851 -251.687838) (xy 35.116516 -251.59462) (xy 35.114484 -251.566426) (xy 35.106102 -251.554742)
			(xy 35.089345 -251.53034) (xy 35.062778 -251.477444) (xy 35.044703 -251.421078) (xy 35.035556 -251.362596)
			(xy 35.034982 -251.333) (xy 35.035468 -251.305749) (xy 35.043224 -251.251801) (xy 35.058579 -251.199506)
			(xy 35.081221 -251.149929) (xy 35.110687 -251.104079) (xy 35.146378 -251.062888) (xy 35.187569 -251.027197)
			(xy 35.233419 -250.997731) (xy 35.282996 -250.975089) (xy 35.335291 -250.959734) (xy 35.389239 -250.951978)
			(xy 35.443741 -250.951978) (xy 35.497689 -250.959734) (xy 35.549984 -250.975089) (xy 35.599561 -250.997731)
			(xy 35.645411 -251.027197) (xy 35.686602 -251.062888) (xy 35.722293 -251.104079) (xy 35.751759 -251.149929)
			(xy 35.774401 -251.199506) (xy 35.789756 -251.251801) (xy 35.797512 -251.305749) (xy 35.797998 -251.333)
			(xy 35.797439 -251.362597) (xy 35.788289 -251.421079) (xy 35.770208 -251.477445) (xy 35.743633 -251.530337)
			(xy 35.726878 -251.554742) (xy 35.718496 -251.566426) (xy 35.716464 -251.59462) (xy 35.76447 -251.687838)
			(xy 35.769085 -251.695948) (xy 35.782952 -251.70841) (xy 35.80036 -251.715086) (xy 35.809682 -251.715524)
			(xy 36.887912 -251.715524) (xy 36.916873 -251.716093) (xy 36.974082 -251.725155) (xy 37.029168 -251.743055)
			(xy 37.080777 -251.769351) (xy 37.127637 -251.803396) (xy 37.148516 -251.823474) (xy 37.698426 -252.373384)
			(xy 37.718502 -252.394264) (xy 37.752547 -252.441124) (xy 37.778843 -252.492733) (xy 37.796743 -252.547819)
			(xy 37.805805 -252.605027) (xy 37.806376 -252.633988) (xy 37.806376 -252.796548) (xy 37.8079 -252.802644)
			(xy 37.813223 -252.825323) (xy 37.818956 -252.871554) (xy 37.81933 -252.894846) (xy 37.818884 -252.92118)
			(xy 37.811635 -252.973348) (xy 37.797281 -253.024023) (xy 37.776095 -253.072243) (xy 37.748479 -253.117092)
			(xy 37.714958 -253.157717) (xy 37.676169 -253.193346) (xy 37.632849 -253.223303) (xy 37.585822 -253.247018)
			(xy 37.535979 -253.26404) (xy 37.510212 -253.269496) (xy 37.499036 -253.271528) (xy 37.480748 -253.284736)
			(xy 37.432234 -253.373128) (xy 37.43071 -253.39548) (xy 37.434774 -253.406148) (xy 37.443062 -253.428319)
			(xy 37.454708 -253.474197) (xy 37.460575 -253.521165) (xy 37.460936 -253.544832) (xy 37.46045 -253.572083)
			(xy 37.452694 -253.626031) (xy 37.437339 -253.678326) (xy 37.414697 -253.727903) (xy 37.385231 -253.773753)
			(xy 37.34954 -253.814944) (xy 37.308349 -253.850635) (xy 37.262499 -253.880101) (xy 37.212922 -253.902743)
			(xy 37.160627 -253.918098) (xy 37.106679 -253.925854) (xy 37.052177 -253.925854) (xy 36.998229 -253.918098)
			(xy 36.945934 -253.902743) (xy 36.896357 -253.880101) (xy 36.850507 -253.850635) (xy 36.809316 -253.814944)
			(xy 36.773625 -253.773753) (xy 36.744159 -253.727903) (xy 36.721517 -253.678326) (xy 36.706162 -253.626031)
			(xy 36.698406 -253.572083) (xy 36.69792 -253.544832) (xy 36.69825 -253.521672) (xy 36.703828 -253.47569)
			(xy 36.714918 -253.430718) (xy 36.722812 -253.408942) (xy 36.72713 -253.39802) (xy 36.725098 -253.37516)
			(xy 36.673282 -253.286768) (xy 36.654232 -253.274068) (xy 36.642802 -253.27229) (xy 36.615978 -253.267851)
			(xy 36.563859 -253.25237) (xy 36.514467 -253.229646) (xy 36.468801 -253.200139) (xy 36.427788 -253.164446)
			(xy 36.392258 -253.123293) (xy 36.362931 -253.077511) (xy 36.340402 -253.028029) (xy 36.325126 -252.97585)
			(xy 36.317414 -252.922031) (xy 36.31692 -252.894846) (xy 36.31748 -252.864986) (xy 36.32675 -252.80599)
			(xy 36.345103 -252.749161) (xy 36.372089 -252.695887) (xy 36.407049 -252.64747) (xy 36.427664 -252.62586)
			(xy 36.43884 -252.614938) (xy 36.444682 -252.584966) (xy 36.402518 -252.484128) (xy 36.398279 -252.475064)
			(xy 36.384205 -252.460868) (xy 36.365774 -252.453127) (xy 36.355782 -252.452632) (xy 31.457646 -252.452632)
			(xy 31.428681 -252.452097) (xy 31.371464 -252.443041) (xy 31.316369 -252.425145) (xy 31.264751 -252.39885)
			(xy 31.217883 -252.364803) (xy 31.197042 -252.344682) (xy 30.887416 -252.03531) (xy 30.88099 -252.029348)
			(xy 30.865175 -252.021816) (xy 30.847744 -252.020086) (xy 30.839156 -252.021848) (xy 30.741366 -252.046486)
			(xy 30.722316 -252.064774) (xy 30.718252 -252.077982) (xy 30.709979 -252.103794) (xy 30.687155 -252.152957)
			(xy 30.657604 -252.198395) (xy 30.62192 -252.239194) (xy 30.580822 -252.274533) (xy 30.535137 -252.303701)
			(xy 30.485784 -252.32611) (xy 30.433756 -252.34131) (xy 30.380101 -252.348994) (xy 30.353 -252.349508)
			(xy 30.319801 -252.348792) (xy 30.254405 -252.337298) (xy 30.222952 -252.326648) (xy 30.211268 -252.32233)
			(xy 30.18663 -252.325632) (xy 30.108398 -252.380496) (xy 30.098763 -252.388115) (xy 30.087479 -252.409887)
			(xy 30.086808 -252.422152) (xy 30.086808 -253.148846) (xy 35.034472 -253.148846) (xy 35.038543 -253.093224)
			(xy 35.050669 -253.038787) (xy 35.070592 -252.986696) (xy 35.097888 -252.938061) (xy 35.131974 -252.893918)
			(xy 35.172123 -252.855209) (xy 35.217481 -252.822758) (xy 35.267081 -252.797257) (xy 35.319865 -252.77925)
			(xy 35.374708 -252.76912) (xy 35.430442 -252.767083) (xy 35.485879 -252.773183) (xy 35.539836 -252.787289)
			(xy 35.591165 -252.809101) (xy 35.638771 -252.838155) (xy 35.681639 -252.87383) (xy 35.718856 -252.915367)
			(xy 35.749629 -252.96188) (xy 35.773301 -253.012377) (xy 35.789369 -253.065784) (xy 35.797489 -253.12096)
			(xy 35.797998 -253.148846) (xy 35.797489 -253.176732) (xy 35.789369 -253.231908) (xy 35.773301 -253.285315)
			(xy 35.749629 -253.335812) (xy 35.718856 -253.382325) (xy 35.681639 -253.423862) (xy 35.638771 -253.459537)
			(xy 35.591165 -253.488591) (xy 35.539836 -253.510403) (xy 35.485879 -253.524509) (xy 35.430442 -253.530609)
			(xy 35.374708 -253.528572) (xy 35.319865 -253.518442) (xy 35.267081 -253.500435) (xy 35.217481 -253.474934)
			(xy 35.172123 -253.442483) (xy 35.131974 -253.403774) (xy 35.097888 -253.359631) (xy 35.070592 -253.310996)
			(xy 35.050669 -253.258905) (xy 35.038543 -253.204468) (xy 35.034472 -253.148846) (xy 30.086808 -253.148846)
			(xy 30.086808 -258.0386) (xy 31.59252 -258.0386) (xy 31.593031 -258.009683) (xy 31.60176 -257.952511)
			(xy 31.619019 -257.897312) (xy 31.644412 -257.84535) (xy 31.677358 -257.797816) (xy 31.7171 -257.7558)
			(xy 31.739586 -257.73761) (xy 31.748337 -257.730037) (xy 31.758527 -257.709287) (xy 31.759144 -257.697732)
			(xy 31.759144 -257.617468) (xy 31.758554 -257.605902) (xy 31.748375 -257.58513) (xy 31.739586 -257.57759)
			(xy 31.717095 -257.559408) (xy 31.677361 -257.517386) (xy 31.644423 -257.469849) (xy 31.619036 -257.417886)
			(xy 31.601781 -257.362687) (xy 31.593054 -257.305516) (xy 31.59252 -257.2766) (xy 31.592955 -257.249346)
			(xy 31.600713 -257.195392) (xy 31.616071 -257.143092) (xy 31.638715 -257.09351) (xy 31.668186 -257.047656)
			(xy 31.703882 -257.006463) (xy 31.745078 -256.970769) (xy 31.790935 -256.941302) (xy 31.840519 -256.918661)
			(xy 31.89282 -256.903307) (xy 31.946774 -256.895553) (xy 31.974028 -256.895092) (xy 32.002945 -256.895627)
			(xy 32.060117 -256.904348) (xy 32.115317 -256.9216) (xy 32.167279 -256.946988) (xy 32.214813 -256.979931)
			(xy 32.256829 -257.019672) (xy 32.275018 -257.042158) (xy 32.282566 -257.050933) (xy 32.303336 -257.061107)
			(xy 32.314896 -257.061716) (xy 32.39516 -257.061716) (xy 32.406724 -257.061117) (xy 32.427495 -257.050942)
			(xy 32.435038 -257.042158) (xy 32.451791 -257.021375) (xy 32.490145 -256.984245) (xy 32.533299 -256.952823)
			(xy 32.580413 -256.927724) (xy 32.630565 -256.909438) (xy 32.682776 -256.898321) (xy 32.736028 -256.894591)
			(xy 32.78928 -256.898321) (xy 32.841491 -256.909438) (xy 32.891643 -256.927724) (xy 32.938757 -256.952823)
			(xy 32.981911 -256.984245) (xy 33.020265 -257.021375) (xy 33.037018 -257.042158) (xy 33.044566 -257.050933)
			(xy 33.065336 -257.061107) (xy 33.076896 -257.061716) (xy 33.15716 -257.061716) (xy 33.168724 -257.061117)
			(xy 33.189495 -257.050942) (xy 33.197038 -257.042158) (xy 33.213791 -257.021375) (xy 33.252145 -256.984245)
			(xy 33.295299 -256.952823) (xy 33.342413 -256.927724) (xy 33.392565 -256.909438) (xy 33.444776 -256.898321)
			(xy 33.498028 -256.894591) (xy 33.55128 -256.898321) (xy 33.603491 -256.909438) (xy 33.653643 -256.927724)
			(xy 33.700757 -256.952823) (xy 33.743911 -256.984245) (xy 33.782265 -257.021375) (xy 33.799018 -257.042158)
			(xy 33.806566 -257.050933) (xy 33.827336 -257.061107) (xy 33.838896 -257.061716) (xy 33.91916 -257.061716)
			(xy 33.930724 -257.061117) (xy 33.951495 -257.050942) (xy 33.959038 -257.042158) (xy 33.977197 -257.019648)
			(xy 34.019225 -256.979916) (xy 34.066767 -256.946981) (xy 34.118734 -256.921598) (xy 34.173937 -256.904347)
			(xy 34.23111 -256.895624) (xy 34.260028 -256.895092) (xy 34.28728 -256.895552) (xy 34.341229 -256.903312)
			(xy 34.393524 -256.918671) (xy 34.443101 -256.941315) (xy 34.488951 -256.970784) (xy 34.530141 -257.006479)
			(xy 34.565832 -257.047671) (xy 34.595298 -257.093523) (xy 34.617939 -257.143102) (xy 34.633294 -257.195399)
			(xy 34.64105 -257.249348) (xy 34.641536 -257.2766) (xy 34.641042 -257.305518) (xy 34.632311 -257.362692)
			(xy 34.61505 -257.417892) (xy 34.589654 -257.469854) (xy 34.556705 -257.517387) (xy 34.516958 -257.559402)
			(xy 34.49447 -257.57759) (xy 34.485712 -257.585155) (xy 34.475528 -257.605912) (xy 34.474912 -257.617468)
			(xy 34.474912 -257.697732) (xy 34.475517 -257.709295) (xy 34.485687 -257.730067) (xy 34.49447 -257.73761)
			(xy 34.516952 -257.755803) (xy 34.556689 -257.797821) (xy 34.589629 -257.845356) (xy 34.615018 -257.897317)
			(xy 34.632274 -257.952514) (xy 34.641002 -258.009684) (xy 34.641536 -258.0386) (xy 34.641022 -258.06585)
			(xy 34.633267 -258.119795) (xy 34.617913 -258.172088) (xy 34.595274 -258.221663) (xy 34.56581 -258.267512)
			(xy 34.530122 -258.308702) (xy 34.488935 -258.344393) (xy 34.443088 -258.37386) (xy 34.393514 -258.396503)
			(xy 34.341223 -258.411861) (xy 34.287278 -258.41962) (xy 34.260028 -258.420108) (xy 34.23111 -258.419605)
			(xy 34.173937 -258.410877) (xy 34.118736 -258.393619) (xy 34.066773 -258.368225) (xy 34.01924 -258.335277)
			(xy 33.977226 -258.29553) (xy 33.959038 -258.273042) (xy 33.951465 -258.264292) (xy 33.930714 -258.254104)
			(xy 33.91916 -258.253484) (xy 33.838896 -258.253484) (xy 33.827329 -258.254058) (xy 33.806558 -258.264251)
			(xy 33.799018 -258.273042) (xy 33.782265 -258.293825) (xy 33.743911 -258.330955) (xy 33.700757 -258.362377)
			(xy 33.653643 -258.387476) (xy 33.603491 -258.405762) (xy 33.55128 -258.416879) (xy 33.498028 -258.420609)
			(xy 33.444776 -258.416879) (xy 33.392565 -258.405762) (xy 33.342413 -258.387476) (xy 33.295299 -258.362377)
			(xy 33.252145 -258.330955) (xy 33.213791 -258.293825) (xy 33.197038 -258.273042) (xy 33.189465 -258.264292)
			(xy 33.168714 -258.254104) (xy 33.15716 -258.253484) (xy 33.076896 -258.253484) (xy 33.065329 -258.254058)
			(xy 33.044558 -258.264251) (xy 33.037018 -258.273042) (xy 33.020265 -258.293825) (xy 32.981911 -258.330955)
			(xy 32.938757 -258.362377) (xy 32.891643 -258.387476) (xy 32.841491 -258.405762) (xy 32.78928 -258.416879)
			(xy 32.736028 -258.420609) (xy 32.682776 -258.416879) (xy 32.630565 -258.405762) (xy 32.580413 -258.387476)
			(xy 32.533299 -258.362377) (xy 32.490145 -258.330955) (xy 32.451791 -258.293825) (xy 32.435038 -258.273042)
			(xy 32.427465 -258.264292) (xy 32.406714 -258.254104) (xy 32.39516 -258.253484) (xy 32.314896 -258.253484)
			(xy 32.303329 -258.254058) (xy 32.282558 -258.264251) (xy 32.275018 -258.273042) (xy 32.256827 -258.295526)
			(xy 32.214806 -258.335259) (xy 32.167271 -258.368197) (xy 32.11531 -258.393585) (xy 32.060113 -258.410841)
			(xy 32.002944 -258.419572) (xy 31.974028 -258.420108) (xy 31.946776 -258.419619) (xy 31.892826 -258.411865)
			(xy 31.840528 -258.396513) (xy 31.790948 -258.373874) (xy 31.745095 -258.344409) (xy 31.703902 -258.308718)
			(xy 31.668208 -258.267527) (xy 31.63874 -258.221676) (xy 31.616097 -258.172098) (xy 31.60074 -258.119802)
			(xy 31.592983 -258.065852) (xy 31.59252 -258.0386) (xy 30.086808 -258.0386) (xy 30.086808 -259.842)
			(xy 37.590982 -259.842) (xy 37.595053 -259.786378) (xy 37.607179 -259.731941) (xy 37.627102 -259.67985)
			(xy 37.654398 -259.631215) (xy 37.688484 -259.587072) (xy 37.728633 -259.548363) (xy 37.773991 -259.515912)
			(xy 37.823591 -259.490411) (xy 37.876375 -259.472404) (xy 37.931218 -259.462274) (xy 37.986952 -259.460237)
			(xy 38.042389 -259.466337) (xy 38.096346 -259.480443) (xy 38.147675 -259.502255) (xy 38.195281 -259.531309)
			(xy 38.238149 -259.566984) (xy 38.275366 -259.608521) (xy 38.306139 -259.655034) (xy 38.329811 -259.705531)
			(xy 38.345879 -259.758938) (xy 38.353999 -259.814114) (xy 38.354508 -259.842) (xy 38.353999 -259.869886)
			(xy 38.345879 -259.925062) (xy 38.329811 -259.978469) (xy 38.306139 -260.028966) (xy 38.275366 -260.075479)
			(xy 38.238149 -260.117016) (xy 38.195281 -260.152691) (xy 38.147675 -260.181745) (xy 38.096346 -260.203557)
			(xy 38.042389 -260.217663) (xy 37.986952 -260.223763) (xy 37.931218 -260.221726) (xy 37.876375 -260.211596)
			(xy 37.823591 -260.193589) (xy 37.773991 -260.168088) (xy 37.728633 -260.135637) (xy 37.688484 -260.096928)
			(xy 37.654398 -260.052785) (xy 37.627102 -260.00415) (xy 37.607179 -259.952059) (xy 37.595053 -259.897622)
			(xy 37.590982 -259.842) (xy 30.086808 -259.842) (xy 30.086808 -261.266254) (xy 36.825355 -261.266254)
			(xy 36.825355 -261.211746) (xy 36.833113 -261.157792) (xy 36.848471 -261.105492) (xy 36.871115 -261.05591)
			(xy 36.900586 -261.010056) (xy 36.936282 -260.968863) (xy 36.977478 -260.933169) (xy 37.023335 -260.903702)
			(xy 37.072919 -260.881061) (xy 37.12522 -260.865707) (xy 37.179174 -260.857953) (xy 37.206428 -260.857492)
			(xy 37.235345 -260.858027) (xy 37.292517 -260.866748) (xy 37.347717 -260.884) (xy 37.399679 -260.909388)
			(xy 37.447213 -260.942331) (xy 37.489229 -260.982072) (xy 37.507418 -261.004558) (xy 37.514966 -261.013333)
			(xy 37.535736 -261.023507) (xy 37.547296 -261.024116) (xy 37.62756 -261.024116) (xy 37.639124 -261.023517)
			(xy 37.659895 -261.013342) (xy 37.667438 -261.004558) (xy 37.685597 -260.982048) (xy 37.727625 -260.942316)
			(xy 37.775167 -260.909381) (xy 37.827134 -260.883998) (xy 37.882337 -260.866747) (xy 37.93951 -260.858024)
			(xy 37.968428 -260.857492) (xy 37.995678 -260.85798) (xy 38.049623 -260.865739) (xy 38.101914 -260.881097)
			(xy 38.151488 -260.90374) (xy 38.197335 -260.933207) (xy 38.238522 -260.968898) (xy 38.27421 -261.010088)
			(xy 38.303674 -261.055937) (xy 38.326313 -261.105512) (xy 38.341667 -261.157805) (xy 38.349422 -261.21175)
			(xy 38.349422 -261.22122) (xy 38.518082 -261.22122) (xy 38.522153 -261.165598) (xy 38.534279 -261.111161)
			(xy 38.554202 -261.05907) (xy 38.581498 -261.010435) (xy 38.615584 -260.966292) (xy 38.655733 -260.927583)
			(xy 38.701091 -260.895132) (xy 38.750691 -260.869631) (xy 38.803475 -260.851624) (xy 38.858318 -260.841494)
			(xy 38.914052 -260.839457) (xy 38.969489 -260.845557) (xy 39.023446 -260.859663) (xy 39.074775 -260.881475)
			(xy 39.122381 -260.910529) (xy 39.165249 -260.946204) (xy 39.202466 -260.987741) (xy 39.233239 -261.034254)
			(xy 39.256911 -261.084751) (xy 39.272979 -261.138158) (xy 39.281099 -261.193334) (xy 39.281608 -261.22122)
			(xy 39.281099 -261.249106) (xy 39.272979 -261.304282) (xy 39.256911 -261.357689) (xy 39.233239 -261.408186)
			(xy 39.202466 -261.454699) (xy 39.165249 -261.496236) (xy 39.122381 -261.531911) (xy 39.074775 -261.560965)
			(xy 39.023446 -261.582777) (xy 38.969489 -261.596883) (xy 38.914052 -261.602983) (xy 38.858318 -261.600946)
			(xy 38.803475 -261.590816) (xy 38.750691 -261.572809) (xy 38.701091 -261.547308) (xy 38.655733 -261.514857)
			(xy 38.615584 -261.476148) (xy 38.581498 -261.432005) (xy 38.554202 -261.38337) (xy 38.534279 -261.331279)
			(xy 38.522153 -261.276842) (xy 38.518082 -261.22122) (xy 38.349422 -261.22122) (xy 38.349422 -261.26625)
			(xy 38.341667 -261.320195) (xy 38.326313 -261.372488) (xy 38.303674 -261.422063) (xy 38.27421 -261.467912)
			(xy 38.238522 -261.509102) (xy 38.197335 -261.544793) (xy 38.151488 -261.57426) (xy 38.101914 -261.596903)
			(xy 38.049623 -261.612261) (xy 37.995678 -261.62002) (xy 37.968428 -261.620508) (xy 37.93951 -261.620005)
			(xy 37.882337 -261.611277) (xy 37.827136 -261.594019) (xy 37.775173 -261.568625) (xy 37.72764 -261.535677)
			(xy 37.685626 -261.49593) (xy 37.667438 -261.473442) (xy 37.659865 -261.464692) (xy 37.639114 -261.454504)
			(xy 37.62756 -261.453884) (xy 37.547296 -261.453884) (xy 37.535729 -261.454458) (xy 37.514958 -261.464651)
			(xy 37.507418 -261.473442) (xy 37.489227 -261.495926) (xy 37.447206 -261.535659) (xy 37.399671 -261.568597)
			(xy 37.34771 -261.593985) (xy 37.292513 -261.611241) (xy 37.235344 -261.619972) (xy 37.206428 -261.620508)
			(xy 37.179174 -261.620047) (xy 37.12522 -261.612293) (xy 37.072919 -261.596939) (xy 37.023335 -261.574298)
			(xy 36.977478 -261.544831) (xy 36.936282 -261.509137) (xy 36.900586 -261.467944) (xy 36.871115 -261.42209)
			(xy 36.848471 -261.372508) (xy 36.833113 -261.320208) (xy 36.825355 -261.266254) (xy 30.086808 -261.266254)
			(xy 30.086808 -264.668) (xy 31.41472 -264.668) (xy 31.4153 -264.621604) (xy 31.424946 -264.529316)
			(xy 31.444142 -264.438532) (xy 31.472682 -264.350239) (xy 31.49092 -264.307574) (xy 31.49474 -264.297634)
			(xy 31.49474 -264.276366) (xy 31.49092 -264.266426) (xy 31.472677 -264.223763) (xy 31.444132 -264.135471)
			(xy 31.424938 -264.044686) (xy 31.415305 -263.952396) (xy 31.41472 -263.906) (xy 31.415152 -263.864896)
			(xy 31.422738 -263.783039) (xy 31.437844 -263.702231) (xy 31.460341 -263.623161) (xy 31.490039 -263.546505)
			(xy 31.526683 -263.472915) (xy 31.56996 -263.403021) (xy 31.619503 -263.337418) (xy 31.674887 -263.276667)
			(xy 31.73564 -263.221285) (xy 31.801244 -263.171745) (xy 31.87114 -263.128469) (xy 31.94473 -263.091827)
			(xy 32.021388 -263.062132) (xy 32.100458 -263.039637) (xy 32.181266 -263.024534) (xy 32.263124 -263.016951)
			(xy 32.304228 -263.016492) (xy 32.344002 -263.016919) (xy 32.423233 -263.024004) (xy 32.501513 -263.038142)
			(xy 32.578217 -263.05922) (xy 32.65273 -263.087068) (xy 32.688784 -263.103868) (xy 32.699285 -263.1082)
			(xy 32.721971 -263.1082) (xy 32.732472 -263.103868) (xy 32.768526 -263.08707) (xy 32.843045 -263.059245)
			(xy 32.91975 -263.038178) (xy 32.998028 -263.024037) (xy 33.077255 -263.016935) (xy 33.117028 -263.016492)
			(xy 33.163423 -263.0171) (xy 33.255711 -263.026738) (xy 33.346494 -263.045926) (xy 33.434789 -263.074458)
			(xy 33.477454 -263.092692) (xy 33.487394 -263.096512) (xy 33.508662 -263.096512) (xy 33.518602 -263.092692)
			(xy 33.56126 -263.074438) (xy 33.649554 -263.045896) (xy 33.74034 -263.026706) (xy 33.832632 -263.017075)
			(xy 33.879028 -263.016492) (xy 33.920131 -263.01694) (xy 34.001986 -263.024527) (xy 34.082792 -263.039635)
			(xy 34.161859 -263.062134) (xy 34.238513 -263.091832) (xy 34.3121 -263.128476) (xy 34.381992 -263.171753)
			(xy 34.447593 -263.221294) (xy 34.508343 -263.276677) (xy 34.563724 -263.337429) (xy 34.613263 -263.403031)
			(xy 34.656538 -263.472925) (xy 34.69318 -263.546513) (xy 34.722875 -263.623168) (xy 34.745372 -263.702236)
			(xy 34.760477 -263.783042) (xy 34.768061 -263.864897) (xy 34.768536 -263.906) (xy 34.767951 -263.952395)
			(xy 34.758306 -264.044684) (xy 34.739111 -264.135467) (xy 34.710573 -264.223761) (xy 34.692336 -264.266426)
			(xy 34.688519 -264.276366) (xy 34.688519 -264.297634) (xy 34.692336 -264.307574) (xy 34.710582 -264.350235)
			(xy 34.739126 -264.438528) (xy 34.758318 -264.529313) (xy 34.767951 -264.621604) (xy 34.768536 -264.668)
			(xy 34.768033 -264.709102) (xy 34.760449 -264.790954) (xy 34.745344 -264.871758) (xy 34.73105 -264.922)
			(xy 36.316372 -264.922) (xy 36.320402 -264.837396) (xy 36.332457 -264.753558) (xy 36.352426 -264.671245)
			(xy 36.380129 -264.591204) (xy 36.415315 -264.514158) (xy 36.457666 -264.440806) (xy 36.506798 -264.371812)
			(xy 36.562266 -264.307801) (xy 36.623567 -264.249352) (xy 36.690147 -264.196995) (xy 36.761402 -264.151204)
			(xy 36.836688 -264.112394) (xy 36.915321 -264.080916) (xy 36.996591 -264.057055) (xy 37.079761 -264.041028)
			(xy 37.164078 -264.032979) (xy 37.206428 -264.032492) (xy 37.252823 -264.0331) (xy 37.345111 -264.042738)
			(xy 37.435894 -264.061926) (xy 37.524189 -264.090458) (xy 37.566854 -264.108692) (xy 37.576794 -264.112512)
			(xy 37.598062 -264.112512) (xy 37.608002 -264.108692) (xy 37.65066 -264.090438) (xy 37.738954 -264.061896)
			(xy 37.82974 -264.042706) (xy 37.922032 -264.033075) (xy 37.968428 -264.032492) (xy 38.010776 -264.032997)
			(xy 38.095087 -264.04105) (xy 38.178252 -264.057081) (xy 38.259515 -264.080945) (xy 38.338143 -264.112425)
			(xy 38.413422 -264.151236) (xy 38.484672 -264.197027) (xy 38.551246 -264.249383) (xy 38.612542 -264.307831)
			(xy 38.624204 -264.32129) (xy 38.932104 -264.32129) (xy 38.932547 -264.283002) (xy 38.939166 -264.206712)
			(xy 38.952311 -264.131272) (xy 38.971885 -264.05724) (xy 38.984428 -264.021062) (xy 38.987073 -264.012625)
			(xy 38.98707 -263.994956) (xy 38.984428 -263.986518) (xy 38.971869 -263.950344) (xy 38.952273 -263.876315)
			(xy 38.939122 -263.800873) (xy 38.932514 -263.72458) (xy 38.932104 -263.68629) (xy 38.932543 -263.645186)
			(xy 38.940129 -263.56333) (xy 38.955235 -263.482522) (xy 38.977733 -263.403453) (xy 39.007431 -263.326798)
			(xy 39.044075 -263.253209) (xy 39.087352 -263.183315) (xy 39.136894 -263.117713) (xy 39.192277 -263.056962)
			(xy 39.25303 -263.00158) (xy 39.318634 -262.95204) (xy 39.388528 -262.908764) (xy 39.462118 -262.872122)
			(xy 39.538774 -262.842426) (xy 39.617844 -262.81993) (xy 39.698652 -262.804826) (xy 39.780508 -262.797242)
			(xy 39.821612 -262.796782) (xy 39.861181 -262.797206) (xy 39.940009 -262.804212) (xy 40.017903 -262.818193)
			(xy 40.094247 -262.83904) (xy 40.131492 -262.852408) (xy 40.140159 -262.855248) (xy 40.158385 -262.855248)
			(xy 40.167052 -262.852408) (xy 40.204298 -262.839042) (xy 40.280642 -262.818195) (xy 40.358535 -262.804212)
			(xy 40.437363 -262.797203) (xy 40.476932 -262.796782) (xy 40.51522 -262.797219) (xy 40.59151 -262.80384)
			(xy 40.66695 -262.816987) (xy 40.740982 -262.836562) (xy 40.77716 -262.849106) (xy 40.785598 -262.851748)
			(xy 40.803266 -262.851748) (xy 40.811704 -262.849106) (xy 40.847875 -262.83654) (xy 40.921906 -262.816946)
			(xy 40.997348 -262.803797) (xy 41.073642 -262.797191) (xy 41.111932 -262.796782) (xy 41.153035 -262.797236)
			(xy 41.234889 -262.804824) (xy 41.315695 -262.819931) (xy 41.394761 -262.84243) (xy 41.471415 -262.872128)
			(xy 41.545001 -262.908772) (xy 41.614893 -262.952049) (xy 41.680494 -263.00159) (xy 41.741243 -263.056972)
			(xy 41.796624 -263.117723) (xy 41.846164 -263.183325) (xy 41.889439 -263.253218) (xy 41.926081 -263.326805)
			(xy 41.955777 -263.40346) (xy 41.978274 -263.482527) (xy 41.993379 -263.563333) (xy 42.000965 -263.645187)
			(xy 42.00144 -263.68629) (xy 42.001018 -263.724578) (xy 41.994393 -263.800869) (xy 41.981242 -263.876309)
			(xy 41.961662 -263.950341) (xy 41.949116 -263.986518) (xy 41.946479 -263.994957) (xy 41.946475 -264.012624)
			(xy 41.949116 -264.021062) (xy 41.956228 -264.041128) (xy 41.961054 -264.055606) (xy 41.984676 -264.074402)
			(xy 42.107612 -264.085578) (xy 42.134282 -264.071354) (xy 42.141648 -264.058146) (xy 42.162852 -264.020476)
			(xy 42.21161 -263.949087) (xy 42.267062 -263.882764) (xy 42.328687 -263.822133) (xy 42.395903 -263.767767)
			(xy 42.468077 -263.720177) (xy 42.544526 -263.679814) (xy 42.62453 -263.647057) (xy 42.707335 -263.622215)
			(xy 42.792159 -263.605524) (xy 42.878203 -263.59714) (xy 42.921428 -263.596628) (xy 42.960997 -263.59705)
			(xy 43.039825 -263.604057) (xy 43.117719 -263.618038) (xy 43.194063 -263.638885) (xy 43.231308 -263.652254)
			(xy 43.239975 -263.655094) (xy 43.258201 -263.655094) (xy 43.266868 -263.652254) (xy 43.304113 -263.638885)
			(xy 43.380457 -263.618039) (xy 43.458351 -263.604056) (xy 43.537179 -263.597049) (xy 43.576748 -263.596628)
			(xy 43.615036 -263.597058) (xy 43.691327 -263.603681) (xy 43.766766 -263.616829) (xy 43.840799 -263.636407)
			(xy 43.876976 -263.648952) (xy 43.885414 -263.651594) (xy 43.903082 -263.651594) (xy 43.91152 -263.648952)
			(xy 43.947689 -263.636379) (xy 44.021721 -263.616788) (xy 44.097164 -263.603641) (xy 44.173458 -263.597037)
			(xy 44.211748 -263.596628) (xy 44.252852 -263.597021) (xy 44.33471 -263.604611) (xy 44.415518 -263.619721)
			(xy 44.494587 -263.642222) (xy 44.571243 -263.671923) (xy 44.644832 -263.70857) (xy 44.714725 -263.751851)
			(xy 44.780326 -263.801396) (xy 44.841077 -263.856783) (xy 44.896457 -263.917538) (xy 44.945996 -263.983145)
			(xy 44.98927 -264.053042) (xy 45.025911 -264.126634) (xy 45.055605 -264.203292) (xy 45.078099 -264.282364)
			(xy 45.093201 -264.363173) (xy 45.100783 -264.445032) (xy 45.101256 -264.486136) (xy 45.100823 -264.524424)
			(xy 45.094202 -264.600714) (xy 45.081054 -264.676154) (xy 45.061477 -264.750186) (xy 45.048932 -264.786364)
			(xy 45.046271 -264.794797) (xy 45.046283 -264.81247) (xy 45.048932 -264.820908) (xy 45.061501 -264.857078)
			(xy 45.081093 -264.931109) (xy 45.094241 -265.006552) (xy 45.100847 -265.082846) (xy 45.101256 -265.121136)
			(xy 45.100768 -265.162238) (xy 45.09318 -265.24409) (xy 45.078073 -265.324893) (xy 45.055575 -265.403958)
			(xy 45.025878 -265.48061) (xy 44.989236 -265.554195) (xy 44.945961 -265.624085) (xy 44.896423 -265.689685)
			(xy 44.841043 -265.750434) (xy 44.780294 -265.805815) (xy 44.714695 -265.855354) (xy 44.644805 -265.89863)
			(xy 44.571221 -265.935274) (xy 44.49457 -265.964971) (xy 44.415505 -265.98747) (xy 44.334702 -266.002578)
			(xy 44.25285 -266.010167) (xy 44.211748 -266.010644) (xy 44.172816 -266.010201) (xy 44.095253 -266.003367)
			(xy 44.018585 -265.989773) (xy 43.9434 -265.969524) (xy 43.906694 -265.956542) (xy 43.898145 -265.953778)
			(xy 43.880191 -265.953778) (xy 43.871642 -265.956542) (xy 43.834933 -265.969514) (xy 43.759747 -265.989755)
			(xy 43.68308 -266.003352) (xy 43.605519 -266.010203) (xy 43.566588 -266.010644) (xy 43.527656 -266.010219)
			(xy 43.450092 -266.003379) (xy 43.373424 -265.989781) (xy 43.298239 -265.969527) (xy 43.261534 -265.956542)
			(xy 43.252985 -265.953778) (xy 43.235031 -265.953778) (xy 43.226482 -265.956542) (xy 43.189769 -265.969503)
			(xy 43.114584 -265.989746) (xy 43.037919 -266.003347) (xy 42.960359 -266.010201) (xy 42.921428 -266.010644)
			(xy 42.880327 -266.010107) (xy 42.798476 -266.002525) (xy 42.717673 -265.987423) (xy 42.638608 -265.96493)
			(xy 42.561956 -265.935238) (xy 42.488371 -265.8986) (xy 42.41848 -265.855328) (xy 42.352879 -265.805793)
			(xy 42.292129 -265.750416) (xy 42.236748 -265.68967) (xy 42.187208 -265.624073) (xy 42.143932 -265.554185)
			(xy 42.107288 -265.480603) (xy 42.077591 -265.403953) (xy 42.055092 -265.32489) (xy 42.039984 -265.244088)
			(xy 42.032396 -265.162237) (xy 42.03192 -265.121136) (xy 42.032346 -265.082848) (xy 42.03897 -265.006557)
			(xy 42.05212 -264.931117) (xy 42.071699 -264.857085) (xy 42.084244 -264.820908) (xy 42.086866 -264.812465)
			(xy 42.086878 -264.794802) (xy 42.084244 -264.786364) (xy 42.077132 -264.766298) (xy 42.072306 -264.75182)
			(xy 42.048684 -264.733024) (xy 41.925748 -264.721848) (xy 41.899078 -264.736072) (xy 41.891712 -264.74928)
			(xy 41.870433 -264.786906) (xy 41.821685 -264.858298) (xy 41.766242 -264.924623) (xy 41.704625 -264.985256)
			(xy 41.637417 -265.039626) (xy 41.565252 -265.08722) (xy 41.48881 -265.127588) (xy 41.408812 -265.16035)
			(xy 41.326013 -265.185197) (xy 41.241194 -265.201893) (xy 41.155155 -265.210283) (xy 41.111932 -265.210798)
			(xy 41.073 -265.210362) (xy 40.995436 -265.203526) (xy 40.918768 -265.189931) (xy 40.843584 -265.16968)
			(xy 40.806878 -265.156696) (xy 40.798329 -265.153932) (xy 40.780375 -265.153932) (xy 40.771826 -265.156696)
			(xy 40.735118 -265.169671) (xy 40.659931 -265.189911) (xy 40.583265 -265.203508) (xy 40.505703 -265.210358)
			(xy 40.466772 -265.210798) (xy 40.42784 -265.21038) (xy 40.350276 -265.203539) (xy 40.273607 -265.189938)
			(xy 40.198423 -265.169682) (xy 40.161718 -265.156696) (xy 40.153169 -265.153932) (xy 40.135215 -265.153932)
			(xy 40.126666 -265.156696) (xy 40.089954 -265.169659) (xy 40.014769 -265.189903) (xy 39.938103 -265.203503)
			(xy 39.860543 -265.210356) (xy 39.821612 -265.210798) (xy 39.780509 -265.210336) (xy 39.698653 -265.202752)
			(xy 39.617846 -265.187648) (xy 39.538777 -265.165152) (xy 39.462122 -265.135456) (xy 39.388533 -265.098814)
			(xy 39.31864 -265.055538) (xy 39.253037 -265.005998) (xy 39.192286 -264.950615) (xy 39.136904 -264.889864)
			(xy 39.087363 -264.824262) (xy 39.044087 -264.754368) (xy 39.007445 -264.68078) (xy 38.977749 -264.604125)
			(xy 38.955253 -264.525056) (xy 38.940148 -264.444249) (xy 38.932564 -264.362393) (xy 38.932104 -264.32129)
			(xy 38.624204 -264.32129) (xy 38.668004 -264.37184) (xy 38.717132 -264.440831) (xy 38.759479 -264.51418)
			(xy 38.794662 -264.591222) (xy 38.822362 -264.671259) (xy 38.842329 -264.753567) (xy 38.854383 -264.837401)
			(xy 38.858413 -264.922) (xy 38.854383 -265.006599) (xy 38.842329 -265.090433) (xy 38.822362 -265.172741)
			(xy 38.794662 -265.252778) (xy 38.759479 -265.32982) (xy 38.717132 -265.403169) (xy 38.668004 -265.47216)
			(xy 38.612542 -265.536169) (xy 38.551246 -265.594617) (xy 38.484672 -265.646973) (xy 38.413422 -265.692764)
			(xy 38.338143 -265.731575) (xy 38.259515 -265.763055) (xy 38.178252 -265.786919) (xy 38.095087 -265.80295)
			(xy 38.010776 -265.811003) (xy 37.968428 -265.811508) (xy 37.922033 -265.810915) (xy 37.829745 -265.801273)
			(xy 37.738961 -265.78208) (xy 37.650667 -265.753544) (xy 37.608002 -265.735308) (xy 37.598062 -265.731488)
			(xy 37.576794 -265.731488) (xy 37.566854 -265.735308) (xy 37.524188 -265.753544) (xy 37.435897 -265.78209)
			(xy 37.345113 -265.801286) (xy 37.252824 -265.810922) (xy 37.206428 -265.811508) (xy 37.164078 -265.811021)
			(xy 37.079761 -265.802972) (xy 36.996591 -265.786945) (xy 36.915321 -265.763084) (xy 36.836688 -265.731606)
			(xy 36.761402 -265.692796) (xy 36.690147 -265.647005) (xy 36.623567 -265.594648) (xy 36.562266 -265.536199)
			(xy 36.506798 -265.472188) (xy 36.457666 -265.403194) (xy 36.415315 -265.329842) (xy 36.380129 -265.252796)
			(xy 36.352426 -265.172755) (xy 36.332457 -265.090442) (xy 36.320402 -265.006604) (xy 36.316372 -264.922)
			(xy 34.73105 -264.922) (xy 34.722849 -264.950823) (xy 34.693154 -265.027476) (xy 34.656513 -265.101062)
			(xy 34.61324 -265.170953) (xy 34.563702 -265.236553) (xy 34.508323 -265.297303) (xy 34.447575 -265.352684)
			(xy 34.381976 -265.402224) (xy 34.312086 -265.4455) (xy 34.238502 -265.482143) (xy 34.16185 -265.51184)
			(xy 34.082785 -265.534338) (xy 34.001982 -265.549445) (xy 33.92013 -265.557032) (xy 33.879028 -265.557508)
			(xy 33.832633 -265.556915) (xy 33.740345 -265.547273) (xy 33.649561 -265.52808) (xy 33.561267 -265.499544)
			(xy 33.518602 -265.481308) (xy 33.508662 -265.477488) (xy 33.487394 -265.477488) (xy 33.477454 -265.481308)
			(xy 33.434788 -265.499544) (xy 33.346497 -265.52809) (xy 33.255713 -265.547286) (xy 33.163424 -265.556922)
			(xy 33.117028 -265.557508) (xy 33.077254 -265.557098) (xy 32.998023 -265.550009) (xy 32.919742 -265.535867)
			(xy 32.843038 -265.514786) (xy 32.768526 -265.486934) (xy 32.732472 -265.470132) (xy 32.721971 -265.4658)
			(xy 32.699285 -265.4658) (xy 32.688784 -265.470132) (xy 32.652721 -265.48691) (xy 32.578204 -265.514739)
			(xy 32.501502 -265.53581) (xy 32.423226 -265.549956) (xy 32.344 -265.557063) (xy 32.304228 -265.557508)
			(xy 32.263125 -265.557021) (xy 32.18127 -265.549439) (xy 32.100464 -265.534336) (xy 32.021396 -265.511841)
			(xy 31.944741 -265.482147) (xy 31.871153 -265.445507) (xy 31.80126 -265.402232) (xy 31.735658 -265.352694)
			(xy 31.674906 -265.297313) (xy 31.619524 -265.236564) (xy 31.569983 -265.170963) (xy 31.526707 -265.101071)
			(xy 31.490064 -265.027484) (xy 31.460368 -264.95083) (xy 31.437871 -264.871763) (xy 31.422765 -264.790957)
			(xy 31.41518 -264.709103) (xy 31.41472 -264.668) (xy 30.086808 -264.668) (xy 30.086808 -267.97) (xy 31.414217 -267.97)
			(xy 31.418248 -267.885399) (xy 31.430301 -267.801564) (xy 31.450269 -267.719255) (xy 31.477971 -267.639216)
			(xy 31.513155 -267.562173) (xy 31.555503 -267.488824) (xy 31.604632 -267.419831) (xy 31.660097 -267.355822)
			(xy 31.721395 -267.297374) (xy 31.787971 -267.245018) (xy 31.859223 -267.199227) (xy 31.934504 -267.160417)
			(xy 32.013134 -267.128938) (xy 32.0944 -267.105076) (xy 32.177566 -267.089047) (xy 32.26188 -267.080996)
			(xy 32.304228 -267.080492) (xy 32.344002 -267.080919) (xy 32.423233 -267.088004) (xy 32.501513 -267.102142)
			(xy 32.578217 -267.12322) (xy 32.65273 -267.151068) (xy 32.688784 -267.167868) (xy 32.699285 -267.1722)
			(xy 32.721971 -267.1722) (xy 32.732472 -267.167868) (xy 32.768526 -267.15107) (xy 32.843045 -267.123245)
			(xy 32.91975 -267.102178) (xy 32.998028 -267.088037) (xy 33.077255 -267.080935) (xy 33.117028 -267.080492)
			(xy 33.163423 -267.0811) (xy 33.255711 -267.090738) (xy 33.346494 -267.109926) (xy 33.434789 -267.138458)
			(xy 33.477454 -267.156692) (xy 33.487394 -267.160512) (xy 33.508662 -267.160512) (xy 33.518602 -267.156692)
			(xy 33.56126 -267.138438) (xy 33.649554 -267.109896) (xy 33.74034 -267.090706) (xy 33.832632 -267.081075)
			(xy 33.879028 -267.080492) (xy 33.921377 -267.08098) (xy 34.005692 -267.089031) (xy 34.08886 -267.10506)
			(xy 34.170128 -267.128922) (xy 34.24876 -267.160401) (xy 34.324043 -267.199212) (xy 34.395296 -267.245004)
			(xy 34.461874 -267.297361) (xy 34.523173 -267.35581) (xy 34.578639 -267.419821) (xy 34.627769 -267.488814)
			(xy 34.670118 -267.562165) (xy 34.705303 -267.63921) (xy 34.733006 -267.71925) (xy 34.752974 -267.801561)
			(xy 34.765028 -267.885397) (xy 34.769058 -267.97) (xy 34.765028 -268.054603) (xy 34.752974 -268.138439)
			(xy 34.733006 -268.22075) (xy 34.705303 -268.30079) (xy 34.670118 -268.377835) (xy 34.627769 -268.451186)
			(xy 34.578639 -268.520179) (xy 34.523173 -268.58419) (xy 34.461874 -268.642639) (xy 34.395296 -268.694996)
			(xy 34.324043 -268.740788) (xy 34.24876 -268.779599) (xy 34.170128 -268.811078) (xy 34.08886 -268.83494)
			(xy 34.005692 -268.850969) (xy 33.921377 -268.85902) (xy 33.879028 -268.859508) (xy 33.832633 -268.858915)
			(xy 33.740345 -268.849273) (xy 33.649561 -268.83008) (xy 33.561267 -268.801544) (xy 33.518602 -268.783308)
			(xy 33.508662 -268.779488) (xy 33.487394 -268.779488) (xy 33.477454 -268.783308) (xy 33.434788 -268.801544)
			(xy 33.346497 -268.83009) (xy 33.255713 -268.849286) (xy 33.163424 -268.858922) (xy 33.117028 -268.859508)
			(xy 33.077254 -268.859098) (xy 32.998023 -268.852009) (xy 32.919742 -268.837867) (xy 32.843038 -268.816786)
			(xy 32.768526 -268.788934) (xy 32.732472 -268.772132) (xy 32.721971 -268.7678) (xy 32.699285 -268.7678)
			(xy 32.688784 -268.772132) (xy 32.652721 -268.78891) (xy 32.578204 -268.816739) (xy 32.501502 -268.83781)
			(xy 32.423226 -268.851956) (xy 32.344 -268.859063) (xy 32.304228 -268.859508) (xy 32.26188 -268.859004)
			(xy 32.177566 -268.850953) (xy 32.0944 -268.834924) (xy 32.013134 -268.811062) (xy 31.934504 -268.779583)
			(xy 31.859223 -268.740773) (xy 31.787971 -268.694982) (xy 31.721395 -268.642626) (xy 31.660097 -268.584178)
			(xy 31.604632 -268.520169) (xy 31.555503 -268.451176) (xy 31.513155 -268.377827) (xy 31.477971 -268.300784)
			(xy 31.450269 -268.220745) (xy 31.430301 -268.138436) (xy 31.418248 -268.054601) (xy 31.414217 -267.97)
			(xy 30.086808 -267.97) (xy 30.086808 -269.942056) (xy 45.683424 -269.942056) (xy 45.684038 -269.911934)
			(xy 45.693509 -269.85244) (xy 45.71221 -269.795173) (xy 45.739677 -269.741555) (xy 45.775226 -269.692919)
			(xy 45.7962 -269.671292) (xy 45.803566 -269.66418) (xy 45.811186 -269.645384) (xy 45.811186 -269.552928)
			(xy 45.803566 -269.534132) (xy 45.7962 -269.52702) (xy 45.775204 -269.50541) (xy 45.739638 -269.456777)
			(xy 45.712161 -269.403157) (xy 45.693456 -269.345883) (xy 45.68399 -269.286381) (xy 45.683424 -269.256256)
			(xy 45.683837 -269.229002) (xy 45.6916 -269.17505) (xy 45.706963 -269.122752) (xy 45.729611 -269.073173)
			(xy 45.759085 -269.027321) (xy 45.794784 -268.98613) (xy 45.835982 -268.950439) (xy 45.881839 -268.920975)
			(xy 45.931423 -268.898336) (xy 45.983725 -268.882984) (xy 46.037678 -268.875232) (xy 46.064932 -268.874748)
			(xy 46.093848 -268.875297) (xy 46.151019 -268.884017) (xy 46.206217 -268.901268) (xy 46.25818 -268.926654)
			(xy 46.305714 -268.959593) (xy 46.347731 -268.99933) (xy 46.365922 -269.021814) (xy 46.373476 -269.030584)
			(xy 46.394241 -269.040762) (xy 46.4058 -269.041372) (xy 46.486064 -269.041372) (xy 46.497631 -269.04079)
			(xy 46.518402 -269.030605) (xy 46.525942 -269.021814) (xy 46.542695 -269.001031) (xy 46.581049 -268.963901)
			(xy 46.624203 -268.932479) (xy 46.671317 -268.90738) (xy 46.721469 -268.889094) (xy 46.77368 -268.877977)
			(xy 46.826932 -268.874247) (xy 46.880184 -268.877977) (xy 46.932395 -268.889094) (xy 46.982547 -268.90738)
			(xy 47.029661 -268.932479) (xy 47.072815 -268.963901) (xy 47.111169 -269.001031) (xy 47.127922 -269.021814)
			(xy 47.135476 -269.030584) (xy 47.156241 -269.040762) (xy 47.1678 -269.041372) (xy 47.248064 -269.041372)
			(xy 47.259631 -269.04079) (xy 47.280402 -269.030605) (xy 47.287942 -269.021814) (xy 47.304695 -269.001031)
			(xy 47.343049 -268.963901) (xy 47.386203 -268.932479) (xy 47.433317 -268.90738) (xy 47.483469 -268.889094)
			(xy 47.53568 -268.877977) (xy 47.588932 -268.874247) (xy 47.642184 -268.877977) (xy 47.694395 -268.889094)
			(xy 47.744547 -268.90738) (xy 47.791661 -268.932479) (xy 47.834815 -268.963901) (xy 47.873169 -269.001031)
			(xy 47.889922 -269.021814) (xy 47.897476 -269.030584) (xy 47.918241 -269.040762) (xy 47.9298 -269.041372)
			(xy 48.010064 -269.041372) (xy 48.021631 -269.04079) (xy 48.042402 -269.030605) (xy 48.049942 -269.021814)
			(xy 48.068113 -268.999313) (xy 48.110136 -268.959579) (xy 48.157675 -268.926641) (xy 48.209641 -268.901256)
			(xy 48.264842 -268.884003) (xy 48.322015 -268.87528) (xy 48.350932 -268.874748) (xy 48.378182 -268.875248)
			(xy 48.432127 -268.883008) (xy 48.484419 -268.898365) (xy 48.533993 -268.921006) (xy 48.579841 -268.950472)
			(xy 48.62103 -268.986162) (xy 48.656721 -269.027349) (xy 48.686188 -269.073196) (xy 48.708831 -269.12277)
			(xy 48.72419 -269.175061) (xy 48.731951 -269.229006) (xy 48.73244 -269.256256) (xy 48.731844 -269.286378)
			(xy 48.72237 -269.345874) (xy 48.703665 -269.403141) (xy 48.676194 -269.456759) (xy 48.640641 -269.505394)
			(xy 48.619664 -269.52702) (xy 48.612298 -269.534132) (xy 48.604678 -269.552928) (xy 48.604678 -269.645384)
			(xy 48.612298 -269.66418) (xy 48.619664 -269.671292) (xy 48.640659 -269.692903) (xy 48.676227 -269.741535)
			(xy 48.703705 -269.795155) (xy 48.722409 -269.852428) (xy 48.731875 -269.911931) (xy 48.73244 -269.942056)
			(xy 48.731904 -269.969306) (xy 48.724154 -270.023253) (xy 48.708805 -270.075548) (xy 48.68617 -270.125125)
			(xy 48.656709 -270.170977) (xy 48.621023 -270.21217) (xy 48.579838 -270.247864) (xy 48.533992 -270.277333)
			(xy 48.484419 -270.299978) (xy 48.432127 -270.315338) (xy 48.378182 -270.323098) (xy 48.350932 -270.323564)
			(xy 48.322015 -270.323036) (xy 48.264844 -270.314311) (xy 48.209645 -270.297056) (xy 48.157683 -270.271666)
			(xy 48.110149 -270.238724) (xy 48.068132 -270.198983) (xy 48.049942 -270.176498) (xy 48.042358 -270.167759)
			(xy 48.021616 -270.157563) (xy 48.010064 -270.15694) (xy 47.9298 -270.15694) (xy 47.91823 -270.157497)
			(xy 47.897458 -270.1677) (xy 47.889922 -270.176498) (xy 47.873169 -270.197281) (xy 47.834815 -270.234411)
			(xy 47.791661 -270.265833) (xy 47.744547 -270.290932) (xy 47.694395 -270.309218) (xy 47.642184 -270.320335)
			(xy 47.588932 -270.324065) (xy 47.53568 -270.320335) (xy 47.483469 -270.309218) (xy 47.433317 -270.290932)
			(xy 47.386203 -270.265833) (xy 47.343049 -270.234411) (xy 47.304695 -270.197281) (xy 47.287942 -270.176498)
			(xy 47.280358 -270.167759) (xy 47.259616 -270.157563) (xy 47.248064 -270.15694) (xy 47.1678 -270.15694)
			(xy 47.15623 -270.157497) (xy 47.135458 -270.1677) (xy 47.127922 -270.176498) (xy 47.111169 -270.197281)
			(xy 47.072815 -270.234411) (xy 47.029661 -270.265833) (xy 46.982547 -270.290932) (xy 46.932395 -270.309218)
			(xy 46.880184 -270.320335) (xy 46.826932 -270.324065) (xy 46.77368 -270.320335) (xy 46.721469 -270.309218)
			(xy 46.671317 -270.290932) (xy 46.624203 -270.265833) (xy 46.581049 -270.234411) (xy 46.542695 -270.197281)
			(xy 46.525942 -270.176498) (xy 46.518358 -270.167759) (xy 46.497616 -270.157563) (xy 46.486064 -270.15694)
			(xy 46.4058 -270.15694) (xy 46.39423 -270.157497) (xy 46.373458 -270.1677) (xy 46.365922 -270.176498)
			(xy 46.347718 -270.198971) (xy 46.305701 -270.238707) (xy 46.258169 -270.271647) (xy 46.20621 -270.297037)
			(xy 46.151015 -270.314296) (xy 46.093847 -270.323027) (xy 46.064932 -270.323564) (xy 46.037678 -270.323115)
			(xy 45.983724 -270.315361) (xy 45.931423 -270.300007) (xy 45.88184 -270.277365) (xy 45.835985 -270.247896)
			(xy 45.794791 -270.212201) (xy 45.759097 -270.171005) (xy 45.729629 -270.125149) (xy 45.706989 -270.075565)
			(xy 45.691636 -270.023264) (xy 45.683884 -269.96931) (xy 45.683424 -269.942056) (xy 30.086808 -269.942056)
			(xy 30.086808 -273.685) (xy 30.37078 -273.685) (xy 30.371227 -273.657629) (xy 30.379046 -273.603448)
			(xy 30.394539 -273.550944) (xy 30.417385 -273.501197) (xy 30.447116 -273.455232) (xy 30.46476 -273.434302)
			(xy 30.470856 -273.42719) (xy 30.477206 -273.410172) (xy 30.477206 -273.324828) (xy 30.470856 -273.30781)
			(xy 30.46476 -273.300698) (xy 30.447118 -273.279766) (xy 30.417391 -273.233799) (xy 30.394543 -273.184053)
			(xy 30.379046 -273.13155) (xy 30.371216 -273.077371) (xy 30.371216 -273.022629) (xy 30.379046 -272.96845)
			(xy 30.394543 -272.915947) (xy 30.417391 -272.866201) (xy 30.447118 -272.820234) (xy 30.46476 -272.799302)
			(xy 30.470856 -272.79219) (xy 30.477206 -272.775172) (xy 30.477206 -272.689828) (xy 30.470856 -272.67281)
			(xy 30.46476 -272.665698) (xy 30.4471 -272.644783) (xy 30.417392 -272.598805) (xy 30.394561 -272.549053)
			(xy 30.379075 -272.496549) (xy 30.371251 -272.44237) (xy 30.37078 -272.415) (xy 30.371266 -272.387749)
			(xy 30.379022 -272.333801) (xy 30.394377 -272.281506) (xy 30.417019 -272.231929) (xy 30.446485 -272.186079)
			(xy 30.482176 -272.144888) (xy 30.523367 -272.109197) (xy 30.569217 -272.079731) (xy 30.618794 -272.057089)
			(xy 30.671089 -272.041734) (xy 30.725037 -272.033978) (xy 30.779539 -272.033978) (xy 30.820327 -272.039842)
			(xy 31.815532 -272.039842) (xy 31.816016 -272.012506) (xy 31.823828 -271.958394) (xy 31.839283 -271.905951)
			(xy 31.862065 -271.856251) (xy 31.891707 -271.810312) (xy 31.927603 -271.769074) (xy 31.969018 -271.733381)
			(xy 31.991808 -271.718278) (xy 32.003711 -271.710089) (xy 32.022758 -271.688384) (xy 32.034963 -271.662213)
			(xy 32.039348 -271.633671) (xy 32.035563 -271.605043) (xy 32.02391 -271.578622) (xy 32.005323 -271.556522)
			(xy 31.993586 -271.548098) (xy 31.971555 -271.532877) (xy 31.931613 -271.497212) (xy 31.897052 -271.456311)
			(xy 31.868552 -271.410977) (xy 31.846674 -271.362103) (xy 31.831847 -271.310648) (xy 31.824363 -271.257626)
			(xy 31.823914 -271.230852) (xy 31.8244 -271.203601) (xy 31.832156 -271.149653) (xy 31.847511 -271.097358)
			(xy 31.870153 -271.047781) (xy 31.899619 -271.001931) (xy 31.93531 -270.96074) (xy 31.976501 -270.925049)
			(xy 32.022351 -270.895583) (xy 32.071928 -270.872941) (xy 32.124223 -270.857586) (xy 32.178171 -270.84983)
			(xy 32.232673 -270.84983) (xy 32.286621 -270.857586) (xy 32.338916 -270.872941) (xy 32.388493 -270.895583)
			(xy 32.434343 -270.925049) (xy 32.475534 -270.96074) (xy 32.511225 -271.001931) (xy 32.540691 -271.047781)
			(xy 32.563333 -271.097358) (xy 32.578688 -271.149653) (xy 32.586444 -271.203601) (xy 32.58693 -271.230852)
			(xy 32.586413 -271.258187) (xy 32.578603 -271.312296) (xy 32.563152 -271.364737) (xy 32.540375 -271.414435)
			(xy 32.510738 -271.460375) (xy 32.474848 -271.501615) (xy 32.433441 -271.537311) (xy 32.410654 -271.552416)
			(xy 32.398751 -271.560609) (xy 32.379693 -271.582309) (xy 32.36748 -271.60848) (xy 32.363091 -271.637026)
			(xy 32.366878 -271.665657) (xy 32.378537 -271.69208) (xy 32.397134 -271.714176) (xy 32.408876 -271.722596)
			(xy 32.430896 -271.737833) (xy 32.47084 -271.773494) (xy 32.505403 -271.814392) (xy 32.533905 -271.859723)
			(xy 32.543699 -271.8816) (xy 35.06978 -271.8816) (xy 35.070227 -271.843312) (xy 35.076845 -271.767022)
			(xy 35.089989 -271.691583) (xy 35.109562 -271.61755) (xy 35.122104 -271.581372) (xy 35.124746 -271.572934)
			(xy 35.124746 -271.555266) (xy 35.122104 -271.546828) (xy 35.109547 -271.510654) (xy 35.089951 -271.436624)
			(xy 35.0768 -271.361183) (xy 35.070191 -271.284889) (xy 35.06978 -271.2466) (xy 35.070284 -271.204252)
			(xy 35.078335 -271.119938) (xy 35.094364 -271.036772) (xy 35.118225 -270.955505) (xy 35.149704 -270.876875)
			(xy 35.188515 -270.801594) (xy 35.234305 -270.730342) (xy 35.286661 -270.663766) (xy 35.345109 -270.602468)
			(xy 35.409119 -270.547003) (xy 35.478111 -270.497874) (xy 35.551461 -270.455525) (xy 35.628504 -270.420341)
			(xy 35.708543 -270.392639) (xy 35.790852 -270.372671) (xy 35.874687 -270.360618) (xy 35.959288 -270.356588)
			(xy 36.043889 -270.360618) (xy 36.127724 -270.372671) (xy 36.210033 -270.392639) (xy 36.290072 -270.420341)
			(xy 36.367115 -270.455525) (xy 36.440465 -270.497874) (xy 36.509457 -270.547003) (xy 36.573467 -270.602468)
			(xy 36.631915 -270.663766) (xy 36.684271 -270.730342) (xy 36.730061 -270.801594) (xy 36.768872 -270.876875)
			(xy 36.800351 -270.955505) (xy 36.824212 -271.036772) (xy 36.840241 -271.119938) (xy 36.848292 -271.204252)
			(xy 36.848796 -271.2466) (xy 36.84835 -271.284888) (xy 36.841732 -271.361178) (xy 36.828588 -271.436618)
			(xy 36.809015 -271.51065) (xy 36.796472 -271.546828) (xy 36.793832 -271.555266) (xy 36.793832 -271.572934)
			(xy 36.796472 -271.581372) (xy 36.808091 -271.614764) (xy 36.826609 -271.683004) (xy 36.839642 -271.7525)
			(xy 36.843716 -271.78762) (xy 36.845359 -271.798125) (xy 36.856013 -271.816502) (xy 36.86429 -271.82318)
			(xy 36.897853 -271.848193) (xy 36.960558 -271.903652) (xy 37.017777 -271.964756) (xy 37.069003 -272.030964)
			(xy 37.113783 -272.101692) (xy 37.151722 -272.176313) (xy 37.182483 -272.254168) (xy 37.205796 -272.334568)
			(xy 37.221453 -272.416802) (xy 37.229316 -272.500144) (xy 37.229796 -272.542) (xy 37.22935 -272.580288)
			(xy 37.222732 -272.656578) (xy 37.209588 -272.732018) (xy 37.190015 -272.80605) (xy 37.177472 -272.842228)
			(xy 37.174832 -272.850666) (xy 37.174832 -272.868334) (xy 37.177472 -272.876772) (xy 37.190028 -272.912947)
			(xy 37.209625 -272.986976) (xy 37.222776 -273.062417) (xy 37.229385 -273.138711) (xy 37.229796 -273.177)
			(xy 37.22935 -273.215288) (xy 37.222732 -273.291578) (xy 37.209588 -273.367018) (xy 37.190015 -273.44105)
			(xy 37.177472 -273.477228) (xy 37.174832 -273.485666) (xy 37.174832 -273.503334) (xy 37.177472 -273.511772)
			(xy 37.190028 -273.547947) (xy 37.209625 -273.621976) (xy 37.222776 -273.697417) (xy 37.229385 -273.773711)
			(xy 37.229796 -273.812) (xy 37.229292 -273.854348) (xy 37.221241 -273.938662) (xy 37.205212 -274.021828)
			(xy 37.181351 -274.103095) (xy 37.149872 -274.181725) (xy 37.111061 -274.257006) (xy 37.065271 -274.328258)
			(xy 37.012915 -274.394834) (xy 36.954467 -274.456132) (xy 36.890457 -274.511597) (xy 36.821465 -274.560726)
			(xy 36.748115 -274.603075) (xy 36.671072 -274.638259) (xy 36.591033 -274.665961) (xy 36.508724 -274.685929)
			(xy 36.424889 -274.697982) (xy 36.340288 -274.702013) (xy 36.255687 -274.697982) (xy 36.171852 -274.685929)
			(xy 36.089543 -274.665961) (xy 36.009504 -274.638259) (xy 35.932461 -274.603075) (xy 35.859111 -274.560726)
			(xy 35.790119 -274.511597) (xy 35.726109 -274.456132) (xy 35.667661 -274.394834) (xy 35.615305 -274.328258)
			(xy 35.569515 -274.257006) (xy 35.530704 -274.181725) (xy 35.499225 -274.103095) (xy 35.475364 -274.021828)
			(xy 35.459335 -273.938662) (xy 35.451284 -273.854348) (xy 35.45078 -273.812) (xy 35.451227 -273.773712)
			(xy 35.457845 -273.697422) (xy 35.470989 -273.621983) (xy 35.490562 -273.54795) (xy 35.503104 -273.511772)
			(xy 35.505746 -273.503334) (xy 35.505746 -273.485666) (xy 35.503104 -273.477228) (xy 35.490547 -273.441054)
			(xy 35.470951 -273.367024) (xy 35.4578 -273.291583) (xy 35.451191 -273.215289) (xy 35.45078 -273.177)
			(xy 35.451227 -273.138712) (xy 35.457845 -273.062422) (xy 35.470989 -272.986983) (xy 35.490562 -272.91295)
			(xy 35.503104 -272.876772) (xy 35.505746 -272.868334) (xy 35.505746 -272.850666) (xy 35.503104 -272.842228)
			(xy 35.491488 -272.808835) (xy 35.472969 -272.740596) (xy 35.459934 -272.6711) (xy 35.45586 -272.63598)
			(xy 35.454191 -272.625481) (xy 35.443553 -272.607104) (xy 35.435286 -272.60042) (xy 35.40174 -272.575385)
			(xy 35.339032 -272.51993) (xy 35.281811 -272.45883) (xy 35.230582 -272.392625) (xy 35.1858 -272.3219)
			(xy 35.147859 -272.247281) (xy 35.117096 -272.169428) (xy 35.093782 -272.089029) (xy 35.078124 -272.006796)
			(xy 35.07026 -271.923455) (xy 35.06978 -271.8816) (xy 32.543699 -271.8816) (xy 32.555785 -271.908595)
			(xy 32.570613 -271.960048) (xy 32.578098 -272.013069) (xy 32.578548 -272.039842) (xy 32.578062 -272.067093)
			(xy 32.570306 -272.121041) (xy 32.554951 -272.173336) (xy 32.532309 -272.222913) (xy 32.502843 -272.268763)
			(xy 32.467152 -272.309954) (xy 32.425961 -272.345645) (xy 32.380111 -272.375111) (xy 32.330534 -272.397753)
			(xy 32.278239 -272.413108) (xy 32.224291 -272.420864) (xy 32.169789 -272.420864) (xy 32.115841 -272.413108)
			(xy 32.063546 -272.397753) (xy 32.013969 -272.375111) (xy 31.968119 -272.345645) (xy 31.926928 -272.309954)
			(xy 31.891237 -272.268763) (xy 31.861771 -272.222913) (xy 31.839129 -272.173336) (xy 31.823774 -272.121041)
			(xy 31.816018 -272.067093) (xy 31.815532 -272.039842) (xy 30.820327 -272.039842) (xy 30.833487 -272.041734)
			(xy 30.885782 -272.057089) (xy 30.935359 -272.079731) (xy 30.981209 -272.109197) (xy 31.0224 -272.144888)
			(xy 31.058091 -272.186079) (xy 31.087557 -272.231929) (xy 31.110199 -272.281506) (xy 31.125554 -272.333801)
			(xy 31.13331 -272.387749) (xy 31.133796 -272.415) (xy 31.133331 -272.44237) (xy 31.125513 -272.496549)
			(xy 31.110024 -272.549053) (xy 31.087182 -272.598799) (xy 31.057457 -272.644766) (xy 31.039816 -272.665698)
			(xy 31.03372 -272.67281) (xy 31.02737 -272.689828) (xy 31.02737 -272.775172) (xy 31.03372 -272.79219)
			(xy 31.039816 -272.799302) (xy 31.057455 -272.820236) (xy 31.087176 -272.866204) (xy 31.110019 -272.915951)
			(xy 31.125514 -272.968452) (xy 31.133341 -273.02263) (xy 31.133341 -273.07737) (xy 31.125514 -273.131548)
			(xy 31.110019 -273.184049) (xy 31.087176 -273.233796) (xy 31.057455 -273.279764) (xy 31.039816 -273.300698)
			(xy 31.03372 -273.30781) (xy 31.02737 -273.324828) (xy 31.02737 -273.410172) (xy 31.03372 -273.42719)
			(xy 31.039816 -273.434302) (xy 31.057472 -273.45522) (xy 31.087181 -273.501197) (xy 31.110013 -273.550948)
			(xy 31.1255 -273.603452) (xy 31.133324 -273.65763) (xy 31.133796 -273.685) (xy 31.13331 -273.712251)
			(xy 31.125554 -273.766199) (xy 31.110199 -273.818494) (xy 31.087557 -273.868071) (xy 31.058091 -273.913921)
			(xy 31.0224 -273.955112) (xy 30.981209 -273.990803) (xy 30.935359 -274.020269) (xy 30.885782 -274.042911)
			(xy 30.833487 -274.058266) (xy 30.779539 -274.066022) (xy 30.725037 -274.066022) (xy 30.671089 -274.058266)
			(xy 30.618794 -274.042911) (xy 30.569217 -274.020269) (xy 30.523367 -273.990803) (xy 30.482176 -273.955112)
			(xy 30.446485 -273.913921) (xy 30.417019 -273.868071) (xy 30.394377 -273.818494) (xy 30.379022 -273.766199)
			(xy 30.371266 -273.712251) (xy 30.37078 -273.685) (xy 30.086808 -273.685) (xy 30.086808 -278.638)
			(xy 30.37078 -278.638) (xy 30.371227 -278.610629) (xy 30.379046 -278.556448) (xy 30.394539 -278.503944)
			(xy 30.417385 -278.454197) (xy 30.447116 -278.408232) (xy 30.46476 -278.387302) (xy 30.470856 -278.38019)
			(xy 30.477206 -278.363172) (xy 30.477206 -278.277828) (xy 30.470856 -278.26081) (xy 30.46476 -278.253698)
			(xy 30.447118 -278.232766) (xy 30.417391 -278.186799) (xy 30.394543 -278.137053) (xy 30.379046 -278.08455)
			(xy 30.371216 -278.030371) (xy 30.371216 -277.975629) (xy 30.379046 -277.92145) (xy 30.394543 -277.868947)
			(xy 30.417391 -277.819201) (xy 30.447118 -277.773234) (xy 30.46476 -277.752302) (xy 30.470856 -277.74519)
			(xy 30.477206 -277.728172) (xy 30.477206 -277.642828) (xy 30.470856 -277.62581) (xy 30.46476 -277.618698)
			(xy 30.4471 -277.597783) (xy 30.417392 -277.551805) (xy 30.394561 -277.502053) (xy 30.379075 -277.449549)
			(xy 30.371251 -277.39537) (xy 30.37078 -277.368) (xy 30.371266 -277.340749) (xy 30.379022 -277.286801)
			(xy 30.394377 -277.234506) (xy 30.417019 -277.184929) (xy 30.446485 -277.139079) (xy 30.482176 -277.097888)
			(xy 30.523367 -277.062197) (xy 30.569217 -277.032731) (xy 30.618794 -277.010089) (xy 30.671089 -276.994734)
			(xy 30.725037 -276.986978) (xy 30.779539 -276.986978) (xy 30.833487 -276.994734) (xy 30.885782 -277.010089)
			(xy 30.935359 -277.032731) (xy 30.981209 -277.062197) (xy 31.0224 -277.097888) (xy 31.058091 -277.139079)
			(xy 31.087557 -277.184929) (xy 31.110199 -277.234506) (xy 31.125554 -277.286801) (xy 31.13331 -277.340749)
			(xy 31.133796 -277.368) (xy 31.133331 -277.39537) (xy 31.125513 -277.449549) (xy 31.110024 -277.502053)
			(xy 31.087182 -277.551799) (xy 31.057457 -277.597766) (xy 31.039816 -277.618698) (xy 31.03372 -277.62581)
			(xy 31.02737 -277.642828) (xy 31.02737 -277.728172) (xy 31.03372 -277.74519) (xy 31.039816 -277.752302)
			(xy 31.057455 -277.773236) (xy 31.087176 -277.819204) (xy 31.110019 -277.868951) (xy 31.125514 -277.921452)
			(xy 31.133341 -277.97563) (xy 31.133341 -278.03037) (xy 31.125514 -278.084548) (xy 31.110019 -278.137049)
			(xy 31.087176 -278.186796) (xy 31.057455 -278.232764) (xy 31.039816 -278.253698) (xy 31.03372 -278.26081)
			(xy 31.02737 -278.277828) (xy 31.02737 -278.363172) (xy 31.03372 -278.38019) (xy 31.039816 -278.387302)
			(xy 31.057472 -278.40822) (xy 31.087181 -278.454197) (xy 31.110013 -278.503948) (xy 31.1255 -278.556452)
			(xy 31.133324 -278.61063) (xy 31.133796 -278.638) (xy 31.13331 -278.665251) (xy 31.125554 -278.719199)
			(xy 31.112106 -278.765) (xy 35.45078 -278.765) (xy 35.451227 -278.726712) (xy 35.457845 -278.650422)
			(xy 35.470989 -278.574983) (xy 35.490562 -278.50095) (xy 35.503104 -278.464772) (xy 35.505746 -278.456334)
			(xy 35.505746 -278.438666) (xy 35.503104 -278.430228) (xy 35.490547 -278.394054) (xy 35.470951 -278.320024)
			(xy 35.4578 -278.244583) (xy 35.451191 -278.168289) (xy 35.45078 -278.13) (xy 35.451227 -278.091712)
			(xy 35.457845 -278.015422) (xy 35.470989 -277.939983) (xy 35.490562 -277.86595) (xy 35.503104 -277.829772)
			(xy 35.505746 -277.821334) (xy 35.505746 -277.803666) (xy 35.503104 -277.795228) (xy 35.490547 -277.759054)
			(xy 35.470951 -277.685024) (xy 35.4578 -277.609583) (xy 35.451191 -277.533289) (xy 35.45078 -277.495)
			(xy 35.451284 -277.452652) (xy 35.459335 -277.368338) (xy 35.475364 -277.285172) (xy 35.499225 -277.203905)
			(xy 35.530704 -277.125275) (xy 35.569515 -277.049994) (xy 35.615305 -276.978742) (xy 35.667661 -276.912166)
			(xy 35.726109 -276.850868) (xy 35.790119 -276.795403) (xy 35.859111 -276.746274) (xy 35.932461 -276.703925)
			(xy 36.009504 -276.668741) (xy 36.089543 -276.641039) (xy 36.171852 -276.621071) (xy 36.255687 -276.609018)
			(xy 36.340288 -276.604988) (xy 36.424889 -276.609018) (xy 36.508724 -276.621071) (xy 36.591033 -276.641039)
			(xy 36.671072 -276.668741) (xy 36.748115 -276.703925) (xy 36.821465 -276.746274) (xy 36.890457 -276.795403)
			(xy 36.954467 -276.850868) (xy 37.012915 -276.912166) (xy 37.065271 -276.978742) (xy 37.111061 -277.049994)
			(xy 37.149872 -277.125275) (xy 37.181351 -277.203905) (xy 37.205212 -277.285172) (xy 37.221241 -277.368338)
			(xy 37.229292 -277.452652) (xy 37.229796 -277.495) (xy 37.22935 -277.533288) (xy 37.222732 -277.609578)
			(xy 37.209588 -277.685018) (xy 37.190015 -277.75905) (xy 37.177472 -277.795228) (xy 37.174832 -277.803666)
			(xy 37.174832 -277.821334) (xy 37.177472 -277.829772) (xy 37.190028 -277.865947) (xy 37.209625 -277.939976)
			(xy 37.222776 -278.015417) (xy 37.229385 -278.091711) (xy 37.229796 -278.13) (xy 37.22935 -278.168288)
			(xy 37.222732 -278.244578) (xy 37.209588 -278.320018) (xy 37.190015 -278.39405) (xy 37.177472 -278.430228)
			(xy 37.174832 -278.438666) (xy 37.174832 -278.456334) (xy 37.177472 -278.464772) (xy 37.190028 -278.500947)
			(xy 37.209625 -278.574976) (xy 37.222776 -278.650417) (xy 37.229385 -278.726711) (xy 37.229796 -278.765)
			(xy 37.229292 -278.807348) (xy 37.221241 -278.891662) (xy 37.205212 -278.974828) (xy 37.181351 -279.056095)
			(xy 37.149872 -279.134725) (xy 37.111061 -279.210006) (xy 37.065271 -279.281258) (xy 37.012915 -279.347834)
			(xy 36.954467 -279.409132) (xy 36.890457 -279.464597) (xy 36.821465 -279.513726) (xy 36.748115 -279.556075)
			(xy 36.671072 -279.591259) (xy 36.591033 -279.618961) (xy 36.508724 -279.638929) (xy 36.424889 -279.650982)
			(xy 36.340288 -279.655013) (xy 36.255687 -279.650982) (xy 36.171852 -279.638929) (xy 36.089543 -279.618961)
			(xy 36.009504 -279.591259) (xy 35.932461 -279.556075) (xy 35.859111 -279.513726) (xy 35.790119 -279.464597)
			(xy 35.726109 -279.409132) (xy 35.667661 -279.347834) (xy 35.615305 -279.281258) (xy 35.569515 -279.210006)
			(xy 35.530704 -279.134725) (xy 35.499225 -279.056095) (xy 35.475364 -278.974828) (xy 35.459335 -278.891662)
			(xy 35.451284 -278.807348) (xy 35.45078 -278.765) (xy 31.112106 -278.765) (xy 31.110199 -278.771494)
			(xy 31.087557 -278.821071) (xy 31.058091 -278.866921) (xy 31.0224 -278.908112) (xy 30.981209 -278.943803)
			(xy 30.935359 -278.973269) (xy 30.885782 -278.995911) (xy 30.833487 -279.011266) (xy 30.779539 -279.019022)
			(xy 30.725037 -279.019022) (xy 30.671089 -279.011266) (xy 30.618794 -278.995911) (xy 30.569217 -278.973269)
			(xy 30.523367 -278.943803) (xy 30.482176 -278.908112) (xy 30.446485 -278.866921) (xy 30.417019 -278.821071)
			(xy 30.394377 -278.771494) (xy 30.379022 -278.719199) (xy 30.371266 -278.665251) (xy 30.37078 -278.638)
			(xy 30.086808 -278.638) (xy 30.086808 -279.772364) (xy 30.087294 -279.782326) (xy 30.094882 -279.80075)
			(xy 30.10154 -279.808178) (xy 31.385421 -281.092148) (xy 44.946824 -281.092148) (xy 44.947421 -281.045753)
			(xy 44.957062 -280.953465) (xy 44.976253 -280.862681) (xy 45.004788 -280.774387) (xy 45.023024 -280.731722)
			(xy 45.026815 -280.721773) (xy 45.026834 -280.700513) (xy 45.023024 -280.690574) (xy 45.004797 -280.647904)
			(xy 44.976248 -280.559615) (xy 44.95705 -280.468832) (xy 44.947411 -280.376543) (xy 44.946824 -280.330148)
			(xy 44.947298 -280.289045) (xy 44.954879 -280.207188) (xy 44.969981 -280.126381) (xy 44.992475 -280.047312)
			(xy 45.022169 -279.970655) (xy 45.058809 -279.897066) (xy 45.102084 -279.827172) (xy 45.151623 -279.761568)
			(xy 45.207005 -279.700816) (xy 45.267756 -279.645434) (xy 45.333358 -279.595893) (xy 45.403252 -279.552617)
			(xy 45.476841 -279.515975) (xy 45.553496 -279.48628) (xy 45.632565 -279.463785) (xy 45.713373 -279.448681)
			(xy 45.795229 -279.441099) (xy 45.836332 -279.44064) (xy 45.882727 -279.441243) (xy 45.975015 -279.450881)
			(xy 46.065799 -279.470071) (xy 46.154093 -279.498605) (xy 46.196758 -279.51684) (xy 46.206698 -279.52066)
			(xy 46.227966 -279.52066) (xy 46.237906 -279.51684) (xy 46.280565 -279.498588) (xy 46.368858 -279.470045)
			(xy 46.459645 -279.450854) (xy 46.551936 -279.441223) (xy 46.598332 -279.44064) (xy 46.644727 -279.441243)
			(xy 46.737015 -279.450881) (xy 46.827799 -279.470071) (xy 46.916093 -279.498605) (xy 46.958758 -279.51684)
			(xy 46.968698 -279.52066) (xy 46.989966 -279.52066) (xy 46.999906 -279.51684) (xy 47.042565 -279.498588)
			(xy 47.130858 -279.470045) (xy 47.221645 -279.450854) (xy 47.313936 -279.441223) (xy 47.360332 -279.44064)
			(xy 47.401437 -279.441022) (xy 47.483296 -279.44861) (xy 47.564106 -279.463719) (xy 47.643177 -279.48622)
			(xy 47.719835 -279.515921) (xy 47.793425 -279.552568) (xy 47.86332 -279.595849) (xy 47.928923 -279.645395)
			(xy 47.989674 -279.700782) (xy 48.045056 -279.761539) (xy 48.094596 -279.827146) (xy 48.137871 -279.897045)
			(xy 48.174511 -279.970638) (xy 48.204205 -280.047299) (xy 48.226699 -280.126372) (xy 48.241801 -280.207183)
			(xy 48.249382 -280.289043) (xy 48.24984 -280.330148) (xy 48.249245 -280.376543) (xy 48.239604 -280.468831)
			(xy 48.220412 -280.559615) (xy 48.191877 -280.647909) (xy 48.17364 -280.690574) (xy 48.169793 -280.700505)
			(xy 48.169812 -280.721781) (xy 48.17364 -280.731722) (xy 48.19187 -280.77439) (xy 48.220417 -280.862681)
			(xy 48.239614 -280.953464) (xy 48.249252 -281.045752) (xy 48.24984 -281.092148) (xy 48.249379 -281.13325)
			(xy 48.24179 -281.215104) (xy 48.226682 -281.295908) (xy 48.204182 -281.374974) (xy 48.174484 -281.451627)
			(xy 48.13784 -281.525212) (xy 48.094563 -281.595103) (xy 48.045023 -281.660703) (xy 47.989641 -281.721453)
			(xy 47.928891 -281.776833) (xy 47.86329 -281.826373) (xy 47.793398 -281.869648) (xy 47.719812 -281.906291)
			(xy 47.643159 -281.935987) (xy 47.564093 -281.958485) (xy 47.483288 -281.973593) (xy 47.401434 -281.98118)
			(xy 47.360332 -281.981656) (xy 47.313937 -281.981066) (xy 47.221648 -281.971424) (xy 47.130864 -281.95223)
			(xy 47.042571 -281.923693) (xy 46.999906 -281.905456) (xy 46.989966 -281.901636) (xy 46.968698 -281.901636)
			(xy 46.958758 -281.905456) (xy 46.91609 -281.923687) (xy 46.8278 -281.952235) (xy 46.737017 -281.971432)
			(xy 46.644728 -281.981069) (xy 46.598332 -281.981656) (xy 46.551937 -281.981066) (xy 46.459648 -281.971424)
			(xy 46.368864 -281.95223) (xy 46.280571 -281.923693) (xy 46.237906 -281.905456) (xy 46.227966 -281.901636)
			(xy 46.206698 -281.901636) (xy 46.196758 -281.905456) (xy 46.15409 -281.923687) (xy 46.0658 -281.952235)
			(xy 45.975017 -281.971432) (xy 45.882728 -281.981069) (xy 45.836332 -281.981656) (xy 45.795231 -281.981103)
			(xy 45.713381 -281.973521) (xy 45.632579 -281.95842) (xy 45.553515 -281.935928) (xy 45.476863 -281.906236)
			(xy 45.403278 -281.869599) (xy 45.333388 -281.826329) (xy 45.267788 -281.776795) (xy 45.207038 -281.721419)
			(xy 45.151657 -281.660674) (xy 45.102116 -281.595078) (xy 45.05884 -281.525192) (xy 45.022196 -281.45161)
			(xy 44.992498 -281.374961) (xy 44.969998 -281.295899) (xy 44.95489 -281.215099) (xy 44.947301 -281.133249)
			(xy 44.946824 -281.092148) (xy 31.385421 -281.092148) (xy 33.75914 -283.466032) (xy 33.769046 -283.473652)
			(xy 33.792836 -283.488543) (xy 33.836172 -283.524205) (xy 33.873819 -283.565829) (xy 33.904964 -283.612518)
			(xy 33.928936 -283.663264) (xy 33.945218 -283.716973) (xy 33.953459 -283.772489) (xy 33.953958 -283.80055)
			(xy 33.953427 -283.82948) (xy 33.944698 -283.886677) (xy 33.927434 -283.941901) (xy 33.90203 -283.993885)
			(xy 33.869069 -284.041438) (xy 33.829306 -284.083469) (xy 33.783653 -284.119014) (xy 33.758632 -284.133544)
			(xy 33.748218 -284.139386) (xy 33.734756 -284.158944) (xy 33.722056 -284.251146) (xy 33.721064 -284.262927)
			(xy 33.7286 -284.285308) (xy 33.736534 -284.294072) (xy 34.300922 -284.85846) (xy 34.308292 -284.865203)
			(xy 34.326754 -284.872794) (xy 34.336736 -284.873192) (xy 34.925 -284.873192) (xy 34.953975 -284.873747)
			(xy 35.011206 -284.882849) (xy 35.066307 -284.900795) (xy 35.117921 -284.927145) (xy 35.164774 -284.961249)
			(xy 35.185604 -284.981396) (xy 38.711378 -288.50717) (xy 38.73148 -288.52803) (xy 38.765534 -288.574891)
			(xy 38.791837 -288.626504) (xy 38.809743 -288.681595) (xy 38.818809 -288.73881) (xy 38.819328 -288.767774)
			(xy 38.819328 -289.310064) (xy 42.1861 -289.310064) (xy 42.190144 -289.229034) (xy 42.202236 -289.14881)
			(xy 42.222255 -289.070188) (xy 42.250004 -288.99395) (xy 42.285205 -288.920854) (xy 42.327509 -288.851626)
			(xy 42.376496 -288.786954) (xy 42.431679 -288.727482) (xy 42.492509 -288.673799) (xy 42.558382 -288.626439)
			(xy 42.628643 -288.585874) (xy 42.702594 -288.552506) (xy 42.7795 -288.526667) (xy 42.858597 -288.508614)
			(xy 42.939098 -288.498526) (xy 43.020203 -288.496503) (xy 43.101107 -288.502566) (xy 43.181005 -288.516654)
			(xy 43.259103 -288.538627) (xy 43.334625 -288.568268) (xy 43.406821 -288.60528) (xy 43.474973 -288.649297)
			(xy 43.538403 -288.699882) (xy 43.596482 -288.75653) (xy 43.648632 -288.81868) (xy 43.694334 -288.885713)
			(xy 43.733135 -288.956963) (xy 43.764649 -289.031723) (xy 43.788563 -289.109249) (xy 43.804638 -289.188771)
			(xy 43.812716 -289.269499) (xy 43.813222 -289.310064) (xy 44.186096 -289.310064) (xy 44.19014 -289.229034)
			(xy 44.202232 -289.14881) (xy 44.222251 -289.070188) (xy 44.25 -288.99395) (xy 44.285201 -288.920854)
			(xy 44.327505 -288.851626) (xy 44.376492 -288.786954) (xy 44.431675 -288.727482) (xy 44.492505 -288.673799)
			(xy 44.558378 -288.626439) (xy 44.628639 -288.585874) (xy 44.70259 -288.552506) (xy 44.779496 -288.526667)
			(xy 44.858593 -288.508614) (xy 44.939094 -288.498526) (xy 45.020199 -288.496503) (xy 45.101103 -288.502566)
			(xy 45.181001 -288.516654) (xy 45.259099 -288.538627) (xy 45.334621 -288.568268) (xy 45.406817 -288.60528)
			(xy 45.474969 -288.649297) (xy 45.538399 -288.699882) (xy 45.596478 -288.75653) (xy 45.648628 -288.81868)
			(xy 45.69433 -288.885713) (xy 45.733131 -288.956963) (xy 45.764645 -289.031723) (xy 45.788559 -289.109249)
			(xy 45.804634 -289.188771) (xy 45.812712 -289.269499) (xy 45.813218 -289.310064) (xy 45.812712 -289.350629)
			(xy 45.804634 -289.431357) (xy 45.788559 -289.510879) (xy 45.764645 -289.588405) (xy 45.733131 -289.663165)
			(xy 45.69433 -289.734415) (xy 45.648628 -289.801448) (xy 45.596478 -289.863598) (xy 45.538399 -289.920246)
			(xy 45.474969 -289.970831) (xy 45.406817 -290.014848) (xy 45.334621 -290.05186) (xy 45.259099 -290.081501)
			(xy 45.181001 -290.103474) (xy 45.101103 -290.117562) (xy 45.020199 -290.123625) (xy 44.939094 -290.121602)
			(xy 44.858593 -290.111514) (xy 44.779496 -290.093461) (xy 44.70259 -290.067622) (xy 44.628639 -290.034254)
			(xy 44.558378 -289.993689) (xy 44.492505 -289.946329) (xy 44.431675 -289.892646) (xy 44.376492 -289.833174)
			(xy 44.327505 -289.768502) (xy 44.285201 -289.699274) (xy 44.25 -289.626178) (xy 44.222251 -289.54994)
			(xy 44.202232 -289.471318) (xy 44.19014 -289.391094) (xy 44.186096 -289.310064) (xy 43.813222 -289.310064)
			(xy 43.812716 -289.350629) (xy 43.804638 -289.431357) (xy 43.788563 -289.510879) (xy 43.764649 -289.588405)
			(xy 43.733135 -289.663165) (xy 43.694334 -289.734415) (xy 43.648632 -289.801448) (xy 43.596482 -289.863598)
			(xy 43.538403 -289.920246) (xy 43.474973 -289.970831) (xy 43.406821 -290.014848) (xy 43.334625 -290.05186)
			(xy 43.259103 -290.081501) (xy 43.181005 -290.103474) (xy 43.101107 -290.117562) (xy 43.020203 -290.123625)
			(xy 42.939098 -290.121602) (xy 42.858597 -290.111514) (xy 42.7795 -290.093461) (xy 42.702594 -290.067622)
			(xy 42.628643 -290.034254) (xy 42.558382 -289.993689) (xy 42.492509 -289.946329) (xy 42.431679 -289.892646)
			(xy 42.376496 -289.833174) (xy 42.327509 -289.768502) (xy 42.285205 -289.699274) (xy 42.250004 -289.626178)
			(xy 42.222255 -289.54994) (xy 42.202236 -289.471318) (xy 42.190144 -289.391094) (xy 42.1861 -289.310064)
			(xy 38.819328 -289.310064) (xy 38.819328 -291.31006) (xy 42.1861 -291.31006) (xy 42.190144 -291.22903)
			(xy 42.202236 -291.148806) (xy 42.222255 -291.070184) (xy 42.250004 -290.993946) (xy 42.285205 -290.92085)
			(xy 42.327509 -290.851622) (xy 42.376496 -290.78695) (xy 42.431679 -290.727478) (xy 42.492509 -290.673795)
			(xy 42.558382 -290.626435) (xy 42.628643 -290.58587) (xy 42.702594 -290.552502) (xy 42.7795 -290.526663)
			(xy 42.858597 -290.50861) (xy 42.939098 -290.498522) (xy 43.020203 -290.496499) (xy 43.101107 -290.502562)
			(xy 43.181005 -290.51665) (xy 43.259103 -290.538623) (xy 43.334625 -290.568264) (xy 43.406821 -290.605276)
			(xy 43.474973 -290.649293) (xy 43.538403 -290.699878) (xy 43.596482 -290.756526) (xy 43.648632 -290.818676)
			(xy 43.694334 -290.885709) (xy 43.733135 -290.956959) (xy 43.764649 -291.031719) (xy 43.788563 -291.109245)
			(xy 43.804638 -291.188767) (xy 43.812716 -291.269495) (xy 43.813222 -291.31006) (xy 43.812716 -291.350625)
			(xy 43.804638 -291.431353) (xy 43.788563 -291.510875) (xy 43.764649 -291.588401) (xy 43.733135 -291.663161)
			(xy 43.694334 -291.734411) (xy 43.648632 -291.801444) (xy 43.596482 -291.863594) (xy 43.538403 -291.920242)
			(xy 43.474973 -291.970827) (xy 43.406821 -292.014844) (xy 43.334625 -292.051856) (xy 43.259103 -292.081497)
			(xy 43.181005 -292.10347) (xy 43.101107 -292.117558) (xy 43.020203 -292.123621) (xy 42.939098 -292.121598)
			(xy 42.858597 -292.11151) (xy 42.7795 -292.093457) (xy 42.702594 -292.067618) (xy 42.628643 -292.03425)
			(xy 42.558382 -291.993685) (xy 42.492509 -291.946325) (xy 42.431679 -291.892642) (xy 42.376496 -291.83317)
			(xy 42.327509 -291.768498) (xy 42.285205 -291.69927) (xy 42.250004 -291.626174) (xy 42.222255 -291.549936)
			(xy 42.202236 -291.471314) (xy 42.190144 -291.39109) (xy 42.1861 -291.31006) (xy 38.819328 -291.31006)
			(xy 38.819328 -296.976038) (xy 38.819873 -296.986022) (xy 38.827599 -297.004441) (xy 38.834314 -297.011852)
			(xy 39.383424 -297.561) (xy 41.274492 -297.561) (xy 41.274978 -297.533749) (xy 41.282734 -297.479801)
			(xy 41.298089 -297.427506) (xy 41.320731 -297.377929) (xy 41.350197 -297.332079) (xy 41.385888 -297.290888)
			(xy 41.427079 -297.255197) (xy 41.472929 -297.225731) (xy 41.522506 -297.203089) (xy 41.574801 -297.187734)
			(xy 41.628749 -297.179978) (xy 41.656 -297.179492) (xy 41.684061 -297.180006) (xy 41.739577 -297.188241)
			(xy 41.793287 -297.204519) (xy 41.844034 -297.228487) (xy 41.890723 -297.259631) (xy 41.932347 -297.297277)
			(xy 41.968008 -297.340614) (xy 41.982898 -297.364404) (xy 41.9862 -297.369738) (xy 42.013378 -297.396916)
			(xy 42.020761 -297.403793) (xy 42.039394 -297.411498) (xy 42.059557 -297.411387) (xy 42.069004 -297.407838)
			(xy 42.170096 -297.364912) (xy 42.18686 -297.339004) (xy 42.186606 -297.32351) (xy 42.186606 -297.310048)
			(xy 42.187061 -297.270435) (xy 42.194767 -297.191583) (xy 42.210102 -297.113855) (xy 42.232918 -297.037985)
			(xy 42.263002 -296.964692) (xy 42.300067 -296.89467) (xy 42.343764 -296.828583) (xy 42.393677 -296.767056)
			(xy 42.449334 -296.710672) (xy 42.479468 -296.684954) (xy 42.489628 -296.676572) (xy 42.499026 -296.652188)
			(xy 42.48404 -296.540682) (xy 42.468292 -296.519854) (xy 42.456354 -296.514266) (xy 42.408932 -296.492306)
			(xy 42.317358 -296.44193) (xy 42.230052 -296.384477) (xy 42.147559 -296.320303) (xy 42.070394 -296.249812)
			(xy 41.999041 -296.173444) (xy 41.933945 -296.091677) (xy 41.875514 -296.005021) (xy 41.824113 -295.914019)
			(xy 41.780064 -295.81924) (xy 41.743642 -295.721277) (xy 41.715075 -295.620742) (xy 41.694541 -295.518264)
			(xy 41.682169 -295.414484) (xy 41.678036 -295.310051) (xy 41.682169 -295.205618) (xy 41.694541 -295.101838)
			(xy 41.715074 -294.99936) (xy 41.743642 -294.898825) (xy 41.780064 -294.800861) (xy 41.824113 -294.706082)
			(xy 41.875513 -294.61508) (xy 41.933944 -294.528425) (xy 41.99904 -294.446657) (xy 42.070393 -294.370289)
			(xy 42.147557 -294.299798) (xy 42.230051 -294.235624) (xy 42.317357 -294.17817) (xy 42.40893 -294.127795)
			(xy 42.456354 -294.105838) (xy 42.468292 -294.10025) (xy 42.48404 -294.079422) (xy 42.499026 -293.967916)
			(xy 42.489628 -293.943532) (xy 42.479468 -293.93515) (xy 42.449323 -293.909446) (xy 42.393665 -293.853061)
			(xy 42.343752 -293.791533) (xy 42.300057 -293.725444) (xy 42.262995 -293.655421) (xy 42.232915 -293.582125)
			(xy 42.210103 -293.506253) (xy 42.194776 -293.428522) (xy 42.187078 -293.34967) (xy 42.186606 -293.310056)
			(xy 42.18704 -293.270124) (xy 42.194872 -293.190644) (xy 42.210457 -293.112314) (xy 42.233644 -293.035889)
			(xy 42.26421 -292.962105) (xy 42.301861 -292.891672) (xy 42.346235 -292.825269) (xy 42.396903 -292.763535)
			(xy 42.453378 -292.707064) (xy 42.515116 -292.6564) (xy 42.581522 -292.612031) (xy 42.651958 -292.574385)
			(xy 42.725744 -292.543824) (xy 42.802171 -292.520643) (xy 42.880501 -292.505064) (xy 42.959982 -292.497237)
			(xy 42.999914 -292.496748) (xy 43.039527 -292.497216) (xy 43.118378 -292.504919) (xy 43.196107 -292.52025)
			(xy 43.271978 -292.543065) (xy 43.345271 -292.573146) (xy 43.415293 -292.610211) (xy 43.48138 -292.653906)
			(xy 43.542907 -292.703819) (xy 43.599291 -292.759476) (xy 43.625008 -292.78961) (xy 43.63339 -292.79977)
			(xy 43.657774 -292.809168) (xy 43.76928 -292.794182) (xy 43.790108 -292.778434) (xy 43.795696 -292.766496)
			(xy 43.817985 -292.718341) (xy 43.869267 -292.625432) (xy 43.927837 -292.536937) (xy 43.993317 -292.453425)
			(xy 44.065286 -292.375436) (xy 44.14328 -292.303471) (xy 44.226795 -292.237995) (xy 44.315293 -292.17943)
			(xy 44.408205 -292.128153) (xy 44.45635 -292.105842) (xy 44.468288 -292.100254) (xy 44.484036 -292.079426)
			(xy 44.499022 -291.96792) (xy 44.489624 -291.943536) (xy 44.479464 -291.935154) (xy 44.44932 -291.909448)
			(xy 44.393662 -291.853064) (xy 44.343749 -291.791536) (xy 44.300054 -291.725447) (xy 44.262992 -291.655424)
			(xy 44.232912 -291.582129) (xy 44.2101 -291.506257) (xy 44.194772 -291.428526) (xy 44.187074 -291.349674)
			(xy 44.186602 -291.31006) (xy 44.187092 -291.270129) (xy 44.19492 -291.190651) (xy 44.2105 -291.112323)
			(xy 44.233683 -291.0359) (xy 44.264245 -290.962116) (xy 44.301892 -290.891684) (xy 44.346261 -290.825281)
			(xy 44.396925 -290.763546) (xy 44.453396 -290.707075) (xy 44.515131 -290.656411) (xy 44.581534 -290.612042)
			(xy 44.651966 -290.574395) (xy 44.72575 -290.543833) (xy 44.802173 -290.52065) (xy 44.880501 -290.50507)
			(xy 44.959979 -290.497242) (xy 45.039841 -290.497242) (xy 45.119319 -290.50507) (xy 45.197647 -290.52065)
			(xy 45.27407 -290.543833) (xy 45.347854 -290.574395) (xy 45.418286 -290.612042) (xy 45.484689 -290.656411)
			(xy 45.546424 -290.707075) (xy 45.602895 -290.763546) (xy 45.653559 -290.825281) (xy 45.697928 -290.891684)
			(xy 45.735575 -290.962116) (xy 45.766137 -291.0359) (xy 45.78932 -291.112323) (xy 45.8049 -291.190651)
			(xy 45.812728 -291.270129) (xy 45.813218 -291.31006) (xy 45.81276 -291.349673) (xy 45.805053 -291.428524)
			(xy 45.789719 -291.506252) (xy 45.766902 -291.582122) (xy 45.736819 -291.655415) (xy 45.699754 -291.725437)
			(xy 45.656058 -291.791524) (xy 45.606146 -291.853052) (xy 45.550489 -291.909436) (xy 45.520356 -291.935154)
			(xy 45.510196 -291.943536) (xy 45.500798 -291.96792) (xy 45.515784 -292.079426) (xy 45.531532 -292.100254)
			(xy 45.54347 -292.105842) (xy 45.59089 -292.127805) (xy 45.682464 -292.178181) (xy 45.76977 -292.235635)
			(xy 45.852263 -292.299808) (xy 45.929427 -292.370299) (xy 46.00078 -292.446667) (xy 46.065876 -292.528434)
			(xy 46.124306 -292.61509) (xy 46.175707 -292.706091) (xy 46.219756 -292.80087) (xy 46.256178 -292.898833)
			(xy 46.284745 -292.999368) (xy 46.305279 -293.101846) (xy 46.317651 -293.205625) (xy 46.321783 -293.310058)
			(xy 46.317651 -293.414491) (xy 46.305279 -293.518271) (xy 46.284746 -293.620749) (xy 46.256179 -293.721284)
			(xy 46.219757 -293.819247) (xy 46.175708 -293.914026) (xy 46.124308 -294.005027) (xy 46.065878 -294.091683)
			(xy 46.000782 -294.173451) (xy 45.92943 -294.249819) (xy 45.852265 -294.32031) (xy 45.769772 -294.384483)
			(xy 45.682466 -294.441937) (xy 45.590893 -294.492313) (xy 45.54347 -294.51427) (xy 45.531532 -294.519858)
			(xy 45.515784 -294.540686) (xy 45.500798 -294.652192) (xy 45.510196 -294.676576) (xy 45.520356 -294.684958)
			(xy 45.55051 -294.710652) (xy 45.606167 -294.767038) (xy 45.656079 -294.828568) (xy 45.699772 -294.894658)
			(xy 45.736834 -294.964684) (xy 45.766912 -295.03798) (xy 45.789723 -295.113853) (xy 45.805049 -295.191585)
			(xy 45.812747 -295.270438) (xy 45.813218 -295.310052) (xy 45.812688 -295.349983) (xy 45.804865 -295.42946)
			(xy 45.789289 -295.507788) (xy 45.76611 -295.584212) (xy 45.735552 -295.657996) (xy 45.697908 -295.728429)
			(xy 45.653542 -295.794834) (xy 45.602881 -295.856569) (xy 45.546412 -295.913042) (xy 45.48468 -295.963708)
			(xy 45.418279 -296.008079) (xy 45.347849 -296.045727) (xy 45.274067 -296.07629) (xy 45.197644 -296.099475)
			(xy 45.119318 -296.115056) (xy 45.039841 -296.122885) (xy 44.99991 -296.12336) (xy 44.960297 -296.122872)
			(xy 44.881447 -296.115172) (xy 44.803719 -296.099843) (xy 44.727849 -296.077031) (xy 44.654555 -296.046951)
			(xy 44.584533 -296.009889) (xy 44.518445 -295.966196) (xy 44.456918 -295.916286) (xy 44.400534 -295.860631)
			(xy 44.374816 -295.830498) (xy 44.366434 -295.820338) (xy 44.34205 -295.81094) (xy 44.230544 -295.825926)
			(xy 44.209716 -295.841674) (xy 44.204128 -295.853612) (xy 44.18179 -295.901744) (xy 44.130515 -295.994654)
			(xy 44.071952 -296.083152) (xy 44.006479 -296.166666) (xy 43.934516 -296.244658) (xy 43.856528 -296.316625)
			(xy 43.773018 -296.382104) (xy 43.684524 -296.440673) (xy 43.591617 -296.491953) (xy 43.543474 -296.514266)
			(xy 43.531536 -296.519854) (xy 43.515788 -296.540682) (xy 43.500802 -296.652188) (xy 43.5102 -296.676572)
			(xy 43.52036 -296.684954) (xy 43.550513 -296.710649) (xy 43.60617 -296.767035) (xy 43.656082 -296.828565)
			(xy 43.699775 -296.894655) (xy 43.736837 -296.96468) (xy 43.766915 -297.037976) (xy 43.789726 -297.11385)
			(xy 43.805053 -297.191581) (xy 43.81275 -297.270434) (xy 43.813222 -297.310048) (xy 43.812708 -297.350775)
			(xy 43.804538 -297.431819) (xy 43.788315 -297.511642) (xy 43.7642 -297.589445) (xy 43.732435 -297.664451)
			(xy 43.693338 -297.73591) (xy 43.670728 -297.769788) (xy 43.662854 -297.781472) (xy 43.661076 -297.809666)
			(xy 43.70959 -297.901868) (xy 43.714249 -297.909826) (xy 43.728075 -297.922002) (xy 43.745334 -297.92845)
			(xy 43.754548 -297.928792) (xy 43.838622 -297.928792) (xy 43.848594 -297.928356) (xy 43.86703 -297.920754)
			(xy 43.874436 -297.91406) (xy 44.214796 -297.5737) (xy 44.221654 -297.54703) (xy 44.217844 -297.533568)
			(xy 44.207896 -297.497156) (xy 44.19399 -297.422959) (xy 44.187019 -297.347793) (xy 44.186602 -297.310048)
			(xy 44.187092 -297.270117) (xy 44.19492 -297.190639) (xy 44.2105 -297.112311) (xy 44.233683 -297.035888)
			(xy 44.264245 -296.962104) (xy 44.301892 -296.891672) (xy 44.346261 -296.825269) (xy 44.396925 -296.763534)
			(xy 44.453396 -296.707063) (xy 44.515131 -296.656399) (xy 44.581534 -296.61203) (xy 44.651966 -296.574383)
			(xy 44.72575 -296.543821) (xy 44.802173 -296.520638) (xy 44.880501 -296.505058) (xy 44.959979 -296.49723)
			(xy 45.039841 -296.49723) (xy 45.119319 -296.505058) (xy 45.197647 -296.520638) (xy 45.27407 -296.543821)
			(xy 45.347854 -296.574383) (xy 45.418286 -296.61203) (xy 45.484689 -296.656399) (xy 45.546424 -296.707063)
			(xy 45.602895 -296.763534) (xy 45.653559 -296.825269) (xy 45.697928 -296.891672) (xy 45.735575 -296.962104)
			(xy 45.766137 -297.035888) (xy 45.78932 -297.112311) (xy 45.8049 -297.190639) (xy 45.812728 -297.270117)
			(xy 45.813218 -297.310048) (xy 45.812751 -297.349661) (xy 45.805046 -297.428512) (xy 45.789712 -297.50624)
			(xy 45.766897 -297.582109) (xy 45.736814 -297.655402) (xy 45.69975 -297.725424) (xy 45.656056 -297.791512)
			(xy 45.606145 -297.853039) (xy 45.550489 -297.909424) (xy 45.520356 -297.935142) (xy 45.510196 -297.943524)
			(xy 45.500798 -297.967908) (xy 45.515784 -298.079414) (xy 45.531532 -298.100242) (xy 45.54347 -298.10583)
			(xy 45.590897 -298.12778) (xy 45.68247 -298.178156) (xy 45.769777 -298.235611) (xy 45.85227 -298.299785)
			(xy 45.929435 -298.370276) (xy 46.000788 -298.446645) (xy 46.065883 -298.528413) (xy 46.124314 -298.615069)
			(xy 46.175715 -298.706071) (xy 46.219764 -298.80085) (xy 46.256186 -298.898814) (xy 46.284753 -298.999349)
			(xy 46.305287 -299.101828) (xy 46.317658 -299.205608) (xy 46.321791 -299.310042) (xy 46.317658 -299.414475)
			(xy 46.305286 -299.518256) (xy 46.284752 -299.620734) (xy 46.256185 -299.721269) (xy 46.219763 -299.819233)
			(xy 46.175713 -299.914012) (xy 46.124312 -300.005014) (xy 46.065881 -300.09167) (xy 46.000786 -300.173438)
			(xy 45.929432 -300.249806) (xy 45.852268 -300.320298) (xy 45.769774 -300.384471) (xy 45.682467 -300.441925)
			(xy 45.590894 -300.492301) (xy 45.54347 -300.514258) (xy 45.531532 -300.519846) (xy 45.515784 -300.540674)
			(xy 45.500798 -300.65218) (xy 45.510196 -300.676564) (xy 45.520356 -300.684946) (xy 45.550504 -300.710647)
			(xy 45.606161 -300.767032) (xy 45.656073 -300.828561) (xy 45.699768 -300.89465) (xy 45.73683 -300.964675)
			(xy 45.766909 -301.03797) (xy 45.78972 -301.113843) (xy 45.805048 -301.191574) (xy 45.812746 -301.270426)
			(xy 45.813218 -301.31004) (xy 45.812728 -301.349971) (xy 45.8049 -301.429449) (xy 45.78932 -301.507777)
			(xy 45.766137 -301.5842) (xy 45.735575 -301.657984) (xy 45.697928 -301.728416) (xy 45.653559 -301.794819)
			(xy 45.602895 -301.856554) (xy 45.546424 -301.913025) (xy 45.484689 -301.963689) (xy 45.418286 -302.008058)
			(xy 45.347854 -302.045705) (xy 45.27407 -302.076267) (xy 45.197647 -302.09945) (xy 45.119319 -302.11503)
			(xy 45.039841 -302.122858) (xy 44.959979 -302.122858) (xy 44.880501 -302.11503) (xy 44.802173 -302.09945)
			(xy 44.72575 -302.076267) (xy 44.651966 -302.045705) (xy 44.581534 -302.008058) (xy 44.515131 -301.963689)
			(xy 44.453396 -301.913025) (xy 44.396925 -301.856554) (xy 44.346261 -301.794819) (xy 44.301892 -301.728416)
			(xy 44.264245 -301.657984) (xy 44.233683 -301.5842) (xy 44.2105 -301.507777) (xy 44.19492 -301.429449)
			(xy 44.187092 -301.349971) (xy 44.186602 -301.31004) (xy 44.187053 -301.270427) (xy 44.19476 -301.191575)
			(xy 44.210095 -301.113846) (xy 44.232912 -301.037976) (xy 44.262996 -300.964683) (xy 44.300062 -300.894662)
			(xy 44.343759 -300.828574) (xy 44.393672 -300.767047) (xy 44.44933 -300.710664) (xy 44.479464 -300.684946)
			(xy 44.489624 -300.676564) (xy 44.499022 -300.65218) (xy 44.484036 -300.540674) (xy 44.468288 -300.519846)
			(xy 44.45635 -300.514258) (xy 44.408217 -300.491922) (xy 44.315307 -300.440647) (xy 44.22681 -300.382083)
			(xy 44.143297 -300.316608) (xy 44.065305 -300.244645) (xy 43.993338 -300.166657) (xy 43.927859 -300.083147)
			(xy 43.86929 -299.994654) (xy 43.81801 -299.901747) (xy 43.795696 -299.853604) (xy 43.790108 -299.841666)
			(xy 43.76928 -299.825918) (xy 43.657774 -299.810932) (xy 43.63339 -299.82033) (xy 43.625008 -299.83049)
			(xy 43.599286 -299.860619) (xy 43.542903 -299.916276) (xy 43.481376 -299.966188) (xy 43.415289 -300.009883)
			(xy 43.345268 -300.046947) (xy 43.271975 -300.077029) (xy 43.196106 -300.099843) (xy 43.118377 -300.115175)
			(xy 43.039527 -300.122877) (xy 42.999914 -300.123352) (xy 42.959984 -300.122805) (xy 42.88051 -300.114979)
			(xy 42.802185 -300.099401) (xy 42.725764 -300.076221) (xy 42.651983 -300.045662) (xy 42.581552 -300.008019)
			(xy 42.51515 -299.963653) (xy 42.453417 -299.912993) (xy 42.396946 -299.856526) (xy 42.346281 -299.794796)
			(xy 42.301911 -299.728398) (xy 42.264263 -299.65797) (xy 42.233699 -299.584191) (xy 42.210513 -299.507772)
			(xy 42.19493 -299.429448) (xy 42.187098 -299.349974) (xy 42.186606 -299.310044) (xy 42.187052 -299.271993)
			(xy 42.194185 -299.196226) (xy 42.208365 -299.121457) (xy 42.229468 -299.048339) (xy 42.257308 -298.977513)
			(xy 42.291644 -298.909597) (xy 42.332174 -298.845185) (xy 42.355008 -298.814744) (xy 42.362628 -298.804584)
			(xy 42.366692 -298.779184) (xy 42.330878 -298.675044) (xy 42.312336 -298.657772) (xy 42.29989 -298.65447)
			(xy 42.276297 -298.647895) (xy 42.230955 -298.629383) (xy 42.188466 -298.605026) (xy 42.149579 -298.575252)
			(xy 42.131996 -298.558204) (xy 41.464738 -297.8912) (xy 41.459404 -297.887898) (xy 41.435632 -297.872977)
			(xy 41.392279 -297.837334) (xy 41.354619 -297.795721) (xy 41.323466 -297.749037) (xy 41.299493 -297.698291)
			(xy 41.283217 -297.644579) (xy 41.27499 -297.589062) (xy 41.274492 -297.561) (xy 39.383424 -297.561)
			(xy 42.476928 -300.65472) (xy 42.513758 -300.657768) (xy 42.528998 -300.646846) (xy 42.563427 -300.623027)
			(xy 42.636307 -300.581814) (xy 42.713037 -300.548314) (xy 42.792806 -300.522881) (xy 42.874767 -300.505786)
			(xy 42.958051 -300.497209) (xy 42.999914 -300.496732) (xy 43.039845 -300.497222) (xy 43.119323 -300.50505)
			(xy 43.19765 -300.520631) (xy 43.274073 -300.543814) (xy 43.347856 -300.574376) (xy 43.418288 -300.612023)
			(xy 43.484691 -300.656392) (xy 43.546425 -300.707057) (xy 43.602896 -300.763528) (xy 43.65356 -300.825262)
			(xy 43.697929 -300.891665) (xy 43.735576 -300.962097) (xy 43.766137 -301.03588) (xy 43.78932 -301.112304)
			(xy 43.8049 -301.190631) (xy 43.812728 -301.270109) (xy 43.812728 -301.349971) (xy 43.8049 -301.429449)
			(xy 43.78932 -301.507776) (xy 43.766137 -301.5842) (xy 43.735576 -301.657983) (xy 43.697929 -301.728415)
			(xy 43.65356 -301.794818) (xy 43.602896 -301.856552) (xy 43.546425 -301.913023) (xy 43.484691 -301.963688)
			(xy 43.418288 -302.008057) (xy 43.347856 -302.045704) (xy 43.274073 -302.076266) (xy 43.19765 -302.099449)
			(xy 43.119323 -302.11503) (xy 43.039845 -302.122858) (xy 42.999914 -302.123348) (xy 42.958574 -302.122838)
			(xy 42.876321 -302.114451) (xy 42.795343 -302.097763) (xy 42.716477 -302.072945) (xy 42.640535 -302.040254)
			(xy 42.568301 -302.000026) (xy 42.500522 -301.952678) (xy 42.437896 -301.898698) (xy 42.381069 -301.838642)
			(xy 42.330629 -301.773131) (xy 42.287096 -301.702841) (xy 42.250918 -301.628496) (xy 42.22247 -301.550865)
			(xy 42.202044 -301.470748) (xy 42.195496 -301.429928) (xy 42.194226 -301.4218) (xy 42.187114 -301.407576)
			(xy 38.330124 -297.550586) (xy 38.322726 -297.543742) (xy 38.304126 -297.536022) (xy 38.294056 -297.5356)
			(xy 37.905944 -297.5356) (xy 37.895878 -297.536034) (xy 37.877289 -297.543762) (xy 37.869876 -297.550586)
			(xy 36.5252 -298.895262) (xy 36.521898 -298.900596) (xy 36.507008 -298.924386) (xy 36.471347 -298.967723)
			(xy 36.429723 -299.005369) (xy 36.383034 -299.036513) (xy 36.332287 -299.060481) (xy 36.278577 -299.076759)
			(xy 36.223061 -299.084994) (xy 36.195 -299.085508) (xy 36.167749 -299.085022) (xy 36.113801 -299.077266)
			(xy 36.061506 -299.061911) (xy 36.011929 -299.039269) (xy 35.966079 -299.009803) (xy 35.924888 -298.974112)
			(xy 35.889197 -298.932921) (xy 35.859731 -298.887071) (xy 35.837089 -298.837494) (xy 35.821734 -298.785199)
			(xy 35.813978 -298.731251) (xy 35.813492 -298.704) (xy 35.81399 -298.675938) (xy 35.822217 -298.620421)
			(xy 35.838493 -298.566709) (xy 35.862466 -298.515963) (xy 35.893619 -298.469279) (xy 35.931279 -298.427666)
			(xy 35.974632 -298.392023) (xy 35.998404 -298.377102) (xy 36.003738 -298.3738) (xy 36.850828 -297.52671)
			(xy 36.857537 -297.519276) (xy 36.86516 -297.500781) (xy 36.865152 -297.480776) (xy 36.857512 -297.462288)
			(xy 36.850828 -297.454828) (xy 36.794186 -297.398186) (xy 36.787332 -297.390791) (xy 36.77959 -297.372192)
			(xy 36.7792 -297.362118) (xy 36.7792 -297.226482) (xy 36.779627 -297.216413) (xy 36.787346 -297.197814)
			(xy 36.794186 -297.190414) (xy 37.381434 -296.603166) (xy 37.388246 -296.595822) (xy 37.395977 -296.577359)
			(xy 37.39642 -296.567352) (xy 37.39642 -294.586406) (xy 37.395977 -294.576297) (xy 37.388201 -294.557633)
			(xy 37.373871 -294.543368) (xy 37.36467 -294.539162) (xy 37.262816 -294.498014) (xy 37.23259 -294.504364)
			(xy 37.221668 -294.51554) (xy 37.217604 -294.519604) (xy 36.5252 -295.212262) (xy 36.521898 -295.217596)
			(xy 36.507008 -295.241386) (xy 36.471347 -295.284723) (xy 36.429723 -295.322369) (xy 36.383034 -295.353513)
			(xy 36.332287 -295.377481) (xy 36.278577 -295.393759) (xy 36.223061 -295.401994) (xy 36.195 -295.402508)
			(xy 36.167749 -295.402022) (xy 36.113801 -295.394266) (xy 36.061506 -295.378911) (xy 36.011929 -295.356269)
			(xy 35.966079 -295.326803) (xy 35.924888 -295.291112) (xy 35.889197 -295.249921) (xy 35.859731 -295.204071)
			(xy 35.837089 -295.154494) (xy 35.821734 -295.102199) (xy 35.813978 -295.048251) (xy 35.813492 -295.021)
			(xy 35.81399 -294.992938) (xy 35.822217 -294.937421) (xy 35.838493 -294.883709) (xy 35.862466 -294.832963)
			(xy 35.893619 -294.786279) (xy 35.931279 -294.744666) (xy 35.974632 -294.709023) (xy 35.998404 -294.694102)
			(xy 36.00831 -294.686482) (xy 36.57346 -294.121078) (xy 36.580203 -294.113708) (xy 36.587794 -294.095246)
			(xy 36.588192 -294.085264) (xy 36.588192 -292.776656) (xy 36.587832 -292.76786) (xy 36.581895 -292.751301)
			(xy 36.570701 -292.737731) (xy 36.5633 -292.732968) (xy 36.476178 -292.68166) (xy 36.449254 -292.681152)
			(xy 36.43757 -292.687756) (xy 36.409089 -292.702779) (xy 36.348329 -292.724088) (xy 36.284852 -292.734875)
			(xy 36.252658 -292.735508) (xy 36.225409 -292.735019) (xy 36.171466 -292.727258) (xy 36.119176 -292.711899)
			(xy 36.069604 -292.689256) (xy 36.023759 -292.659788) (xy 35.982574 -292.624097) (xy 35.946887 -292.582908)
			(xy 35.917424 -292.537059) (xy 35.894786 -292.487485) (xy 35.879433 -292.435193) (xy 35.871678 -292.381249)
			(xy 35.871678 -292.326751) (xy 35.879433 -292.272807) (xy 35.894786 -292.220515) (xy 35.917424 -292.170941)
			(xy 35.946887 -292.125092) (xy 35.982574 -292.083903) (xy 36.023759 -292.048212) (xy 36.069604 -292.018744)
			(xy 36.119176 -291.996101) (xy 36.171466 -291.980742) (xy 36.225409 -291.972981) (xy 36.252658 -291.972492)
			(xy 36.284849 -291.973161) (xy 36.348321 -291.983955) (xy 36.409088 -292.005229) (xy 36.43757 -292.020244)
			(xy 36.449254 -292.026848) (xy 36.476178 -292.02634) (xy 36.5633 -291.975032) (xy 36.570678 -291.970234)
			(xy 36.581887 -291.956682) (xy 36.58785 -291.940137) (xy 36.588192 -291.931344) (xy 36.588192 -290.306252)
			(xy 36.587709 -290.296289) (xy 36.580125 -290.27786) (xy 36.57346 -290.270438) (xy 36.44773 -290.144454)
			(xy 36.439378 -290.136982) (xy 36.418288 -290.129484) (xy 36.40709 -290.129976) (xy 36.31819 -290.13785)
			(xy 36.298632 -290.14928) (xy 36.292282 -290.158424) (xy 36.276937 -290.179774) (xy 36.241323 -290.218452)
			(xy 36.200737 -290.251875) (xy 36.155947 -290.279411) (xy 36.107801 -290.300538) (xy 36.057211 -290.314855)
			(xy 36.005134 -290.322092) (xy 35.978846 -290.322508) (xy 35.951591 -290.322048) (xy 35.897635 -290.314296)
			(xy 35.845332 -290.298944) (xy 35.795746 -290.276304) (xy 35.749887 -290.246837) (xy 35.708689 -290.211144)
			(xy 35.67299 -290.16995) (xy 35.643518 -290.124095) (xy 35.620872 -290.074511) (xy 35.605514 -290.02221)
			(xy 35.597755 -289.968255) (xy 35.597338 -289.941) (xy 35.597779 -289.914712) (xy 35.605001 -289.862634)
			(xy 35.619309 -289.812042) (xy 35.640431 -289.763895) (xy 35.667967 -289.719106) (xy 35.701394 -289.678524)
			(xy 35.740079 -289.642919) (xy 35.761422 -289.627564) (xy 35.770566 -289.621214) (xy 35.781996 -289.601656)
			(xy 35.78987 -289.512756) (xy 35.790347 -289.501565) (xy 35.782832 -289.480491) (xy 35.775392 -289.472116)
			(xy 30.823408 -284.520386) (xy 30.816014 -284.513529) (xy 30.797415 -284.505778) (xy 30.78734 -284.5054)
			(xy 30.272482 -284.5054) (xy 30.262413 -284.505827) (xy 30.243814 -284.513546) (xy 30.236414 -284.520386)
			(xy 30.10154 -284.65526) (xy 30.094845 -284.662666) (xy 30.087242 -284.681102) (xy 30.086808 -284.691074)
			(xy 30.086808 -286.61995) (xy 30.351982 -286.61995) (xy 30.356053 -286.564328) (xy 30.368179 -286.509891)
			(xy 30.388102 -286.4578) (xy 30.415398 -286.409165) (xy 30.449484 -286.365022) (xy 30.489633 -286.326313)
			(xy 30.534991 -286.293862) (xy 30.584591 -286.268361) (xy 30.637375 -286.250354) (xy 30.692218 -286.240224)
			(xy 30.747952 -286.238187) (xy 30.803389 -286.244287) (xy 30.857346 -286.258393) (xy 30.908675 -286.280205)
			(xy 30.956281 -286.309259) (xy 30.999149 -286.344934) (xy 31.036366 -286.386471) (xy 31.067139 -286.432984)
			(xy 31.090811 -286.483481) (xy 31.106879 -286.536888) (xy 31.114999 -286.592064) (xy 31.115508 -286.61995)
			(xy 31.114999 -286.647836) (xy 31.106879 -286.703012) (xy 31.090811 -286.756419) (xy 31.08632 -286.766)
			(xy 31.748982 -286.766) (xy 31.753053 -286.710378) (xy 31.765179 -286.655941) (xy 31.785102 -286.60385)
			(xy 31.812398 -286.555215) (xy 31.846484 -286.511072) (xy 31.886633 -286.472363) (xy 31.931991 -286.439912)
			(xy 31.981591 -286.414411) (xy 32.034375 -286.396404) (xy 32.089218 -286.386274) (xy 32.144952 -286.384237)
			(xy 32.200389 -286.390337) (xy 32.254346 -286.404443) (xy 32.305675 -286.426255) (xy 32.353281 -286.455309)
			(xy 32.396149 -286.490984) (xy 32.433366 -286.532521) (xy 32.464139 -286.579034) (xy 32.487811 -286.629531)
			(xy 32.503879 -286.682938) (xy 32.511999 -286.738114) (xy 32.512508 -286.766) (xy 32.511999 -286.793886)
			(xy 32.503879 -286.849062) (xy 32.487811 -286.902469) (xy 32.464139 -286.952966) (xy 32.433366 -286.999479)
			(xy 32.396149 -287.041016) (xy 32.353281 -287.076691) (xy 32.305675 -287.105745) (xy 32.254346 -287.127557)
			(xy 32.200389 -287.141663) (xy 32.144952 -287.147763) (xy 32.089218 -287.145726) (xy 32.034375 -287.135596)
			(xy 31.981591 -287.117589) (xy 31.931991 -287.092088) (xy 31.886633 -287.059637) (xy 31.846484 -287.020928)
			(xy 31.812398 -286.976785) (xy 31.785102 -286.92815) (xy 31.765179 -286.876059) (xy 31.753053 -286.821622)
			(xy 31.748982 -286.766) (xy 31.08632 -286.766) (xy 31.067139 -286.806916) (xy 31.036366 -286.853429)
			(xy 30.999149 -286.894966) (xy 30.956281 -286.930641) (xy 30.908675 -286.959695) (xy 30.857346 -286.981507)
			(xy 30.803389 -286.995613) (xy 30.747952 -287.001713) (xy 30.692218 -286.999676) (xy 30.637375 -286.989546)
			(xy 30.584591 -286.971539) (xy 30.534991 -286.946038) (xy 30.489633 -286.913587) (xy 30.449484 -286.874878)
			(xy 30.415398 -286.830735) (xy 30.388102 -286.7821) (xy 30.368179 -286.730009) (xy 30.356053 -286.675572)
			(xy 30.351982 -286.61995) (xy 30.086808 -286.61995) (xy 30.086808 -288.824416) (xy 30.087285 -288.834382)
			(xy 30.094861 -288.852819) (xy 30.10154 -288.86023) (xy 30.30855 -289.06724) (xy 30.316185 -289.074249)
			(xy 30.335387 -289.081997) (xy 30.356088 -289.081529) (xy 30.3657 -289.077654) (xy 30.466792 -289.031426)
			(xy 30.482794 -289.004248) (xy 30.481778 -288.988246) (xy 30.480713 -288.972456) (xy 30.479569 -288.940826)
			(xy 30.479492 -288.925) (xy 30.479976 -288.883075) (xy 30.487867 -288.799596) (xy 30.503579 -288.717231)
			(xy 30.526972 -288.636709) (xy 30.55784 -288.558747) (xy 30.595907 -288.484036) (xy 30.640837 -288.413238)
			(xy 30.692229 -288.346983) (xy 30.749629 -288.285859) (xy 30.812526 -288.230407) (xy 30.880363 -288.181121)
			(xy 30.952537 -288.138438) (xy 31.028407 -288.102736) (xy 31.1073 -288.074332) (xy 31.188517 -288.053479)
			(xy 31.271335 -288.040362) (xy 31.35502 -288.035097) (xy 31.43883 -288.037731) (xy 31.522019 -288.04824)
			(xy 31.60385 -288.066532) (xy 31.683597 -288.092443) (xy 31.760551 -288.125744) (xy 31.83403 -288.16614)
			(xy 31.903382 -288.213271) (xy 31.96799 -288.266719) (xy 32.027281 -288.32601) (xy 32.080729 -288.390618)
			(xy 32.12786 -288.45997) (xy 32.168256 -288.533449) (xy 32.201557 -288.610403) (xy 32.227468 -288.69015)
			(xy 32.24576 -288.771981) (xy 32.256269 -288.85517) (xy 32.258903 -288.93898) (xy 32.253638 -289.022665)
			(xy 32.248992 -289.052) (xy 34.111182 -289.052) (xy 34.115253 -288.996378) (xy 34.127379 -288.941941)
			(xy 34.147302 -288.88985) (xy 34.174598 -288.841215) (xy 34.208684 -288.797072) (xy 34.248833 -288.758363)
			(xy 34.294191 -288.725912) (xy 34.343791 -288.700411) (xy 34.396575 -288.682404) (xy 34.451418 -288.672274)
			(xy 34.507152 -288.670237) (xy 34.562589 -288.676337) (xy 34.616546 -288.690443) (xy 34.667875 -288.712255)
			(xy 34.715481 -288.741309) (xy 34.758349 -288.776984) (xy 34.795566 -288.818521) (xy 34.826339 -288.865034)
			(xy 34.850011 -288.915531) (xy 34.866079 -288.968938) (xy 34.874199 -289.024114) (xy 34.874708 -289.052)
			(xy 34.874199 -289.079886) (xy 34.866079 -289.135062) (xy 34.850011 -289.188469) (xy 34.826339 -289.238966)
			(xy 34.795566 -289.285479) (xy 34.758349 -289.327016) (xy 34.715481 -289.362691) (xy 34.667875 -289.391745)
			(xy 34.616546 -289.413557) (xy 34.562589 -289.427663) (xy 34.507152 -289.433763) (xy 34.451418 -289.431726)
			(xy 34.396575 -289.421596) (xy 34.343791 -289.403589) (xy 34.294191 -289.378088) (xy 34.248833 -289.345637)
			(xy 34.208684 -289.306928) (xy 34.174598 -289.262785) (xy 34.147302 -289.21415) (xy 34.127379 -289.162059)
			(xy 34.115253 -289.107622) (xy 34.111182 -289.052) (xy 32.248992 -289.052) (xy 32.240521 -289.105483)
			(xy 32.219668 -289.1867) (xy 32.191264 -289.265593) (xy 32.155562 -289.341463) (xy 32.112879 -289.413637)
			(xy 32.063593 -289.481474) (xy 32.008141 -289.544371) (xy 31.947017 -289.601771) (xy 31.880762 -289.653163)
			(xy 31.809964 -289.698093) (xy 31.735253 -289.73616) (xy 31.657291 -289.767028) (xy 31.576769 -289.790421)
			(xy 31.494404 -289.806133) (xy 31.410925 -289.814024) (xy 31.369 -289.814508) (xy 31.353174 -289.81443)
			(xy 31.321544 -289.813287) (xy 31.305754 -289.812222) (xy 31.289752 -289.811206) (xy 31.262574 -289.827208)
			(xy 31.216346 -289.9283) (xy 31.212491 -289.937918) (xy 31.212025 -289.958612) (xy 31.219758 -289.977813)
			(xy 31.22676 -289.98545) (xy 31.675151 -290.434014) (xy 34.034982 -290.434014) (xy 34.039053 -290.378392)
			(xy 34.051179 -290.323955) (xy 34.071102 -290.271864) (xy 34.098398 -290.223229) (xy 34.132484 -290.179086)
			(xy 34.172633 -290.140377) (xy 34.217991 -290.107926) (xy 34.267591 -290.082425) (xy 34.320375 -290.064418)
			(xy 34.375218 -290.054288) (xy 34.430952 -290.052251) (xy 34.486389 -290.058351) (xy 34.540346 -290.072457)
			(xy 34.591675 -290.094269) (xy 34.639281 -290.123323) (xy 34.682149 -290.158998) (xy 34.719366 -290.200535)
			(xy 34.750139 -290.247048) (xy 34.773811 -290.297545) (xy 34.789879 -290.350952) (xy 34.797999 -290.406128)
			(xy 34.798508 -290.434014) (xy 34.797999 -290.4619) (xy 34.789879 -290.517076) (xy 34.773811 -290.570483)
			(xy 34.750139 -290.62098) (xy 34.719366 -290.667493) (xy 34.682149 -290.70903) (xy 34.639281 -290.744705)
			(xy 34.591675 -290.773759) (xy 34.540346 -290.795571) (xy 34.486389 -290.809677) (xy 34.430952 -290.815777)
			(xy 34.375218 -290.81374) (xy 34.320375 -290.80361) (xy 34.267591 -290.785603) (xy 34.217991 -290.760102)
			(xy 34.172633 -290.727651) (xy 34.132484 -290.688942) (xy 34.098398 -290.644799) (xy 34.071102 -290.596164)
			(xy 34.051179 -290.544073) (xy 34.039053 -290.489636) (xy 34.034982 -290.434014) (xy 31.675151 -290.434014)
			(xy 31.883604 -290.642548) (xy 31.903727 -290.663399) (xy 31.937825 -290.710249) (xy 31.964173 -290.761858)
			(xy 31.98212 -290.816954) (xy 31.991225 -290.87418) (xy 31.991808 -290.903152) (xy 31.991808 -291.639752)
			(xy 31.993078 -291.645848) (xy 31.998401 -291.668527) (xy 32.004134 -291.714758) (xy 32.004508 -291.73805)
			(xy 32.004048 -291.765305) (xy 31.996297 -291.819262) (xy 31.980945 -291.871565) (xy 31.958306 -291.921152)
			(xy 31.928839 -291.967011) (xy 31.92365 -291.973) (xy 34.835082 -291.973) (xy 34.839153 -291.917378)
			(xy 34.851279 -291.862941) (xy 34.871202 -291.81085) (xy 34.898498 -291.762215) (xy 34.932584 -291.718072)
			(xy 34.972733 -291.679363) (xy 35.018091 -291.646912) (xy 35.067691 -291.621411) (xy 35.120475 -291.603404)
			(xy 35.175318 -291.593274) (xy 35.231052 -291.591237) (xy 35.286489 -291.597337) (xy 35.340446 -291.611443)
			(xy 35.391775 -291.633255) (xy 35.439381 -291.662309) (xy 35.482249 -291.697984) (xy 35.519466 -291.739521)
			(xy 35.550239 -291.786034) (xy 35.573911 -291.836531) (xy 35.589979 -291.889938) (xy 35.598099 -291.945114)
			(xy 35.598608 -291.973) (xy 35.598099 -292.000886) (xy 35.589979 -292.056062) (xy 35.573911 -292.109469)
			(xy 35.550239 -292.159966) (xy 35.519466 -292.206479) (xy 35.482249 -292.248016) (xy 35.439381 -292.283691)
			(xy 35.391775 -292.312745) (xy 35.340446 -292.334557) (xy 35.286489 -292.348663) (xy 35.231052 -292.354763)
			(xy 35.175318 -292.352726) (xy 35.120475 -292.342596) (xy 35.067691 -292.324589) (xy 35.018091 -292.299088)
			(xy 34.972733 -292.266637) (xy 34.932584 -292.227928) (xy 34.898498 -292.183785) (xy 34.871202 -292.13515)
			(xy 34.851279 -292.083059) (xy 34.839153 -292.028622) (xy 34.835082 -291.973) (xy 31.92365 -291.973)
			(xy 31.893145 -292.00821) (xy 31.851951 -292.043909) (xy 31.806096 -292.073382) (xy 31.756512 -292.096028)
			(xy 31.70421 -292.111386) (xy 31.650255 -292.119145) (xy 31.623 -292.119558) (xy 31.608529 -292.119444)
			(xy 31.579669 -292.117282) (xy 31.565342 -292.11524) (xy 31.55442 -292.113462) (xy 31.533084 -292.119558)
			(xy 31.466028 -292.176962) (xy 31.457994 -292.18453) (xy 31.448754 -292.204547) (xy 31.448248 -292.21557)
			(xy 31.448248 -293.812214) (xy 33.234882 -293.812214) (xy 33.238953 -293.756592) (xy 33.251079 -293.702155)
			(xy 33.271002 -293.650064) (xy 33.298298 -293.601429) (xy 33.332384 -293.557286) (xy 33.372533 -293.518577)
			(xy 33.417891 -293.486126) (xy 33.467491 -293.460625) (xy 33.520275 -293.442618) (xy 33.575118 -293.432488)
			(xy 33.630852 -293.430451) (xy 33.686289 -293.436551) (xy 33.740246 -293.450657) (xy 33.791575 -293.472469)
			(xy 33.839181 -293.501523) (xy 33.882049 -293.537198) (xy 33.919266 -293.578735) (xy 33.950039 -293.625248)
			(xy 33.973711 -293.675745) (xy 33.989779 -293.729152) (xy 33.997899 -293.784328) (xy 33.998408 -293.812214)
			(xy 33.997899 -293.8401) (xy 33.989779 -293.895276) (xy 33.973711 -293.948683) (xy 33.950039 -293.99918)
			(xy 33.919266 -294.045693) (xy 33.882049 -294.08723) (xy 33.839181 -294.122905) (xy 33.791575 -294.151959)
			(xy 33.740246 -294.173771) (xy 33.686289 -294.187877) (xy 33.630852 -294.193977) (xy 33.575118 -294.19194)
			(xy 33.520275 -294.18181) (xy 33.467491 -294.163803) (xy 33.417891 -294.138302) (xy 33.372533 -294.105851)
			(xy 33.332384 -294.067142) (xy 33.298298 -294.022999) (xy 33.271002 -293.974364) (xy 33.251079 -293.922273)
			(xy 33.238953 -293.867836) (xy 33.234882 -293.812214) (xy 31.448248 -293.812214) (xy 31.448248 -294.811958)
			(xy 31.448779 -294.821948) (xy 31.456487 -294.840386) (xy 31.463234 -294.847772) (xy 32.449262 -295.8338)
			(xy 32.454596 -295.837102) (xy 32.478386 -295.851992) (xy 32.521723 -295.887653) (xy 32.559369 -295.929277)
			(xy 32.590513 -295.975966) (xy 32.614481 -296.026713) (xy 32.617599 -296.037) (xy 34.835082 -296.037)
			(xy 34.839153 -295.981378) (xy 34.851279 -295.926941) (xy 34.871202 -295.87485) (xy 34.898498 -295.826215)
			(xy 34.932584 -295.782072) (xy 34.972733 -295.743363) (xy 35.018091 -295.710912) (xy 35.067691 -295.685411)
			(xy 35.120475 -295.667404) (xy 35.175318 -295.657274) (xy 35.231052 -295.655237) (xy 35.286489 -295.661337)
			(xy 35.340446 -295.675443) (xy 35.391775 -295.697255) (xy 35.439381 -295.726309) (xy 35.482249 -295.761984)
			(xy 35.519466 -295.803521) (xy 35.550239 -295.850034) (xy 35.573911 -295.900531) (xy 35.589979 -295.953938)
			(xy 35.598099 -296.009114) (xy 35.598608 -296.037) (xy 35.598099 -296.064886) (xy 35.589979 -296.120062)
			(xy 35.573911 -296.173469) (xy 35.550239 -296.223966) (xy 35.519466 -296.270479) (xy 35.482249 -296.312016)
			(xy 35.439381 -296.347691) (xy 35.391775 -296.376745) (xy 35.340446 -296.398557) (xy 35.286489 -296.412663)
			(xy 35.231052 -296.418763) (xy 35.175318 -296.416726) (xy 35.120475 -296.406596) (xy 35.067691 -296.388589)
			(xy 35.018091 -296.363088) (xy 34.972733 -296.330637) (xy 34.932584 -296.291928) (xy 34.898498 -296.247785)
			(xy 34.871202 -296.19915) (xy 34.851279 -296.147059) (xy 34.839153 -296.092622) (xy 34.835082 -296.037)
			(xy 32.617599 -296.037) (xy 32.630759 -296.080423) (xy 32.638994 -296.135939) (xy 32.639508 -296.164)
			(xy 32.639067 -296.190713) (xy 32.631627 -296.243619) (xy 32.616879 -296.294969) (xy 32.59511 -296.343759)
			(xy 32.566747 -296.389035) (xy 32.532345 -296.429911) (xy 32.492576 -296.465587) (xy 32.448219 -296.495366)
			(xy 32.42437 -296.507408) (xy 32.413194 -296.512742) (xy 32.398462 -296.5323) (xy 32.382714 -296.62628)
			(xy 32.381334 -296.638384) (xy 32.388627 -296.661592) (xy 32.396684 -296.67073) (xy 32.897064 -297.17111)
			(xy 32.917192 -297.191959) (xy 32.951298 -297.238807) (xy 32.977653 -297.290416) (xy 32.995608 -297.345513)
			(xy 33.004721 -297.40274) (xy 33.005268 -297.431714) (xy 33.005268 -300.609) (xy 35.812982 -300.609)
			(xy 35.817053 -300.553378) (xy 35.829179 -300.498941) (xy 35.849102 -300.44685) (xy 35.876398 -300.398215)
			(xy 35.910484 -300.354072) (xy 35.950633 -300.315363) (xy 35.995991 -300.282912) (xy 36.045591 -300.257411)
			(xy 36.098375 -300.239404) (xy 36.153218 -300.229274) (xy 36.208952 -300.227237) (xy 36.264389 -300.233337)
			(xy 36.318346 -300.247443) (xy 36.369675 -300.269255) (xy 36.417281 -300.298309) (xy 36.460149 -300.333984)
			(xy 36.497366 -300.375521) (xy 36.528139 -300.422034) (xy 36.551811 -300.472531) (xy 36.567879 -300.525938)
			(xy 36.575999 -300.581114) (xy 36.576508 -300.609) (xy 36.575999 -300.636886) (xy 36.567879 -300.692062)
			(xy 36.551811 -300.745469) (xy 36.528139 -300.795966) (xy 36.497366 -300.842479) (xy 36.460149 -300.884016)
			(xy 36.417281 -300.919691) (xy 36.369675 -300.948745) (xy 36.318346 -300.970557) (xy 36.264389 -300.984663)
			(xy 36.208952 -300.990763) (xy 36.153218 -300.988726) (xy 36.098375 -300.978596) (xy 36.045591 -300.960589)
			(xy 35.995991 -300.935088) (xy 35.950633 -300.902637) (xy 35.910484 -300.863928) (xy 35.876398 -300.819785)
			(xy 35.849102 -300.77115) (xy 35.829179 -300.719059) (xy 35.817053 -300.664622) (xy 35.812982 -300.609)
			(xy 33.005268 -300.609) (xy 33.005268 -300.689518) (xy 33.004712 -300.718493) (xy 32.995609 -300.775724)
			(xy 32.977662 -300.830825) (xy 32.951314 -300.882439) (xy 32.917213 -300.929294) (xy 32.897064 -300.950122)
			(xy 32.42564 -301.4218) (xy 32.422338 -301.427134) (xy 32.407447 -301.450924) (xy 32.371786 -301.494261)
			(xy 32.330162 -301.531908) (xy 32.283473 -301.563053) (xy 32.232727 -301.587024) (xy 32.179017 -301.603305)
			(xy 32.123501 -301.611545) (xy 32.09544 -301.612046) (xy 32.068184 -301.611586) (xy 32.014227 -301.603834)
			(xy 31.961922 -301.588482) (xy 31.912334 -301.565842) (xy 31.866473 -301.536375) (xy 31.825273 -301.500682)
			(xy 31.789571 -301.459489) (xy 31.760096 -301.413634) (xy 31.737446 -301.364051) (xy 31.722083 -301.311749)
			(xy 31.71432 -301.257794) (xy 31.713932 -301.230538) (xy 31.714427 -301.202474) (xy 31.722648 -301.146952)
			(xy 31.738919 -301.093234) (xy 31.762887 -301.042481) (xy 31.794036 -300.995789) (xy 31.831691 -300.954167)
			(xy 31.875041 -300.918514) (xy 31.898844 -300.90364) (xy 31.904178 -300.900338) (xy 32.25292 -300.551596)
			(xy 32.259601 -300.544185) (xy 32.267179 -300.525749) (xy 32.267652 -300.515782) (xy 32.267652 -299.071538)
			(xy 32.267294 -299.061973) (xy 32.260364 -299.044145) (xy 32.24738 -299.0301) (xy 32.23895 -299.025564)
			(xy 32.142684 -298.979844) (xy 32.113728 -298.9834) (xy 32.102044 -298.992544) (xy 32.081578 -299.008603)
			(xy 32.037118 -299.035613) (xy 31.989398 -299.056327) (xy 31.939306 -299.070362) (xy 31.887771 -299.077456)
			(xy 31.86176 -299.077888) (xy 31.834512 -299.077399) (xy 31.780572 -299.069638) (xy 31.728284 -299.054281)
			(xy 31.678715 -299.031638) (xy 31.632872 -299.002173) (xy 31.591689 -298.966483) (xy 31.556003 -298.925296)
			(xy 31.526542 -298.87945) (xy 31.503905 -298.829878) (xy 31.488553 -298.777589) (xy 31.480798 -298.723648)
			(xy 31.480798 -298.669152) (xy 31.488553 -298.615211) (xy 31.503905 -298.562922) (xy 31.526542 -298.51335)
			(xy 31.556003 -298.467504) (xy 31.591689 -298.426317) (xy 31.632872 -298.390627) (xy 31.678715 -298.361162)
			(xy 31.728284 -298.338519) (xy 31.780572 -298.323162) (xy 31.834512 -298.315401) (xy 31.86176 -298.314872)
			(xy 31.887769 -298.31533) (xy 31.939301 -298.322429) (xy 31.989392 -298.33646) (xy 32.037113 -298.357164)
			(xy 32.081581 -298.384156) (xy 32.102044 -298.400216) (xy 32.113728 -298.40936) (xy 32.142684 -298.412916)
			(xy 32.23895 -298.367196) (xy 32.247387 -298.362671) (xy 32.260367 -298.348617) (xy 32.267305 -298.330789)
			(xy 32.267652 -298.321222) (xy 32.267652 -297.60545) (xy 32.267167 -297.595488) (xy 32.259579 -297.577063)
			(xy 32.25292 -297.569636) (xy 30.28569 -295.602152) (xy 30.265611 -295.581273) (xy 30.23156 -295.534415)
			(xy 30.205257 -295.482807) (xy 30.187352 -295.42772) (xy 30.178284 -295.37051) (xy 30.17774 -295.341548)
			(xy 30.17774 -291.618162) (xy 30.177194 -291.608179) (xy 30.169464 -291.589763) (xy 30.162754 -291.582348)
			(xy 28.377896 -289.797236) (xy 28.361084 -289.779942) (xy 28.331669 -289.741717) (xy 28.307503 -289.699975)
			(xy 28.297886 -289.677856) (xy 28.292552 -289.664902) (xy 28.270962 -289.648392) (xy 28.154884 -289.634676)
			(xy 28.129992 -289.645598) (xy 28.121864 -289.657028) (xy 28.106427 -289.677604) (xy 28.070912 -289.714815)
			(xy 28.030717 -289.746915) (xy 27.986572 -289.77332) (xy 27.939278 -289.793552) (xy 27.889694 -289.807242)
			(xy 27.83872 -289.814143) (xy 27.813 -289.814508) (xy 27.785749 -289.814022) (xy 27.731801 -289.806266)
			(xy 27.679506 -289.790911) (xy 27.629929 -289.768269) (xy 27.584079 -289.738803) (xy 27.542888 -289.703112)
			(xy 27.507197 -289.661921) (xy 27.477731 -289.616071) (xy 27.455089 -289.566494) (xy 27.439734 -289.514199)
			(xy 27.431978 -289.460251) (xy 27.431978 -289.405749) (xy 27.439734 -289.351801) (xy 27.455089 -289.299506)
			(xy 27.477731 -289.249929) (xy 27.507197 -289.204079) (xy 27.542888 -289.162888) (xy 27.584079 -289.127197)
			(xy 27.629929 -289.097731) (xy 27.679506 -289.075089) (xy 27.731801 -289.059734) (xy 27.785749 -289.051978)
			(xy 27.813 -289.051492) (xy 27.839267 -289.051931) (xy 27.891304 -289.059143) (xy 27.941858 -289.07343)
			(xy 27.989973 -289.094522) (xy 28.034736 -289.12202) (xy 28.0753 -289.155402) (xy 28.093416 -289.174428)
			(xy 28.104338 -289.186112) (xy 28.134564 -289.193224) (xy 28.237434 -289.152838) (xy 28.246733 -289.148698)
			(xy 28.261291 -289.134496) (xy 28.269208 -289.115762) (xy 28.269692 -289.105594) (xy 28.269692 -284.796484)
			(xy 28.269215 -284.786518) (xy 28.261639 -284.768081) (xy 28.25496 -284.76067) (xy 26.820876 -283.326586)
			(xy 26.81348 -283.319734) (xy 26.794881 -283.311995) (xy 26.784808 -283.3116) (xy 26.081482 -283.3116)
			(xy 26.071413 -283.312027) (xy 26.052814 -283.319746) (xy 26.045414 -283.326586) (xy 25.91054 -283.46146)
			(xy 25.903845 -283.468866) (xy 25.896242 -283.487302) (xy 25.895808 -283.497274) (xy 25.895808 -284.799786)
			(xy 25.895246 -284.828758) (xy 25.886133 -284.885982) (xy 25.868177 -284.941075) (xy 25.841819 -284.992679)
			(xy 25.80771 -285.039522) (xy 25.787604 -285.06039) (xy 25.124918 -285.72333) (xy 25.11811 -285.730676)
			(xy 25.110386 -285.749139) (xy 25.109932 -285.759144) (xy 25.109932 -291.14496) (xy 28.304996 -291.14496)
			(xy 28.309067 -291.089338) (xy 28.321193 -291.034901) (xy 28.341116 -290.98281) (xy 28.368412 -290.934175)
			(xy 28.402498 -290.890032) (xy 28.442647 -290.851323) (xy 28.488005 -290.818872) (xy 28.537605 -290.793371)
			(xy 28.590389 -290.775364) (xy 28.645232 -290.765234) (xy 28.700966 -290.763197) (xy 28.756403 -290.769297)
			(xy 28.81036 -290.783403) (xy 28.861689 -290.805215) (xy 28.909295 -290.834269) (xy 28.952163 -290.869944)
			(xy 28.98938 -290.911481) (xy 29.020153 -290.957994) (xy 29.043825 -291.008491) (xy 29.059893 -291.061898)
			(xy 29.068013 -291.117074) (xy 29.068522 -291.14496) (xy 29.068013 -291.172846) (xy 29.059893 -291.228022)
			(xy 29.043825 -291.281429) (xy 29.020153 -291.331926) (xy 28.98938 -291.378439) (xy 28.952163 -291.419976)
			(xy 28.909295 -291.455651) (xy 28.861689 -291.484705) (xy 28.81036 -291.506517) (xy 28.756403 -291.520623)
			(xy 28.700966 -291.526723) (xy 28.645232 -291.524686) (xy 28.590389 -291.514556) (xy 28.537605 -291.496549)
			(xy 28.488005 -291.471048) (xy 28.442647 -291.438597) (xy 28.402498 -291.399888) (xy 28.368412 -291.355745)
			(xy 28.341116 -291.30711) (xy 28.321193 -291.255019) (xy 28.309067 -291.200582) (xy 28.304996 -291.14496)
			(xy 25.109932 -291.14496) (xy 25.109932 -294.128952) (xy 25.109397 -294.157917) (xy 25.100342 -294.215134)
			(xy 25.082446 -294.27023) (xy 25.056151 -294.321847) (xy 25.022104 -294.368715) (xy 25.001982 -294.389556)
			(xy 22.22754 -297.164252) (xy 22.220844 -297.171657) (xy 22.213238 -297.190094) (xy 22.212808 -297.200066)
			(xy 22.212808 -298.17314) (xy 23.679402 -298.17314) (xy 23.683473 -298.117518) (xy 23.695599 -298.063081)
			(xy 23.715522 -298.01099) (xy 23.742818 -297.962355) (xy 23.776904 -297.918212) (xy 23.817053 -297.879503)
			(xy 23.862411 -297.847052) (xy 23.912011 -297.821551) (xy 23.964795 -297.803544) (xy 24.019638 -297.793414)
			(xy 24.075372 -297.791377) (xy 24.130809 -297.797477) (xy 24.184766 -297.811583) (xy 24.236095 -297.833395)
			(xy 24.283701 -297.862449) (xy 24.326569 -297.898124) (xy 24.363786 -297.939661) (xy 24.394559 -297.986174)
			(xy 24.418231 -298.036671) (xy 24.434299 -298.090078) (xy 24.442419 -298.145254) (xy 24.442928 -298.17314)
			(xy 24.442419 -298.201026) (xy 24.434299 -298.256202) (xy 24.418231 -298.309609) (xy 24.394559 -298.360106)
			(xy 24.363786 -298.406619) (xy 24.326569 -298.448156) (xy 24.283701 -298.483831) (xy 24.236095 -298.512885)
			(xy 24.184766 -298.534697) (xy 24.130809 -298.548803) (xy 24.075372 -298.554903) (xy 24.019638 -298.552866)
			(xy 23.964795 -298.542736) (xy 23.912011 -298.524729) (xy 23.862411 -298.499228) (xy 23.817053 -298.466777)
			(xy 23.776904 -298.428068) (xy 23.742818 -298.383925) (xy 23.715522 -298.33529) (xy 23.695599 -298.283199)
			(xy 23.683473 -298.228762) (xy 23.679402 -298.17314) (xy 22.212808 -298.17314) (xy 22.212808 -298.751752)
			(xy 22.214078 -298.757848) (xy 22.219401 -298.780527) (xy 22.225134 -298.826758) (xy 22.225508 -298.85005)
			(xy 22.225022 -298.877301) (xy 22.217266 -298.931249) (xy 22.201911 -298.983544) (xy 22.179269 -299.033121)
			(xy 22.149803 -299.078971) (xy 22.114112 -299.120162) (xy 22.072921 -299.155853) (xy 22.027071 -299.185319)
			(xy 21.977494 -299.207961) (xy 21.925199 -299.223316) (xy 21.871251 -299.231072) (xy 21.816749 -299.231072)
			(xy 21.762801 -299.223316) (xy 21.710506 -299.207961) (xy 21.660929 -299.185319) (xy 21.615079 -299.155853)
			(xy 21.573888 -299.120162) (xy 21.538197 -299.078971) (xy 21.508731 -299.033121) (xy 21.486089 -298.983544)
			(xy 21.470734 -298.931249) (xy 21.462978 -298.877301) (xy 21.462492 -298.85005) (xy 21.462873 -298.826758)
			(xy 21.468606 -298.780528) (xy 21.473922 -298.757848) (xy 21.475192 -298.751752) (xy 21.475192 -298.203874)
			(xy 21.474713 -298.193909) (xy 21.467135 -298.175475) (xy 21.46046 -298.16806) (xy 21.249386 -297.956986)
			(xy 21.241991 -297.950132) (xy 21.223392 -297.94239) (xy 21.213318 -297.942) (xy 20.716494 -297.942)
			(xy 20.706424 -297.942424) (xy 20.687821 -297.95014) (xy 20.680426 -297.956986) (xy 20.400518 -298.23664)
			(xy 20.392898 -298.246546) (xy 20.378006 -298.270334) (xy 20.342342 -298.313665) (xy 20.300717 -298.351306)
			(xy 20.254028 -298.382446) (xy 20.203282 -298.406411) (xy 20.149573 -298.422686) (xy 20.09406 -298.43092)
			(xy 20.066 -298.431458) (xy 20.038748 -298.430995) (xy 19.9848 -298.423237) (xy 19.932505 -298.407881)
			(xy 19.882928 -298.385238) (xy 19.837079 -298.355769) (xy 19.79589 -298.320074) (xy 19.760201 -298.278881)
			(xy 19.730738 -298.233028) (xy 19.708102 -298.183448) (xy 19.692752 -298.131151) (xy 19.685002 -298.077202)
			(xy 19.684492 -298.04995) (xy 19.684986 -298.021886) (xy 19.693207 -297.966364) (xy 19.709478 -297.912647)
			(xy 19.733448 -297.861896) (xy 19.764598 -297.815206) (xy 19.802257 -297.773588) (xy 19.845609 -297.737939)
			(xy 19.869404 -297.723052) (xy 19.874738 -297.71975) (xy 23.824438 -293.77005) (xy 23.831248 -293.762705)
			(xy 23.838972 -293.744242) (xy 23.839424 -293.734236) (xy 23.839424 -285.364428) (xy 23.83999 -285.335466)
			(xy 23.849046 -285.278254) (xy 23.866941 -285.223163) (xy 23.893234 -285.17155) (xy 23.927277 -285.124685)
			(xy 23.947374 -285.103824) (xy 24.61006 -284.440884) (xy 24.616804 -284.433514) (xy 24.624397 -284.415052)
			(xy 24.624792 -284.40507) (xy 24.624792 -283.612844) (xy 24.624428 -283.602817) (xy 24.616821 -283.584268)
			(xy 24.602647 -283.57009) (xy 24.59355 -283.565854) (xy 24.579072 -283.560012) (xy 24.549354 -283.565854)
			(xy 22.98954 -285.125668) (xy 22.982846 -285.133074) (xy 22.975246 -285.15151) (xy 22.974808 -285.161482)
			(xy 22.974808 -292.481254) (xy 22.974249 -292.510227) (xy 22.96514 -292.567454) (xy 22.947187 -292.62255)
			(xy 22.920832 -292.674157) (xy 22.886726 -292.721004) (xy 22.866604 -292.741858) (xy 21.361908 -294.246554)
			(xy 21.341027 -294.266629) (xy 21.294166 -294.30067) (xy 21.242557 -294.326963) (xy 21.187471 -294.34486)
			(xy 21.130264 -294.35392) (xy 21.101304 -294.354504) (xy 20.164298 -294.354504) (xy 20.158202 -294.356028)
			(xy 20.135523 -294.361348) (xy 20.089292 -294.367074) (xy 20.066 -294.367458) (xy 20.038749 -294.366972)
			(xy 19.984801 -294.359216) (xy 19.932506 -294.343861) (xy 19.882929 -294.321219) (xy 19.837079 -294.291753)
			(xy 19.795888 -294.256062) (xy 19.760197 -294.214871) (xy 19.730731 -294.169021) (xy 19.708089 -294.119444)
			(xy 19.692734 -294.067149) (xy 19.684978 -294.013201) (xy 19.684978 -293.958699) (xy 19.692734 -293.904751)
			(xy 19.708089 -293.852456) (xy 19.730731 -293.802879) (xy 19.760197 -293.757029) (xy 19.795888 -293.715838)
			(xy 19.837079 -293.680147) (xy 19.882929 -293.650681) (xy 19.932506 -293.628039) (xy 19.984801 -293.612684)
			(xy 20.038749 -293.604928) (xy 20.066 -293.604442) (xy 20.089292 -293.60482) (xy 20.135524 -293.610546)
			(xy 20.158202 -293.615872) (xy 20.164298 -293.617396) (xy 20.927568 -293.617396) (xy 20.937558 -293.616864)
			(xy 20.955998 -293.609158) (xy 20.963382 -293.60241) (xy 22.22246 -292.343332) (xy 22.229154 -292.335926)
			(xy 22.236754 -292.31749) (xy 22.237192 -292.307518) (xy 22.237192 -284.987746) (xy 22.237751 -284.958773)
			(xy 22.24686 -284.901546) (xy 22.264813 -284.84645) (xy 22.291168 -284.794843) (xy 22.325274 -284.747996)
			(xy 22.345396 -284.727142) (xy 24.07666 -282.995624) (xy 24.083352 -282.988218) (xy 24.090949 -282.969781)
			(xy 24.091392 -282.95981) (xy 24.091392 -280.474674) (xy 24.090913 -280.464709) (xy 24.083335 -280.446275)
			(xy 24.07666 -280.43886) (xy 23.941786 -280.303986) (xy 23.934391 -280.297132) (xy 23.915792 -280.28939)
			(xy 23.905718 -280.289) (xy 23.529544 -280.289) (xy 23.519478 -280.289434) (xy 23.500889 -280.297162)
			(xy 23.493476 -280.303986) (xy 19.772376 -284.025086) (xy 19.765688 -284.032496) (xy 19.758083 -284.05093)
			(xy 19.758083 -284.07087) (xy 19.765688 -284.089304) (xy 19.772376 -284.096714) (xy 20.153884 -284.478476)
			(xy 20.174013 -284.499325) (xy 20.208122 -284.546173) (xy 20.23448 -284.597781) (xy 20.252439 -284.652878)
			(xy 20.261556 -284.710106) (xy 20.262088 -284.73908) (xy 20.262088 -285.03372) (xy 20.261531 -285.062694)
			(xy 20.252427 -285.119923) (xy 20.234477 -285.175022) (xy 20.208124 -285.226632) (xy 20.174018 -285.273482)
			(xy 20.153884 -285.294324) (xy 19.945604 -285.502604) (xy 19.924754 -285.522731) (xy 19.877905 -285.556835)
			(xy 19.826297 -285.583189) (xy 19.771201 -285.601144) (xy 19.713974 -285.610258) (xy 19.685 -285.610808)
			(xy 19.39036 -285.610808) (xy 19.36369 -285.609792) (xy 19.352514 -285.60903) (xy 19.332194 -285.616396)
			(xy 19.261836 -285.686754) (xy 19.25447 -285.707074) (xy 19.255232 -285.71825) (xy 19.256248 -285.74492)
			(xy 19.256248 -286.03956) (xy 19.255688 -286.068533) (xy 19.24658 -286.12576) (xy 19.228627 -286.180857)
			(xy 19.202274 -286.232465) (xy 19.16817 -286.279314) (xy 19.148044 -286.300164) (xy 18.939764 -286.508444)
			(xy 18.918915 -286.528571) (xy 18.872066 -286.562676) (xy 18.820458 -286.589029) (xy 18.765361 -286.606981)
			(xy 18.708133 -286.61609) (xy 18.67916 -286.616648) (xy 18.38452 -286.616648) (xy 18.355547 -286.616087)
			(xy 18.298322 -286.606975) (xy 18.243227 -286.589021) (xy 18.191621 -286.562666) (xy 18.144775 -286.52856)
			(xy 18.123916 -286.508444) (xy 17.742154 -286.126936) (xy 17.734742 -286.120252) (xy 17.716309 -286.112655)
			(xy 17.696371 -286.112655) (xy 17.677938 -286.120252) (xy 17.670526 -286.126936) (xy 17.598898 -286.198564)
			(xy 17.591247 -286.207051) (xy 17.583606 -286.228552) (xy 17.584166 -286.239966) (xy 17.594072 -286.330136)
			(xy 17.60601 -286.349694) (xy 17.615916 -286.356044) (xy 17.638615 -286.371163) (xy 17.679853 -286.406856)
			(xy 17.71559 -286.448055) (xy 17.745098 -286.493923) (xy 17.767774 -286.543524) (xy 17.783159 -286.595849)
			(xy 17.790937 -286.649831) (xy 17.79143 -286.6771) (xy 19.383246 -286.6771) (xy 19.387317 -286.621478)
			(xy 19.399443 -286.567041) (xy 19.419366 -286.51495) (xy 19.446662 -286.466315) (xy 19.480748 -286.422172)
			(xy 19.520897 -286.383463) (xy 19.566255 -286.351012) (xy 19.615855 -286.325511) (xy 19.668639 -286.307504)
			(xy 19.723482 -286.297374) (xy 19.779216 -286.295337) (xy 19.834653 -286.301437) (xy 19.88861 -286.315543)
			(xy 19.939939 -286.337355) (xy 19.987545 -286.366409) (xy 20.030413 -286.402084) (xy 20.06763 -286.443621)
			(xy 20.098403 -286.490134) (xy 20.122075 -286.540631) (xy 20.138143 -286.594038) (xy 20.146263 -286.649214)
			(xy 20.146772 -286.6771) (xy 20.146263 -286.704986) (xy 20.138143 -286.760162) (xy 20.122075 -286.813569)
			(xy 20.098403 -286.864066) (xy 20.06763 -286.910579) (xy 20.030413 -286.952116) (xy 19.987545 -286.987791)
			(xy 19.939939 -287.016845) (xy 19.88861 -287.038657) (xy 19.834653 -287.052763) (xy 19.779216 -287.058863)
			(xy 19.723482 -287.056826) (xy 19.668639 -287.046696) (xy 19.615855 -287.028689) (xy 19.566255 -287.003188)
			(xy 19.520897 -286.970737) (xy 19.480748 -286.932028) (xy 19.446662 -286.887885) (xy 19.419366 -286.83925)
			(xy 19.399443 -286.787159) (xy 19.387317 -286.732722) (xy 19.383246 -286.6771) (xy 17.79143 -286.6771)
			(xy 17.790944 -286.704352) (xy 17.783188 -286.758301) (xy 17.767833 -286.810597) (xy 17.745192 -286.860175)
			(xy 17.715726 -286.906027) (xy 17.680035 -286.947219) (xy 17.638845 -286.982913) (xy 17.592995 -287.012382)
			(xy 17.543417 -287.035025) (xy 17.491122 -287.050383) (xy 17.437174 -287.058143) (xy 17.409922 -287.058608)
			(xy 17.38265 -287.058144) (xy 17.328664 -287.050376) (xy 17.276334 -287.034994) (xy 17.226731 -287.012313)
			(xy 17.180865 -286.982796) (xy 17.139673 -286.947045) (xy 17.103995 -286.905789) (xy 17.088866 -286.883094)
			(xy 17.082516 -286.873188) (xy 17.062958 -286.86125) (xy 16.972788 -286.851344) (xy 16.961378 -286.85078)
			(xy 16.93989 -286.858444) (xy 16.931386 -286.866076) (xy 15.521432 -288.27603) (xy 15.514691 -288.283401)
			(xy 15.507105 -288.301863) (xy 15.5067 -288.311844) (xy 15.5067 -289.105086) (xy 15.507335 -289.117791)
			(xy 15.519342 -289.140178) (xy 15.52956 -289.147758) (xy 15.611856 -289.201352) (xy 15.637256 -289.203384)
			(xy 15.649194 -289.19805) (xy 15.673516 -289.187855) (xy 15.72426 -289.173488) (xy 15.776495 -289.166227)
			(xy 15.802864 -289.165792) (xy 15.830115 -289.166278) (xy 15.884062 -289.174035) (xy 15.936357 -289.189391)
			(xy 15.985933 -289.212032) (xy 16.031783 -289.241498) (xy 16.072973 -289.27719) (xy 16.108664 -289.31838)
			(xy 16.13813 -289.36423) (xy 16.160771 -289.413807) (xy 16.176126 -289.466102) (xy 16.183882 -289.520049)
			(xy 16.183882 -289.558222) (xy 17.064226 -289.558222) (xy 17.068297 -289.5026) (xy 17.080423 -289.448163)
			(xy 17.100346 -289.396072) (xy 17.127642 -289.347437) (xy 17.161728 -289.303294) (xy 17.201877 -289.264585)
			(xy 17.247235 -289.232134) (xy 17.296835 -289.206633) (xy 17.349619 -289.188626) (xy 17.404462 -289.178496)
			(xy 17.460196 -289.176459) (xy 17.515633 -289.182559) (xy 17.56959 -289.196665) (xy 17.620919 -289.218477)
			(xy 17.668525 -289.247531) (xy 17.711393 -289.283206) (xy 17.74861 -289.324743) (xy 17.779383 -289.371256)
			(xy 17.803055 -289.421753) (xy 17.819123 -289.47516) (xy 17.827243 -289.530336) (xy 17.827752 -289.558222)
			(xy 17.827243 -289.586108) (xy 17.819123 -289.641284) (xy 17.803055 -289.694691) (xy 17.779383 -289.745188)
			(xy 17.74861 -289.791701) (xy 17.711393 -289.833238) (xy 17.668525 -289.868913) (xy 17.620919 -289.897967)
			(xy 17.56959 -289.919779) (xy 17.515633 -289.933885) (xy 17.460196 -289.939985) (xy 17.404462 -289.937948)
			(xy 17.349619 -289.927818) (xy 17.296835 -289.909811) (xy 17.247235 -289.88431) (xy 17.201877 -289.851859)
			(xy 17.161728 -289.81315) (xy 17.127642 -289.769007) (xy 17.100346 -289.720372) (xy 17.080423 -289.668281)
			(xy 17.068297 -289.613844) (xy 17.064226 -289.558222) (xy 16.183882 -289.558222) (xy 16.183882 -289.574551)
			(xy 16.176126 -289.628498) (xy 16.160771 -289.680793) (xy 16.13813 -289.73037) (xy 16.108664 -289.77622)
			(xy 16.072973 -289.81741) (xy 16.031783 -289.853102) (xy 15.985933 -289.882568) (xy 15.936357 -289.905209)
			(xy 15.884062 -289.920565) (xy 15.830115 -289.928322) (xy 15.802864 -289.928808) (xy 15.776493 -289.928384)
			(xy 15.724251 -289.921148) (xy 15.67351 -289.906765) (xy 15.649194 -289.89655) (xy 15.637256 -289.891216)
			(xy 15.611856 -289.893248) (xy 15.52956 -289.946842) (xy 15.519323 -289.954404) (xy 15.50731 -289.976803)
			(xy 15.5067 -289.989514) (xy 15.5067 -291.5031) (xy 17.148554 -291.5031) (xy 17.152625 -291.447478)
			(xy 17.164751 -291.393041) (xy 17.184674 -291.34095) (xy 17.21197 -291.292315) (xy 17.246056 -291.248172)
			(xy 17.286205 -291.209463) (xy 17.331563 -291.177012) (xy 17.381163 -291.151511) (xy 17.433947 -291.133504)
			(xy 17.48879 -291.123374) (xy 17.544524 -291.121337) (xy 17.599961 -291.127437) (xy 17.653918 -291.141543)
			(xy 17.705247 -291.163355) (xy 17.752853 -291.192409) (xy 17.795721 -291.228084) (xy 17.832938 -291.269621)
			(xy 17.863711 -291.316134) (xy 17.887383 -291.366631) (xy 17.903451 -291.420038) (xy 17.911571 -291.475214)
			(xy 17.91208 -291.5031) (xy 17.911571 -291.530986) (xy 17.903451 -291.586162) (xy 17.887383 -291.639569)
			(xy 17.863711 -291.690066) (xy 17.832938 -291.736579) (xy 17.795721 -291.778116) (xy 17.752853 -291.813791)
			(xy 17.705247 -291.842845) (xy 17.653918 -291.864657) (xy 17.599961 -291.878763) (xy 17.544524 -291.884863)
			(xy 17.48879 -291.882826) (xy 17.433947 -291.872696) (xy 17.381163 -291.854689) (xy 17.331563 -291.829188)
			(xy 17.286205 -291.796737) (xy 17.246056 -291.758028) (xy 17.21197 -291.713885) (xy 17.184674 -291.66525)
			(xy 17.164751 -291.613159) (xy 17.152625 -291.558722) (xy 17.148554 -291.5031) (xy 15.5067 -291.5031)
			(xy 15.5067 -292.211506) (xy 15.507175 -292.221473) (xy 15.514748 -292.239913) (xy 15.521432 -292.24732)
			(xy 15.551912 -292.2778) (xy 15.557246 -292.281102) (xy 15.581034 -292.295994) (xy 15.624365 -292.331658)
			(xy 15.662006 -292.373283) (xy 15.693146 -292.419972) (xy 15.717111 -292.470718) (xy 15.733386 -292.524427)
			(xy 15.74162 -292.57994) (xy 15.742158 -292.608) (xy 15.741695 -292.635252) (xy 15.733937 -292.6892)
			(xy 15.718581 -292.741495) (xy 15.695938 -292.791072) (xy 15.666469 -292.836921) (xy 15.630774 -292.87811)
			(xy 15.589581 -292.913799) (xy 15.543728 -292.943262) (xy 15.494148 -292.965898) (xy 15.441851 -292.981248)
			(xy 15.387902 -292.988998) (xy 15.36065 -292.989508) (xy 15.332586 -292.989014) (xy 15.277064 -292.980793)
			(xy 15.223347 -292.964522) (xy 15.172596 -292.940552) (xy 15.125906 -292.909402) (xy 15.084288 -292.871743)
			(xy 15.048639 -292.828391) (xy 15.033752 -292.804596) (xy 15.03045 -292.799262) (xy 14.877288 -292.645846)
			(xy 14.868906 -292.637464) (xy 14.81328 -292.659562) (xy 14.804016 -292.663722) (xy 14.789538 -292.67794)
			(xy 14.781707 -292.696659) (xy 14.781276 -292.706806) (xy 14.781276 -293.257732) (xy 14.781755 -293.267697)
			(xy 14.789332 -293.286133) (xy 14.796008 -293.293546) (xy 15.812262 -294.3098) (xy 15.817596 -294.313102)
			(xy 15.841386 -294.327992) (xy 15.884723 -294.363653) (xy 15.922369 -294.405277) (xy 15.953513 -294.451966)
			(xy 15.977481 -294.502713) (xy 15.993759 -294.556423) (xy 16.001994 -294.611939) (xy 16.002508 -294.64)
			(xy 16.001906 -294.670941) (xy 15.991914 -294.732009) (xy 15.972192 -294.790664) (xy 15.943257 -294.845363)
			(xy 15.925038 -294.870378) (xy 15.916148 -294.882062) (xy 15.913608 -294.91051) (xy 15.960598 -295.005252)
			(xy 15.965149 -295.01349) (xy 15.979091 -295.026113) (xy 15.996658 -295.032831) (xy 16.006064 -295.033192)
			(xy 17.479264 -295.033192) (xy 17.489226 -295.032706) (xy 17.50765 -295.025118) (xy 17.515078 -295.01846)
			(xy 18.785332 -293.748206) (xy 18.792014 -293.740795) (xy 18.799593 -293.722359) (xy 18.800064 -293.712392)
			(xy 18.800064 -289.6108) (xy 18.800619 -289.581825) (xy 18.80972 -289.524593) (xy 18.827666 -289.469491)
			(xy 18.854014 -289.417876) (xy 18.888116 -289.371022) (xy 18.908268 -289.350196) (xy 19.340068 -288.918396)
			(xy 19.359846 -288.899338) (xy 19.404015 -288.866694) (xy 19.452535 -288.84096) (xy 19.504335 -288.822703)
			(xy 19.558269 -288.812328) (xy 19.585686 -288.8107) (xy 19.5961 -288.809176) (xy 19.60245 -288.807652)
			(xy 19.616166 -288.749232) (xy 19.617943 -288.740244) (xy 19.615712 -288.722071) (xy 19.607233 -288.705844)
			(xy 19.600672 -288.699448) (xy 19.569949 -288.671378) (xy 19.513306 -288.610402) (xy 19.462607 -288.544401)
			(xy 19.418296 -288.473952) (xy 19.38076 -288.399672) (xy 19.350328 -288.32221) (xy 19.327266 -288.242244)
			(xy 19.311774 -288.160473) (xy 19.30399 -288.077613) (xy 19.303492 -288.036) (xy 19.303976 -287.994075)
			(xy 19.311867 -287.910596) (xy 19.327579 -287.828231) (xy 19.350972 -287.747709) (xy 19.38184 -287.669747)
			(xy 19.419907 -287.595036) (xy 19.464837 -287.524238) (xy 19.516229 -287.457983) (xy 19.573629 -287.396859)
			(xy 19.636526 -287.341407) (xy 19.704363 -287.292121) (xy 19.776537 -287.249438) (xy 19.852407 -287.213736)
			(xy 19.9313 -287.185332) (xy 20.012517 -287.164479) (xy 20.095335 -287.151362) (xy 20.17902 -287.146097)
			(xy 20.26283 -287.148731) (xy 20.346019 -287.15924) (xy 20.42785 -287.177532) (xy 20.507597 -287.203443)
			(xy 20.584551 -287.236744) (xy 20.65803 -287.27714) (xy 20.727382 -287.324271) (xy 20.79199 -287.377719)
			(xy 20.851281 -287.43701) (xy 20.904729 -287.501618) (xy 20.95186 -287.57097) (xy 20.992256 -287.644449)
			(xy 21.025557 -287.721403) (xy 21.051468 -287.80115) (xy 21.06976 -287.882981) (xy 21.080269 -287.96617)
			(xy 21.082903 -288.04998) (xy 21.077638 -288.133665) (xy 21.064521 -288.216483) (xy 21.043668 -288.2977)
			(xy 21.015264 -288.376593) (xy 20.979562 -288.452463) (xy 20.936879 -288.524637) (xy 20.887593 -288.592474)
			(xy 20.832141 -288.655371) (xy 20.771017 -288.712771) (xy 20.704762 -288.764163) (xy 20.633964 -288.809093)
			(xy 20.559253 -288.84716) (xy 20.481291 -288.878028) (xy 20.400769 -288.901421) (xy 20.318404 -288.917133)
			(xy 20.234925 -288.925024) (xy 20.193 -288.925508) (xy 20.15236 -288.924492) (xy 20.13966 -288.923984)
			(xy 20.117308 -288.934398) (xy 20.051522 -289.021774) (xy 20.047458 -289.046158) (xy 20.051522 -289.05835)
			(xy 20.06068 -289.087666) (xy 20.070505 -289.148292) (xy 20.07108 -289.179) (xy 20.07092 -289.193666)
			(xy 20.068628 -289.222907) (xy 20.066508 -289.23742) (xy 20.066 -289.24123) (xy 20.066 -290.17087)
			(xy 20.066508 -290.17468) (xy 20.068637 -290.189191) (xy 20.070926 -290.218434) (xy 20.07108 -290.2331)
			(xy 20.07092 -290.247766) (xy 20.068628 -290.277007) (xy 20.066508 -290.29152) (xy 20.066 -290.29533)
			(xy 20.066 -291.229288) (xy 20.066267 -291.236613) (xy 20.070388 -291.250671) (xy 20.074128 -291.256974)
			(xy 20.088729 -291.280302) (xy 20.111803 -291.330265) (xy 20.127461 -291.383023) (xy 20.135379 -291.437484)
			(xy 20.13585 -291.465) (xy 20.135364 -291.492252) (xy 20.127608 -291.546202) (xy 20.112253 -291.598499)
			(xy 20.089613 -291.648079) (xy 20.060147 -291.693933) (xy 20.024456 -291.735126) (xy 19.983266 -291.770822)
			(xy 19.937416 -291.800293) (xy 19.887839 -291.822939) (xy 19.835543 -291.838299) (xy 19.781594 -291.846061)
			(xy 19.754342 -291.846508) (xy 19.731383 -291.846183) (xy 19.685792 -291.840711) (xy 19.66341 -291.835586)
			(xy 19.65198 -291.832792) (xy 19.62912 -291.837618) (xy 19.556984 -291.89426) (xy 19.548265 -291.901836)
			(xy 19.538205 -291.922601) (xy 19.53768 -291.934138) (xy 19.53768 -293.886128) (xy 19.537123 -293.915102)
			(xy 19.528017 -293.97233) (xy 19.510066 -294.027428) (xy 19.483712 -294.079037) (xy 19.449605 -294.125885)
			(xy 19.429476 -294.146732) (xy 18.086578 -295.489884) (xy 18.080285 -295.49668) (xy 18.072626 -295.513527)
			(xy 18.07147 -295.531997) (xy 18.073878 -295.540938) (xy 18.10512 -295.640506) (xy 18.126202 -295.659048)
			(xy 18.140172 -295.661588) (xy 18.166216 -295.666778) (xy 18.216647 -295.683411) (xy 18.264284 -295.706879)
			(xy 18.308205 -295.736729) (xy 18.34756 -295.772382) (xy 18.38159 -295.81315) (xy 18.409635 -295.858243)
			(xy 18.431154 -295.906792) (xy 18.445731 -295.957856) (xy 18.453084 -296.010448) (xy 18.453608 -296.037)
			(xy 18.453122 -296.064251) (xy 18.445366 -296.118199) (xy 18.430011 -296.170494) (xy 18.407369 -296.220071)
			(xy 18.377903 -296.265921) (xy 18.342212 -296.307112) (xy 18.301021 -296.342803) (xy 18.255171 -296.372269)
			(xy 18.205594 -296.394911) (xy 18.153299 -296.410266) (xy 18.099351 -296.418022) (xy 18.044849 -296.418022)
			(xy 17.990901 -296.410266) (xy 17.938606 -296.394911) (xy 17.889029 -296.372269) (xy 17.843179 -296.342803)
			(xy 17.801988 -296.307112) (xy 17.766297 -296.265921) (xy 17.736831 -296.220071) (xy 17.714189 -296.170494)
			(xy 17.698834 -296.118199) (xy 17.691078 -296.064251) (xy 17.690592 -296.037) (xy 17.691003 -296.011767)
			(xy 17.697654 -295.961742) (xy 17.710827 -295.913026) (xy 17.730294 -295.866466) (xy 17.742662 -295.844468)
			(xy 17.746965 -295.836153) (xy 17.749863 -295.817673) (xy 17.745941 -295.799383) (xy 17.73572 -295.783716)
			(xy 17.720561 -295.772757) (xy 17.702479 -295.767964) (xy 17.693132 -295.768522) (xy 17.683131 -295.769567)
			(xy 17.663054 -295.77071) (xy 17.653 -295.770808) (xy 16.818102 -295.770808) (xy 16.805856 -295.771534)
			(xy 16.784114 -295.78282) (xy 16.776446 -295.792398) (xy 16.721582 -295.87063) (xy 16.71828 -295.895268)
			(xy 16.722598 -295.906952) (xy 16.733245 -295.938405) (xy 16.744732 -296.003801) (xy 16.745458 -296.037)
			(xy 16.744972 -296.064251) (xy 16.737216 -296.118199) (xy 16.721861 -296.170494) (xy 16.699219 -296.220071)
			(xy 16.669753 -296.265921) (xy 16.634062 -296.307112) (xy 16.592871 -296.342803) (xy 16.547021 -296.372269)
			(xy 16.497444 -296.394911) (xy 16.445149 -296.410266) (xy 16.391201 -296.418022) (xy 16.336699 -296.418022)
			(xy 16.282751 -296.410266) (xy 16.230456 -296.394911) (xy 16.180879 -296.372269) (xy 16.135029 -296.342803)
			(xy 16.093838 -296.307112) (xy 16.058147 -296.265921) (xy 16.028681 -296.220071) (xy 16.006039 -296.170494)
			(xy 15.990684 -296.118199) (xy 15.982928 -296.064251) (xy 15.982442 -296.037) (xy 15.983158 -296.003801)
			(xy 15.99465 -295.938404) (xy 16.005302 -295.906952) (xy 16.00962 -295.895268) (xy 16.006318 -295.87063)
			(xy 15.951454 -295.792398) (xy 15.943838 -295.782755) (xy 15.922067 -295.771449) (xy 15.909798 -295.770808)
			(xy 15.367 -295.770808) (xy 15.338025 -295.770253) (xy 15.280794 -295.761151) (xy 15.225693 -295.743205)
			(xy 15.174079 -295.716855) (xy 15.127226 -295.682751) (xy 15.106396 -295.662604) (xy 13.511022 -294.067484)
			(xy 13.503658 -294.060659) (xy 13.485148 -294.05292) (xy 13.465085 -294.052874) (xy 13.45565 -294.056308)
			(xy 13.441172 -294.062404) (xy 13.424408 -294.08755) (xy 13.424408 -297.23461) (xy 13.424884 -297.244577)
			(xy 13.432458 -297.263015) (xy 13.43914 -297.270424) (xy 13.983692 -297.815) (xy 15.111982 -297.815)
			(xy 15.116053 -297.759378) (xy 15.128179 -297.704941) (xy 15.148102 -297.65285) (xy 15.175398 -297.604215)
			(xy 15.209484 -297.560072) (xy 15.249633 -297.521363) (xy 15.294991 -297.488912) (xy 15.344591 -297.463411)
			(xy 15.397375 -297.445404) (xy 15.452218 -297.435274) (xy 15.507952 -297.433237) (xy 15.563389 -297.439337)
			(xy 15.617346 -297.453443) (xy 15.668675 -297.475255) (xy 15.716281 -297.504309) (xy 15.759149 -297.539984)
			(xy 15.796366 -297.581521) (xy 15.827139 -297.628034) (xy 15.850811 -297.678531) (xy 15.866879 -297.731938)
			(xy 15.874999 -297.787114) (xy 15.875508 -297.815) (xy 15.874999 -297.842886) (xy 15.866879 -297.898062)
			(xy 15.850811 -297.951469) (xy 15.827139 -298.001966) (xy 15.796366 -298.048479) (xy 15.759149 -298.090016)
			(xy 15.716281 -298.125691) (xy 15.668675 -298.154745) (xy 15.617346 -298.176557) (xy 15.563389 -298.190663)
			(xy 15.507952 -298.196763) (xy 15.452218 -298.194726) (xy 15.397375 -298.184596) (xy 15.344591 -298.166589)
			(xy 15.294991 -298.141088) (xy 15.249633 -298.108637) (xy 15.209484 -298.069928) (xy 15.175398 -298.025785)
			(xy 15.148102 -297.97715) (xy 15.128179 -297.925059) (xy 15.116053 -297.870622) (xy 15.111982 -297.815)
			(xy 13.983692 -297.815) (xy 15.634621 -299.466) (xy 16.089882 -299.466) (xy 16.093953 -299.410378)
			(xy 16.106079 -299.355941) (xy 16.126002 -299.30385) (xy 16.153298 -299.255215) (xy 16.187384 -299.211072)
			(xy 16.227533 -299.172363) (xy 16.272891 -299.139912) (xy 16.322491 -299.114411) (xy 16.375275 -299.096404)
			(xy 16.430118 -299.086274) (xy 16.485852 -299.084237) (xy 16.541289 -299.090337) (xy 16.595246 -299.104443)
			(xy 16.646575 -299.126255) (xy 16.694181 -299.155309) (xy 16.737049 -299.190984) (xy 16.774266 -299.232521)
			(xy 16.805039 -299.279034) (xy 16.828711 -299.329531) (xy 16.836069 -299.353986) (xy 18.493484 -299.353986)
			(xy 18.497555 -299.298364) (xy 18.509681 -299.243927) (xy 18.529604 -299.191836) (xy 18.5569 -299.143201)
			(xy 18.590986 -299.099058) (xy 18.631135 -299.060349) (xy 18.676493 -299.027898) (xy 18.726093 -299.002397)
			(xy 18.778877 -298.98439) (xy 18.83372 -298.97426) (xy 18.889454 -298.972223) (xy 18.944891 -298.978323)
			(xy 18.998848 -298.992429) (xy 19.050177 -299.014241) (xy 19.097783 -299.043295) (xy 19.140651 -299.07897)
			(xy 19.177868 -299.120507) (xy 19.208641 -299.16702) (xy 19.232313 -299.217517) (xy 19.248381 -299.270924)
			(xy 19.256501 -299.3261) (xy 19.25701 -299.353986) (xy 19.256501 -299.381872) (xy 19.248381 -299.437048)
			(xy 19.232313 -299.490455) (xy 19.208641 -299.540952) (xy 19.177868 -299.587465) (xy 19.140651 -299.629002)
			(xy 19.097783 -299.664677) (xy 19.050177 -299.693731) (xy 18.998848 -299.715543) (xy 18.944891 -299.729649)
			(xy 18.889454 -299.735749) (xy 18.83372 -299.733712) (xy 18.778877 -299.723582) (xy 18.726093 -299.705575)
			(xy 18.676493 -299.680074) (xy 18.631135 -299.647623) (xy 18.590986 -299.608914) (xy 18.5569 -299.564771)
			(xy 18.529604 -299.516136) (xy 18.509681 -299.464045) (xy 18.497555 -299.409608) (xy 18.493484 -299.353986)
			(xy 16.836069 -299.353986) (xy 16.844779 -299.382938) (xy 16.852899 -299.438114) (xy 16.853408 -299.466)
			(xy 16.852899 -299.493886) (xy 16.844779 -299.549062) (xy 16.828711 -299.602469) (xy 16.805039 -299.652966)
			(xy 16.774266 -299.699479) (xy 16.737049 -299.741016) (xy 16.694181 -299.776691) (xy 16.646575 -299.805745)
			(xy 16.595246 -299.827557) (xy 16.541289 -299.841663) (xy 16.485852 -299.847763) (xy 16.430118 -299.845726)
			(xy 16.375275 -299.835596) (xy 16.322491 -299.817589) (xy 16.272891 -299.792088) (xy 16.227533 -299.759637)
			(xy 16.187384 -299.720928) (xy 16.153298 -299.676785) (xy 16.126002 -299.62815) (xy 16.106079 -299.576059)
			(xy 16.093953 -299.521622) (xy 16.089882 -299.466) (xy 15.634621 -299.466) (xy 16.184945 -300.016348)
			(xy 30.352996 -300.016348) (xy 30.352996 -299.931652) (xy 30.361047 -299.847338) (xy 30.377076 -299.764172)
			(xy 30.400937 -299.682905) (xy 30.432416 -299.604275) (xy 30.471227 -299.528994) (xy 30.517017 -299.457742)
			(xy 30.569373 -299.391166) (xy 30.627821 -299.329868) (xy 30.691831 -299.274403) (xy 30.760823 -299.225274)
			(xy 30.834173 -299.182925) (xy 30.911216 -299.147741) (xy 30.991255 -299.120039) (xy 31.073564 -299.100071)
			(xy 31.157399 -299.088018) (xy 31.242 -299.083988) (xy 31.326601 -299.088018) (xy 31.410436 -299.100071)
			(xy 31.492745 -299.120039) (xy 31.572784 -299.147741) (xy 31.649827 -299.182925) (xy 31.723177 -299.225274)
			(xy 31.792169 -299.274403) (xy 31.856179 -299.329868) (xy 31.914627 -299.391166) (xy 31.966983 -299.457742)
			(xy 32.012773 -299.528994) (xy 32.051584 -299.604275) (xy 32.083063 -299.682905) (xy 32.106924 -299.764172)
			(xy 32.122953 -299.847338) (xy 32.131004 -299.931652) (xy 32.131508 -299.974) (xy 32.131004 -300.016348)
			(xy 32.122953 -300.100662) (xy 32.106924 -300.183828) (xy 32.083063 -300.265095) (xy 32.051584 -300.343725)
			(xy 32.012773 -300.419006) (xy 31.966983 -300.490258) (xy 31.914627 -300.556834) (xy 31.856179 -300.618132)
			(xy 31.792169 -300.673597) (xy 31.723177 -300.722726) (xy 31.649827 -300.765075) (xy 31.572784 -300.800259)
			(xy 31.492745 -300.827961) (xy 31.410436 -300.847929) (xy 31.326601 -300.859982) (xy 31.242 -300.864013)
			(xy 31.157399 -300.859982) (xy 31.073564 -300.847929) (xy 30.991255 -300.827961) (xy 30.911216 -300.800259)
			(xy 30.834173 -300.765075) (xy 30.760823 -300.722726) (xy 30.691831 -300.673597) (xy 30.627821 -300.618132)
			(xy 30.569373 -300.556834) (xy 30.517017 -300.490258) (xy 30.471227 -300.419006) (xy 30.432416 -300.343725)
			(xy 30.400937 -300.265095) (xy 30.377076 -300.183828) (xy 30.361047 -300.100662) (xy 30.352996 -300.016348)
			(xy 16.184945 -300.016348) (xy 17.988267 -301.819748) (xy 18.516596 -301.819748) (xy 18.516596 -301.735052)
			(xy 18.524647 -301.650738) (xy 18.540676 -301.567572) (xy 18.564537 -301.486305) (xy 18.596016 -301.407675)
			(xy 18.634827 -301.332394) (xy 18.680617 -301.261142) (xy 18.732973 -301.194566) (xy 18.791421 -301.133268)
			(xy 18.855431 -301.077803) (xy 18.924423 -301.028674) (xy 18.997773 -300.986325) (xy 19.074816 -300.951141)
			(xy 19.154855 -300.923439) (xy 19.237164 -300.903471) (xy 19.320999 -300.891418) (xy 19.4056 -300.887388)
			(xy 19.490201 -300.891418) (xy 19.574036 -300.903471) (xy 19.656345 -300.923439) (xy 19.736384 -300.951141)
			(xy 19.813427 -300.986325) (xy 19.886777 -301.028674) (xy 19.955769 -301.077803) (xy 20.019779 -301.133268)
			(xy 20.078227 -301.194566) (xy 20.130583 -301.261142) (xy 20.176373 -301.332394) (xy 20.215184 -301.407675)
			(xy 20.246663 -301.486305) (xy 20.270524 -301.567572) (xy 20.286553 -301.650738) (xy 20.294604 -301.735052)
			(xy 20.295108 -301.7774) (xy 20.294604 -301.819748) (xy 20.286553 -301.904062) (xy 20.270524 -301.987228)
			(xy 20.246663 -302.068495) (xy 20.215184 -302.147125) (xy 20.176373 -302.222406) (xy 20.130583 -302.293658)
			(xy 20.078227 -302.360234) (xy 20.019779 -302.421532) (xy 19.955769 -302.476997) (xy 19.886777 -302.526126)
			(xy 19.813427 -302.568475) (xy 19.736384 -302.603659) (xy 19.656345 -302.631361) (xy 19.574036 -302.651329)
			(xy 19.490201 -302.663382) (xy 19.4056 -302.667413) (xy 19.320999 -302.663382) (xy 19.237164 -302.651329)
			(xy 19.154855 -302.631361) (xy 19.074816 -302.603659) (xy 18.997773 -302.568475) (xy 18.924423 -302.526126)
			(xy 18.855431 -302.476997) (xy 18.791421 -302.421532) (xy 18.732973 -302.360234) (xy 18.680617 -302.293658)
			(xy 18.634827 -302.222406) (xy 18.596016 -302.147125) (xy 18.564537 -302.068495) (xy 18.540676 -301.987228)
			(xy 18.524647 -301.904062) (xy 18.516596 -301.819748) (xy 17.988267 -301.819748) (xy 19.310604 -303.142142)
			(xy 19.330728 -303.162993) (xy 19.364827 -303.209843) (xy 19.391175 -303.261452) (xy 19.409123 -303.316548)
			(xy 19.418229 -303.373774) (xy 19.418808 -303.402746) (xy 19.418808 -303.812702) (xy 19.420078 -303.818798)
			(xy 19.425398 -303.841477) (xy 19.431125 -303.887708) (xy 19.431508 -303.911) (xy 19.431022 -303.938251)
			(xy 19.423266 -303.992199) (xy 19.407911 -304.044494) (xy 19.385269 -304.094071) (xy 19.355803 -304.139921)
			(xy 19.320112 -304.181112) (xy 19.278921 -304.216803) (xy 19.233071 -304.246269) (xy 19.183494 -304.268911)
			(xy 19.131199 -304.284266) (xy 19.077404 -304.292) (xy 31.367982 -304.292) (xy 31.372053 -304.236378)
			(xy 31.384179 -304.181941) (xy 31.404102 -304.12985) (xy 31.431398 -304.081215) (xy 31.465484 -304.037072)
			(xy 31.505633 -303.998363) (xy 31.550991 -303.965912) (xy 31.600591 -303.940411) (xy 31.653375 -303.922404)
			(xy 31.708218 -303.912274) (xy 31.763952 -303.910237) (xy 31.819389 -303.916337) (xy 31.873346 -303.930443)
			(xy 31.924675 -303.952255) (xy 31.972281 -303.981309) (xy 32.015149 -304.016984) (xy 32.052366 -304.058521)
			(xy 32.083139 -304.105034) (xy 32.106811 -304.155531) (xy 32.117859 -304.192251) (xy 33.908978 -304.192251)
			(xy 33.908978 -304.137749) (xy 33.916734 -304.083801) (xy 33.932089 -304.031506) (xy 33.954731 -303.981929)
			(xy 33.984197 -303.936079) (xy 34.019888 -303.894888) (xy 34.061079 -303.859197) (xy 34.106929 -303.829731)
			(xy 34.156506 -303.807089) (xy 34.208801 -303.791734) (xy 34.262749 -303.783978) (xy 34.29 -303.783492)
			(xy 34.304986 -303.783746) (xy 34.319841 -303.783731) (xy 34.348572 -303.776244) (xy 34.37394 -303.760819)
			(xy 34.393806 -303.738756) (xy 34.406496 -303.711914) (xy 34.410939 -303.682559) (xy 34.40676 -303.653165)
			(xy 34.400998 -303.639474) (xy 34.389853 -303.61424) (xy 34.374126 -303.561368) (xy 34.366179 -303.506781)
			(xy 34.365692 -303.4792) (xy 34.366178 -303.451949) (xy 34.373934 -303.398001) (xy 34.389289 -303.345706)
			(xy 34.411931 -303.296129) (xy 34.441397 -303.250279) (xy 34.477088 -303.209088) (xy 34.518279 -303.173397)
			(xy 34.564129 -303.143931) (xy 34.613706 -303.121289) (xy 34.666001 -303.105934) (xy 34.719949 -303.098178)
			(xy 34.774451 -303.098178) (xy 34.828399 -303.105934) (xy 34.880694 -303.121289) (xy 34.930271 -303.143931)
			(xy 34.976121 -303.173397) (xy 35.017312 -303.209088) (xy 35.053003 -303.250279) (xy 35.082469 -303.296129)
			(xy 35.105111 -303.345706) (xy 35.106352 -303.349931) (xy 42.187052 -303.349931) (xy 42.187052 -303.270064)
			(xy 42.194881 -303.190582) (xy 42.210463 -303.112251) (xy 42.233647 -303.035824) (xy 42.264211 -302.962037)
			(xy 42.301861 -302.891602) (xy 42.346233 -302.825196) (xy 42.3969 -302.763459) (xy 42.453375 -302.706985)
			(xy 42.515113 -302.65632) (xy 42.58152 -302.611949) (xy 42.651957 -302.574302) (xy 42.725744 -302.54374)
			(xy 42.802172 -302.520557) (xy 42.880504 -302.504978) (xy 42.959986 -302.497151) (xy 43.039852 -302.497153)
			(xy 43.119334 -302.504984) (xy 43.197665 -302.520567) (xy 43.274092 -302.543753) (xy 43.347878 -302.574318)
			(xy 43.418313 -302.611969) (xy 43.484718 -302.656343) (xy 43.546454 -302.707011) (xy 43.602926 -302.763487)
			(xy 43.65359 -302.825227) (xy 43.697959 -302.891635) (xy 43.735605 -302.962072) (xy 43.766166 -303.03586)
			(xy 43.789347 -303.112288) (xy 43.804925 -303.190621) (xy 43.812749 -303.270103) (xy 43.813222 -303.310036)
			(xy 43.812747 -303.349165) (xy 43.805235 -303.427063) (xy 43.790274 -303.503878) (xy 43.768003 -303.578901)
			(xy 43.738628 -303.651438) (xy 43.702421 -303.720817) (xy 43.659716 -303.786396) (xy 43.635676 -303.817274)
			(xy 43.625516 -303.829974) (xy 43.623484 -303.861978) (xy 43.691048 -303.970944) (xy 43.720512 -303.98339)
			(xy 43.73626 -303.980088) (xy 43.788329 -303.969494) (xy 43.893742 -303.956065) (xy 43.999912 -303.951578)
			(xy 44.106082 -303.956065) (xy 44.211495 -303.969494) (xy 44.263564 -303.980088) (xy 44.279312 -303.98339)
			(xy 44.308776 -303.970944) (xy 44.37634 -303.861978) (xy 44.374308 -303.829974) (xy 44.364148 -303.817274)
			(xy 44.340118 -303.786389) (xy 44.297415 -303.720809) (xy 44.261207 -303.651431) (xy 44.23183 -303.578896)
			(xy 44.209555 -303.503875) (xy 44.194589 -303.427061) (xy 44.187069 -303.349165) (xy 44.186602 -303.310036)
			(xy 44.187096 -303.270105) (xy 44.194924 -303.190628) (xy 44.210505 -303.1123) (xy 44.233688 -303.035877)
			(xy 44.26425 -302.962095) (xy 44.301897 -302.891663) (xy 44.346266 -302.82526) (xy 44.39693 -302.763527)
			(xy 44.453401 -302.707056) (xy 44.515136 -302.656392) (xy 44.581539 -302.612024) (xy 44.651971 -302.574377)
			(xy 44.725754 -302.543816) (xy 44.802177 -302.520633) (xy 44.880504 -302.505053) (xy 44.959982 -302.497226)
			(xy 45.039844 -302.497226) (xy 45.119321 -302.505054) (xy 45.197648 -302.520634) (xy 45.274071 -302.543817)
			(xy 45.347854 -302.574379) (xy 45.418286 -302.612026) (xy 45.484689 -302.656395) (xy 45.546422 -302.707059)
			(xy 45.602893 -302.76353) (xy 45.653557 -302.825265) (xy 45.697926 -302.891668) (xy 45.735572 -302.9621)
			(xy 45.766134 -303.035882) (xy 45.789316 -303.112306) (xy 45.804897 -303.190633) (xy 45.812724 -303.27011)
			(xy 45.812724 -303.349972) (xy 45.804896 -303.42945) (xy 45.789316 -303.507777) (xy 45.766133 -303.5842)
			(xy 45.735571 -303.657983) (xy 45.697924 -303.728415) (xy 45.653555 -303.794817) (xy 45.602891 -303.856552)
			(xy 45.546421 -303.913022) (xy 45.484686 -303.963686) (xy 45.418284 -304.008055) (xy 45.347852 -304.045702)
			(xy 45.274069 -304.076263) (xy 45.197646 -304.099446) (xy 45.119318 -304.115026) (xy 45.039841 -304.122854)
			(xy 44.99991 -304.123344) (xy 44.985356 -304.123288) (xy 44.956266 -304.122273) (xy 44.941744 -304.121312)
			(xy 44.925488 -304.120042) (xy 44.898056 -304.136552) (xy 44.846494 -304.2539) (xy 44.852844 -304.285142)
			(xy 44.864528 -304.296318) (xy 44.90049 -304.331033) (xy 44.967413 -304.405289) (xy 45.028231 -304.484624)
			(xy 45.08256 -304.568535) (xy 45.130057 -304.656494) (xy 45.170422 -304.747945) (xy 45.203401 -304.842312)
			(xy 45.228785 -304.938999) (xy 45.246415 -305.037395) (xy 45.256179 -305.136881) (xy 45.258016 -305.236828)
			(xy 45.251913 -305.336605) (xy 45.23791 -305.435583) (xy 45.216095 -305.533137) (xy 45.186605 -305.628651)
			(xy 45.149627 -305.721524) (xy 45.105394 -305.811169) (xy 45.054185 -305.897019) (xy 44.996323 -305.978534)
			(xy 44.932173 -306.055199) (xy 44.862141 -306.12653) (xy 44.786667 -306.192078) (xy 44.706229 -306.251428)
			(xy 44.621334 -306.304206) (xy 44.532517 -306.350078) (xy 44.440339 -306.388757) (xy 44.345383 -306.419996)
			(xy 44.248246 -306.4436) (xy 44.149542 -306.459419) (xy 44.049894 -306.467354) (xy 43.94993 -306.467354)
			(xy 43.850282 -306.459419) (xy 43.751578 -306.4436) (xy 43.654441 -306.419996) (xy 43.559485 -306.388757)
			(xy 43.467307 -306.350078) (xy 43.37849 -306.304206) (xy 43.293595 -306.251428) (xy 43.213157 -306.192078)
			(xy 43.137683 -306.12653) (xy 43.067651 -306.055199) (xy 43.003501 -305.978534) (xy 42.945639 -305.897019)
			(xy 42.89443 -305.811169) (xy 42.850197 -305.721524) (xy 42.813219 -305.628651) (xy 42.783729 -305.533137)
			(xy 42.761914 -305.435583) (xy 42.747911 -305.336605) (xy 42.741808 -305.236828) (xy 42.743645 -305.136881)
			(xy 42.753409 -305.037395) (xy 42.771039 -304.938999) (xy 42.796423 -304.842312) (xy 42.829402 -304.747945)
			(xy 42.869767 -304.656494) (xy 42.917264 -304.568535) (xy 42.971593 -304.484624) (xy 43.032411 -304.405289)
			(xy 43.099334 -304.331033) (xy 43.135296 -304.296318) (xy 43.14698 -304.285142) (xy 43.15333 -304.2539)
			(xy 43.101768 -304.136552) (xy 43.074336 -304.120042) (xy 43.05808 -304.121312) (xy 43.043558 -304.122277)
			(xy 43.014468 -304.123293) (xy 42.999914 -304.123344) (xy 42.959981 -304.122848) (xy 42.880499 -304.115021)
			(xy 42.802167 -304.099441) (xy 42.725739 -304.076258) (xy 42.651952 -304.045696) (xy 42.581516 -304.008048)
			(xy 42.515109 -303.963677) (xy 42.453371 -303.913011) (xy 42.396897 -303.856537) (xy 42.34623 -303.7948)
			(xy 42.301858 -303.728394) (xy 42.264209 -303.657958) (xy 42.233645 -303.584171) (xy 42.210461 -303.507744)
			(xy 42.19488 -303.429412) (xy 42.187052 -303.349931) (xy 35.106352 -303.349931) (xy 35.120466 -303.398001)
			(xy 35.128222 -303.451949) (xy 35.128222 -303.506451) (xy 35.120466 -303.560399) (xy 35.105111 -303.612694)
			(xy 35.082469 -303.662271) (xy 35.053003 -303.708121) (xy 35.017312 -303.749312) (xy 34.976121 -303.785003)
			(xy 34.930271 -303.814469) (xy 34.880694 -303.837111) (xy 34.828399 -303.852466) (xy 34.774451 -303.860222)
			(xy 34.7472 -303.860708) (xy 34.732214 -303.860454) (xy 34.717359 -303.860469) (xy 34.688628 -303.867956)
			(xy 34.66326 -303.883381) (xy 34.643394 -303.905444) (xy 34.630704 -303.932286) (xy 34.626261 -303.961641)
			(xy 34.63044 -303.991035) (xy 34.636202 -304.004726) (xy 34.647347 -304.02996) (xy 34.663074 -304.082832)
			(xy 34.671021 -304.137419) (xy 34.671508 -304.165) (xy 34.671022 -304.192251) (xy 34.663266 -304.246199)
			(xy 34.647911 -304.298494) (xy 34.625269 -304.348071) (xy 34.595803 -304.393921) (xy 34.560112 -304.435112)
			(xy 34.518921 -304.470803) (xy 34.473071 -304.500269) (xy 34.423494 -304.522911) (xy 34.371199 -304.538266)
			(xy 34.317251 -304.546022) (xy 34.262749 -304.546022) (xy 34.208801 -304.538266) (xy 34.156506 -304.522911)
			(xy 34.106929 -304.500269) (xy 34.061079 -304.470803) (xy 34.019888 -304.435112) (xy 33.984197 -304.393921)
			(xy 33.954731 -304.348071) (xy 33.932089 -304.298494) (xy 33.916734 -304.246199) (xy 33.908978 -304.192251)
			(xy 32.117859 -304.192251) (xy 32.122879 -304.208938) (xy 32.130999 -304.264114) (xy 32.131508 -304.292)
			(xy 32.130999 -304.319886) (xy 32.122879 -304.375062) (xy 32.106811 -304.428469) (xy 32.083139 -304.478966)
			(xy 32.052366 -304.525479) (xy 32.015149 -304.567016) (xy 31.972281 -304.602691) (xy 31.924675 -304.631745)
			(xy 31.873346 -304.653557) (xy 31.819389 -304.667663) (xy 31.763952 -304.673763) (xy 31.708218 -304.671726)
			(xy 31.653375 -304.661596) (xy 31.600591 -304.643589) (xy 31.550991 -304.618088) (xy 31.505633 -304.585637)
			(xy 31.465484 -304.546928) (xy 31.431398 -304.502785) (xy 31.404102 -304.45415) (xy 31.384179 -304.402059)
			(xy 31.372053 -304.347622) (xy 31.367982 -304.292) (xy 19.077404 -304.292) (xy 19.077251 -304.292022)
			(xy 19.022749 -304.292022) (xy 18.968801 -304.284266) (xy 18.916506 -304.268911) (xy 18.866929 -304.246269)
			(xy 18.821079 -304.216803) (xy 18.779888 -304.181112) (xy 18.744197 -304.139921) (xy 18.714731 -304.094071)
			(xy 18.692089 -304.044494) (xy 18.676734 -303.992199) (xy 18.668978 -303.938251) (xy 18.668492 -303.911)
			(xy 18.66887 -303.887708) (xy 18.674597 -303.841476) (xy 18.679922 -303.818798) (xy 18.681192 -303.812702)
			(xy 18.681192 -303.576482) (xy 18.680714 -303.566516) (xy 18.673138 -303.54808) (xy 18.66646 -303.540668)
			(xy 15.145512 -300.019466) (xy 15.138895 -300.013409) (xy 15.122598 -300.005937) (xy 15.104727 -300.004502)
			(xy 15.095982 -300.006512) (xy 14.99743 -300.03369) (xy 14.97838 -300.053248) (xy 14.975078 -300.06671)
			(xy 14.967763 -300.093851) (xy 14.946252 -300.145781) (xy 14.917353 -300.193993) (xy 14.881694 -300.237443)
			(xy 14.840045 -300.27519) (xy 14.793308 -300.306418) (xy 14.742495 -300.33045) (xy 14.688706 -300.346766)
			(xy 14.633105 -300.355014) (xy 14.605 -300.355508) (xy 14.577749 -300.355022) (xy 14.523801 -300.347266)
			(xy 14.471506 -300.331911) (xy 14.421929 -300.309269) (xy 14.376079 -300.279803) (xy 14.334888 -300.244112)
			(xy 14.299197 -300.202921) (xy 14.269731 -300.157071) (xy 14.247089 -300.107494) (xy 14.231734 -300.055199)
			(xy 14.223978 -300.001251) (xy 14.223492 -299.974) (xy 14.223992 -299.945896) (xy 14.232239 -299.890296)
			(xy 14.248556 -299.836507) (xy 14.272587 -299.785695) (xy 14.303815 -299.738959) (xy 14.341561 -299.697311)
			(xy 14.385011 -299.661652) (xy 14.433222 -299.632754) (xy 14.485151 -299.611242) (xy 14.51229 -299.603922)
			(xy 14.525752 -299.60062) (xy 14.54531 -299.58157) (xy 14.572488 -299.483018) (xy 14.574578 -299.474281)
			(xy 14.57316 -299.456384) (xy 14.56563 -299.440087) (xy 14.559534 -299.433488) (xy 12.794996 -297.66895)
			(xy 12.774873 -297.648099) (xy 12.740775 -297.601248) (xy 12.714428 -297.549639) (xy 12.696481 -297.494544)
			(xy 12.687376 -297.437318) (xy 12.686792 -297.408346) (xy 12.686792 -288.958274) (xy 12.686313 -288.948309)
			(xy 12.678735 -288.929875) (xy 12.67206 -288.92246) (xy 12.486386 -288.736786) (xy 12.478991 -288.729932)
			(xy 12.460392 -288.72219) (xy 12.450318 -288.7218) (xy 11.830812 -288.7218) (xy 11.820741 -288.722221)
			(xy 11.802133 -288.729932) (xy 11.794744 -288.736786) (xy 9.485122 -291.046408) (xy 9.478264 -291.073078)
			(xy 9.482074 -291.08654) (xy 9.492026 -291.122952) (xy 9.505935 -291.197149) (xy 9.512908 -291.272315)
			(xy 9.513316 -291.31006) (xy 9.512826 -291.349991) (xy 9.504998 -291.429469) (xy 9.489418 -291.507796)
			(xy 9.466235 -291.58422) (xy 9.435673 -291.658003) (xy 9.398027 -291.728435) (xy 9.353658 -291.794838)
			(xy 9.302994 -291.856572) (xy 9.246523 -291.913043) (xy 9.184788 -291.963707) (xy 9.118385 -292.008076)
			(xy 9.047953 -292.045723) (xy 8.97417 -292.076285) (xy 8.897747 -292.099468) (xy 8.819419 -292.115048)
			(xy 8.739942 -292.122876) (xy 8.66008 -292.122876) (xy 8.580602 -292.115048) (xy 8.502274 -292.099468)
			(xy 8.425851 -292.076286) (xy 8.352068 -292.045724) (xy 8.281636 -292.008077) (xy 8.215233 -291.963708)
			(xy 8.153498 -291.913044) (xy 8.097027 -291.856573) (xy 8.046363 -291.794839) (xy 8.001994 -291.728436)
			(xy 7.964347 -291.658004) (xy 7.933785 -291.584221) (xy 7.910602 -291.507798) (xy 7.895022 -291.42947)
			(xy 7.887194 -291.349992) (xy 7.887194 -291.27013) (xy 7.895021 -291.190653) (xy 7.910602 -291.112325)
			(xy 7.933784 -291.035902) (xy 7.964346 -290.962119) (xy 8.001993 -290.891686) (xy 8.046362 -290.825283)
			(xy 8.097025 -290.763549) (xy 8.153496 -290.707078) (xy 8.215231 -290.656414) (xy 8.281633 -290.612044)
			(xy 8.352066 -290.574397) (xy 8.425848 -290.543835) (xy 8.502272 -290.520652) (xy 8.580599 -290.505072)
			(xy 8.660077 -290.497244) (xy 8.700008 -290.496752) (xy 8.737753 -290.497167) (xy 8.81292 -290.504134)
			(xy 8.887118 -290.518035) (xy 8.923528 -290.527994) (xy 8.93699 -290.531804) (xy 8.96366 -290.524946)
			(xy 11.19886 -288.289746) (xy 11.205556 -288.282341) (xy 11.213161 -288.263904) (xy 11.213592 -288.253932)
			(xy 11.213592 -288.0106) (xy 11.214147 -287.981625) (xy 11.223249 -287.924394) (xy 11.241195 -287.869293)
			(xy 11.267545 -287.817679) (xy 11.301649 -287.770826) (xy 11.321796 -287.749996) (xy 15.284704 -283.786834)
			(xy 15.291393 -283.779426) (xy 15.298987 -283.76099) (xy 15.299436 -283.75102) (xy 15.299436 -283.162756)
			(xy 15.299994 -283.133782) (xy 15.309101 -283.076553) (xy 15.32705 -283.021455) (xy 15.353401 -282.969844)
			(xy 15.387504 -282.922992) (xy 15.40764 -282.902152) (xy 20.145502 -278.164036) (xy 20.152302 -278.156687)
			(xy 20.160011 -278.138225) (xy 20.160488 -278.128222) (xy 20.160488 -253.729236) (xy 20.159957 -253.719246)
			(xy 20.152251 -253.700805) (xy 20.145502 -253.693422) (xy 13.917676 -247.465342) (xy 13.897554 -247.444491)
			(xy 13.863459 -247.397639) (xy 13.837115 -247.34603) (xy 13.81917 -247.290934) (xy 13.810067 -247.23371)
			(xy 13.809472 -247.204738) (xy 13.809472 -224.968562) (xy 13.809012 -224.957874) (xy 13.800329 -224.938342)
			(xy 13.784443 -224.924042) (xy 13.77442 -224.920302) (xy 13.666724 -224.885504) (xy 13.635482 -224.895664)
			(xy 13.62583 -224.909126) (xy 13.600796 -224.942855) (xy 13.545325 -225.005938) (xy 13.484154 -225.06351)
			(xy 13.41783 -225.115061) (xy 13.346941 -225.16013) (xy 13.27212 -225.198317) (xy 13.194032 -225.229282)
			(xy 13.113374 -225.252748) (xy 13.030863 -225.268507) (xy 12.947233 -225.276419) (xy 12.905232 -225.276918)
			(xy 12.866942 -225.276509) (xy 12.790648 -225.269903) (xy 12.715206 -225.256754) (xy 12.641175 -225.23716)
			(xy 12.605004 -225.224594) (xy 12.596566 -225.221952) (xy 12.578898 -225.221952) (xy 12.57046 -225.224594)
			(xy 12.534282 -225.237138) (xy 12.46025 -225.256713) (xy 12.38481 -225.26986) (xy 12.30852 -225.276481)
			(xy 12.270232 -225.276918) (xy 12.229128 -225.276459) (xy 12.14727 -225.268877) (xy 12.06646 -225.253774)
			(xy 11.987389 -225.231279) (xy 11.910731 -225.201584) (xy 11.83714 -225.164943) (xy 11.767244 -225.121667)
			(xy 11.701639 -225.072127) (xy 11.640885 -225.016745) (xy 11.5855 -224.955994) (xy 11.535956 -224.890391)
			(xy 11.492678 -224.820497) (xy 11.456033 -224.746907) (xy 11.426335 -224.670251) (xy 11.403836 -224.591181)
			(xy 11.388729 -224.510372) (xy 11.381143 -224.428514) (xy 11.380724 -224.38741) (xy 11.381308 -224.341014)
			(xy 11.390941 -224.248723) (xy 11.410134 -224.157938) (xy 11.438678 -224.069646) (xy 11.456924 -224.026984)
			(xy 11.460746 -224.017044) (xy 11.460749 -223.995774) (xy 11.456924 -223.985836) (xy 11.438685 -223.943171)
			(xy 11.410145 -223.854878) (xy 11.390947 -223.764094) (xy 11.381301 -223.671806) (xy 11.380724 -223.62541)
			(xy 11.381308 -223.579014) (xy 11.390941 -223.486723) (xy 11.410134 -223.395938) (xy 11.438678 -223.307646)
			(xy 11.456924 -223.264984) (xy 11.460746 -223.255044) (xy 11.460749 -223.233774) (xy 11.456924 -223.223836)
			(xy 11.438685 -223.181171) (xy 11.410145 -223.092878) (xy 11.390947 -223.002094) (xy 11.381301 -222.909806)
			(xy 11.380724 -222.86341) (xy 11.381184 -222.822307) (xy 11.388768 -222.740452) (xy 11.403873 -222.659646)
			(xy 11.426369 -222.580578) (xy 11.456065 -222.503923) (xy 11.492708 -222.430336) (xy 11.535984 -222.360443)
			(xy 11.585525 -222.294842) (xy 11.640907 -222.234092) (xy 11.701659 -222.178711) (xy 11.767261 -222.129172)
			(xy 11.837155 -222.085897) (xy 11.910743 -222.049257) (xy 11.987399 -222.019562) (xy 12.066467 -221.997068)
			(xy 12.147274 -221.981965) (xy 12.229129 -221.974383) (xy 12.270232 -221.973902) (xy 12.308522 -221.97431)
			(xy 12.384817 -221.980913) (xy 12.46026 -221.994059) (xy 12.534292 -222.013651) (xy 12.57046 -222.026226)
			(xy 12.578898 -222.028868) (xy 12.596566 -222.028868) (xy 12.605004 -222.026226) (xy 12.641181 -222.013681)
			(xy 12.715213 -221.994102) (xy 12.790653 -221.980952) (xy 12.866944 -221.974328) (xy 12.905232 -221.973902)
			(xy 12.947233 -221.97439) (xy 13.030862 -221.982309) (xy 13.113371 -221.998074) (xy 13.194029 -222.021544)
			(xy 13.272115 -222.052511) (xy 13.346936 -222.090698) (xy 13.417825 -222.135767) (xy 13.484151 -222.187315)
			(xy 13.545325 -222.244884) (xy 13.600801 -222.307962) (xy 13.62583 -222.341694) (xy 13.635482 -222.355156)
			(xy 13.666724 -222.365316) (xy 13.77442 -222.330518) (xy 13.78438 -222.326679) (xy 13.800208 -222.312395)
			(xy 13.80888 -222.292918) (xy 13.809472 -222.282258) (xy 13.809472 -216.210896) (xy 13.808997 -216.200929)
			(xy 13.801422 -216.182491) (xy 13.79474 -216.175082) (xy 10.359644 -212.739986) (xy 10.352247 -212.733139)
			(xy 10.333647 -212.725412) (xy 10.323576 -212.725) (xy 5.609082 -212.725) (xy 5.599013 -212.725427)
			(xy 5.580414 -212.733146) (xy 5.573014 -212.739986) (xy 4.484878 -213.828122) (xy 4.478027 -213.835518)
			(xy 4.470288 -213.854117) (xy 4.469892 -213.86419) (xy 4.469892 -217.150696) (xy 4.469469 -217.160766)
			(xy 4.461755 -217.179371) (xy 4.454906 -217.186764) (xy 4.30784 -217.33383) (xy 4.301098 -217.341201)
			(xy 4.29351 -217.359663) (xy 4.293108 -217.369644) (xy 4.293108 -218.863418) (xy 4.294378 -218.86926)
			(xy 4.305676 -218.919943) (xy 4.317768 -219.023079) (xy 4.318508 -219.075) (xy 4.318033 -219.116102)
			(xy 4.310448 -219.197957) (xy 4.295343 -219.278762) (xy 4.272847 -219.357829) (xy 4.243151 -219.434483)
			(xy 4.206509 -219.50807) (xy 4.163234 -219.577962) (xy 4.113694 -219.643563) (xy 4.058313 -219.704313)
			(xy 3.997563 -219.759694) (xy 3.931962 -219.809234) (xy 3.86207 -219.852509) (xy 3.788483 -219.889151)
			(xy 3.711829 -219.918847) (xy 3.632762 -219.941343) (xy 3.551957 -219.956448) (xy 3.470102 -219.964033)
			(xy 3.429 -219.964508) (xy 3.38201 -219.963898) (xy 3.288554 -219.953987) (xy 3.196664 -219.934276)
			(xy 3.107365 -219.904985) (xy 3.064256 -219.886276) (xy 3.052318 -219.880942) (xy 3.026918 -219.88272)
			(xy 2.944114 -219.936314) (xy 2.937181 -219.941176) (xy 2.926764 -219.954512) (xy 2.921284 -219.970523)
			(xy 2.921 -219.978986) (xy 2.921 -220.706696) (xy 2.921321 -220.715466) (xy 2.927184 -220.731992)
			(xy 2.938318 -220.745539) (xy 2.945638 -220.750384) (xy 3.032252 -220.8022) (xy 3.058668 -220.802708)
			(xy 3.070606 -220.796358) (xy 3.098542 -220.782066) (xy 3.157927 -220.761803) (xy 3.219827 -220.751525)
			(xy 3.2512 -220.750892) (xy 3.277518 -220.751314) (xy 3.329659 -220.758517) (xy 3.380312 -220.772826)
			(xy 3.428515 -220.79397) (xy 3.473349 -220.821546) (xy 3.513961 -220.85503) (xy 3.532124 -220.874082)
			(xy 3.539619 -220.881523) (xy 3.558914 -220.890045) (xy 3.569462 -220.890592) (xy 3.644138 -220.890592)
			(xy 3.654676 -220.890013) (xy 3.673963 -220.881494) (xy 3.681476 -220.874082) (xy 3.699625 -220.855019)
			(xy 3.740255 -220.821558) (xy 3.785096 -220.793995) (xy 3.833298 -220.772852) (xy 3.883947 -220.758531)
			(xy 3.936083 -220.751301) (xy 3.9624 -220.750892) (xy 3.989651 -220.751378) (xy 4.043599 -220.759134)
			(xy 4.095894 -220.774489) (xy 4.145471 -220.797131) (xy 4.191321 -220.826597) (xy 4.232512 -220.862288)
			(xy 4.268203 -220.903479) (xy 4.297669 -220.949329) (xy 4.320311 -220.998906) (xy 4.335666 -221.051201)
			(xy 4.343422 -221.105149) (xy 4.343908 -221.1324) (xy 4.343362 -221.161842) (xy 4.334317 -221.220027)
			(xy 4.316442 -221.276131) (xy 4.290161 -221.328825) (xy 4.256097 -221.376855) (xy 4.235958 -221.398338)
			(xy 4.228592 -221.405958) (xy 4.221226 -221.4245) (xy 4.223512 -221.517972) (xy 4.23164 -221.53626)
			(xy 4.23926 -221.543372) (xy 4.257979 -221.561484) (xy 4.290828 -221.601907) (xy 4.317872 -221.646423)
			(xy 4.338608 -221.694205) (xy 4.352649 -221.744364) (xy 4.359735 -221.795966) (xy 4.360164 -221.82201)
			(xy 4.359629 -221.850926) (xy 4.3509 -221.908095) (xy 4.333644 -221.963293) (xy 4.308255 -222.015254)
			(xy 4.275316 -222.062789) (xy 4.235581 -222.104808) (xy 4.213098 -222.123) (xy 4.204313 -222.130541)
			(xy 4.194141 -222.151314) (xy 4.19354 -222.162878) (xy 4.19354 -222.243142) (xy 4.194159 -222.254696)
			(xy 4.204349 -222.275445) (xy 4.213098 -222.28302) (xy 4.233881 -222.299773) (xy 4.271012 -222.338126)
			(xy 4.302434 -222.381281) (xy 4.327533 -222.428394) (xy 4.345819 -222.478547) (xy 4.356936 -222.530758)
			(xy 4.360666 -222.58401) (xy 4.356936 -222.637262) (xy 4.345819 -222.689473) (xy 4.327533 -222.739626)
			(xy 4.302434 -222.786739) (xy 4.271012 -222.829894) (xy 4.233881 -222.868247) (xy 4.213098 -222.885)
			(xy 4.204313 -222.892541) (xy 4.194141 -222.913314) (xy 4.19354 -222.924878) (xy 4.19354 -223.005142)
			(xy 4.194159 -223.016696) (xy 4.204349 -223.037445) (xy 4.213098 -223.04502) (xy 4.235584 -223.063209)
			(xy 4.275327 -223.105225) (xy 4.308273 -223.152759) (xy 4.333665 -223.204721) (xy 4.350924 -223.259921)
			(xy 4.359652 -223.317093) (xy 4.360164 -223.34601) (xy 4.359701 -223.373263) (xy 4.351944 -223.427213)
			(xy 4.336588 -223.479511) (xy 4.313945 -223.529091) (xy 4.284477 -223.574944) (xy 4.248783 -223.616136)
			(xy 4.207591 -223.651829) (xy 4.161737 -223.681297) (xy 4.112157 -223.703939) (xy 4.05986 -223.719295)
			(xy 4.005909 -223.727051) (xy 3.978656 -223.727518) (xy 3.952336 -223.727099) (xy 3.900191 -223.719904)
			(xy 3.849533 -223.705601) (xy 3.801325 -223.684462) (xy 3.756484 -223.65689) (xy 3.715865 -223.623409)
			(xy 3.697732 -223.604328) (xy 3.690241 -223.596877) (xy 3.670946 -223.588332) (xy 3.660394 -223.587818)
			(xy 3.585718 -223.587818) (xy 3.575184 -223.588406) (xy 3.555911 -223.596937) (xy 3.54838 -223.604328)
			(xy 3.53023 -223.623389) (xy 3.489598 -223.656844) (xy 3.444757 -223.684401) (xy 3.396555 -223.705537)
			(xy 3.345907 -223.719853) (xy 3.293772 -223.727076) (xy 3.267456 -223.727518) (xy 3.24211 -223.727101)
			(xy 3.191865 -223.720385) (xy 3.142951 -223.707079) (xy 3.096229 -223.687415) (xy 3.074162 -223.67494)
			(xy 3.062224 -223.667828) (xy 3.035046 -223.667828) (xy 2.946654 -223.718374) (xy 2.939046 -223.723107)
			(xy 2.927493 -223.736788) (xy 2.921371 -223.753615) (xy 2.921 -223.76257) (xy 2.921 -229.353872)
			(xy 2.921436 -229.363936) (xy 2.929169 -229.382522) (xy 2.935986 -229.38994) (xy 2.9718 -229.425754)
			(xy 2.999052 -229.42624) (xy 3.053002 -229.433996) (xy 3.105299 -229.449351) (xy 3.154879 -229.471991)
			(xy 3.200732 -229.501457) (xy 3.241925 -229.537148) (xy 3.27762 -229.578338) (xy 3.30709 -229.624188)
			(xy 3.329736 -229.673765) (xy 3.345096 -229.726061) (xy 3.352858 -229.78001) (xy 3.353308 -229.807262)
			(xy 3.352773 -229.836178) (xy 3.344044 -229.893347) (xy 3.326788 -229.948545) (xy 3.301399 -230.000506)
			(xy 3.26846 -230.048041) (xy 3.228725 -230.09006) (xy 3.206242 -230.108252) (xy 3.197456 -230.115795)
			(xy 3.187277 -230.136565) (xy 3.186684 -230.14813) (xy 3.186684 -230.228394) (xy 3.187291 -230.239955)
			(xy 3.197462 -230.260728) (xy 3.206242 -230.268272) (xy 3.228728 -230.286461) (xy 3.268471 -230.328476)
			(xy 3.301414 -230.37601) (xy 3.326804 -230.427973) (xy 3.330318 -230.439214) (xy 7.371842 -230.439214)
			(xy 7.372426 -230.392818) (xy 7.38207 -230.30053) (xy 7.401265 -230.209746) (xy 7.429804 -230.121453)
			(xy 7.448042 -230.078788) (xy 7.451853 -230.068845) (xy 7.451858 -230.04758) (xy 7.448042 -230.03764)
			(xy 7.429805 -229.994975) (xy 7.401258 -229.906684) (xy 7.382063 -229.815899) (xy 7.372428 -229.72361)
			(xy 7.371842 -229.677214) (xy 7.372346 -229.634866) (xy 7.380397 -229.550552) (xy 7.396426 -229.467386)
			(xy 7.420287 -229.386119) (xy 7.451766 -229.307489) (xy 7.490577 -229.232208) (xy 7.536367 -229.160956)
			(xy 7.588723 -229.09438) (xy 7.647171 -229.033082) (xy 7.711181 -228.977617) (xy 7.780173 -228.928488)
			(xy 7.853523 -228.886139) (xy 7.930566 -228.850955) (xy 8.010605 -228.823253) (xy 8.092914 -228.803285)
			(xy 8.176749 -228.791232) (xy 8.26135 -228.787202) (xy 8.345951 -228.791232) (xy 8.429786 -228.803285)
			(xy 8.512095 -228.823253) (xy 8.592134 -228.850955) (xy 8.669177 -228.886139) (xy 8.742527 -228.928488)
			(xy 8.811519 -228.977617) (xy 8.875529 -229.033082) (xy 8.933977 -229.09438) (xy 8.986333 -229.160956)
			(xy 9.032123 -229.232208) (xy 9.070934 -229.307489) (xy 9.102413 -229.386119) (xy 9.126274 -229.467386)
			(xy 9.142303 -229.550552) (xy 9.150354 -229.634866) (xy 9.150858 -229.677214) (xy 9.150284 -229.72361)
			(xy 9.140637 -229.815899) (xy 9.121439 -229.906682) (xy 9.092897 -229.994976) (xy 9.074658 -230.03764)
			(xy 9.070831 -230.047577) (xy 9.070836 -230.068848) (xy 9.074658 -230.078788) (xy 9.092904 -230.12145)
			(xy 9.121449 -230.209742) (xy 9.140641 -230.300527) (xy 9.150274 -230.392818) (xy 9.150858 -230.439214)
			(xy 9.150354 -230.481562) (xy 9.142303 -230.565876) (xy 9.126274 -230.649042) (xy 9.102413 -230.730309)
			(xy 9.070934 -230.808939) (xy 9.032123 -230.88422) (xy 8.986333 -230.955472) (xy 8.933977 -231.022048)
			(xy 8.875529 -231.083346) (xy 8.811519 -231.138811) (xy 8.742527 -231.18794) (xy 8.669177 -231.230289)
			(xy 8.592134 -231.265473) (xy 8.512095 -231.293175) (xy 8.429786 -231.313143) (xy 8.345951 -231.325196)
			(xy 8.26135 -231.329227) (xy 8.176749 -231.325196) (xy 8.092914 -231.313143) (xy 8.010605 -231.293175)
			(xy 7.930566 -231.265473) (xy 7.853523 -231.230289) (xy 7.780173 -231.18794) (xy 7.711181 -231.138811)
			(xy 7.647171 -231.083346) (xy 7.588723 -231.022048) (xy 7.536367 -230.955472) (xy 7.490577 -230.88422)
			(xy 7.451766 -230.808939) (xy 7.420287 -230.730309) (xy 7.396426 -230.649042) (xy 7.380397 -230.565876)
			(xy 7.372346 -230.481562) (xy 7.371842 -230.439214) (xy 3.330318 -230.439214) (xy 3.344058 -230.483173)
			(xy 3.35278 -230.540345) (xy 3.353308 -230.569262) (xy 3.352822 -230.596513) (xy 3.345065 -230.650461)
			(xy 3.32971 -230.702755) (xy 3.307069 -230.752332) (xy 3.277602 -230.798182) (xy 3.241911 -230.839372)
			(xy 3.200721 -230.875064) (xy 3.15487 -230.90453) (xy 3.105293 -230.927171) (xy 3.052999 -230.942526)
			(xy 2.999051 -230.950282) (xy 2.9718 -230.95077) (xy 2.935986 -230.986584) (xy 2.929143 -230.993983)
			(xy 2.921426 -231.012582) (xy 2.921 -231.022652) (xy 2.921 -232.147872) (xy 2.921436 -232.157936)
			(xy 2.929169 -232.176522) (xy 2.935986 -232.18394) (xy 2.9718 -232.219754) (xy 2.999052 -232.22024)
			(xy 3.053002 -232.227996) (xy 3.105299 -232.243351) (xy 3.154879 -232.265991) (xy 3.200732 -232.295457)
			(xy 3.241925 -232.331148) (xy 3.27762 -232.372338) (xy 3.30709 -232.418188) (xy 3.329736 -232.467765)
			(xy 3.345096 -232.520061) (xy 3.352858 -232.57401) (xy 3.353308 -232.601262) (xy 3.352773 -232.630178)
			(xy 3.344044 -232.687347) (xy 3.326788 -232.742545) (xy 3.301399 -232.794506) (xy 3.26846 -232.842041)
			(xy 3.228725 -232.88406) (xy 3.206242 -232.902252) (xy 3.197456 -232.909795) (xy 3.187277 -232.930565)
			(xy 3.186684 -232.94213) (xy 3.186684 -233.022394) (xy 3.187291 -233.033955) (xy 3.197462 -233.054728)
			(xy 3.206242 -233.062272) (xy 3.228728 -233.080461) (xy 3.268471 -233.122476) (xy 3.301414 -233.17001)
			(xy 3.326804 -233.221973) (xy 3.344058 -233.277173) (xy 3.35278 -233.334345) (xy 3.353308 -233.363262)
			(xy 3.352822 -233.390513) (xy 3.345065 -233.444461) (xy 3.32971 -233.496755) (xy 3.307069 -233.546332)
			(xy 3.277602 -233.592182) (xy 3.241911 -233.633372) (xy 3.200721 -233.669064) (xy 3.15487 -233.69853)
			(xy 3.105293 -233.721171) (xy 3.052999 -233.736526) (xy 2.999051 -233.744282) (xy 2.9718 -233.74477)
			(xy 2.935986 -233.780584) (xy 2.929143 -233.787983) (xy 2.921426 -233.806582) (xy 2.921 -233.816652)
			(xy 2.921 -234.687872) (xy 2.921436 -234.697936) (xy 2.929169 -234.716522) (xy 2.935986 -234.72394)
			(xy 2.9718 -234.759754) (xy 2.999052 -234.76024) (xy 3.053002 -234.767996) (xy 3.105299 -234.783351)
			(xy 3.154879 -234.805991) (xy 3.200732 -234.835457) (xy 3.241925 -234.871148) (xy 3.27762 -234.912338)
			(xy 3.30709 -234.958188) (xy 3.329736 -235.007765) (xy 3.345096 -235.060061) (xy 3.352858 -235.11401)
			(xy 3.353308 -235.141262) (xy 3.352773 -235.170178) (xy 3.344044 -235.227347) (xy 3.326788 -235.282545)
			(xy 3.301399 -235.334506) (xy 3.26846 -235.382041) (xy 3.228725 -235.42406) (xy 3.206242 -235.442252)
			(xy 3.197456 -235.449795) (xy 3.187277 -235.470565) (xy 3.186684 -235.48213) (xy 3.186684 -235.562394)
			(xy 3.187291 -235.573955) (xy 3.197462 -235.594728) (xy 3.206242 -235.602272) (xy 3.228728 -235.620461)
			(xy 3.268471 -235.662476) (xy 3.301414 -235.71001) (xy 3.326804 -235.761973) (xy 3.330318 -235.773214)
			(xy 7.397242 -235.773214) (xy 7.397826 -235.726818) (xy 7.40747 -235.63453) (xy 7.426665 -235.543746)
			(xy 7.455204 -235.455453) (xy 7.473442 -235.412788) (xy 7.477253 -235.402845) (xy 7.477258 -235.38158)
			(xy 7.473442 -235.37164) (xy 7.455205 -235.328975) (xy 7.426658 -235.240684) (xy 7.407463 -235.149899)
			(xy 7.397828 -235.05761) (xy 7.397242 -235.011214) (xy 7.39779 -234.967554) (xy 7.406336 -234.880653)
			(xy 7.423357 -234.795007) (xy 7.448689 -234.711442) (xy 7.482088 -234.630762) (xy 7.523233 -234.553743)
			(xy 7.571727 -234.481127) (xy 7.627105 -234.413613) (xy 7.688832 -234.35185) (xy 7.756314 -234.296434)
			(xy 7.828902 -234.247897) (xy 7.905897 -234.206708) (xy 7.986558 -234.173262) (xy 8.028178 -234.16006)
			(xy 8.043926 -234.155234) (xy 8.063738 -234.129326) (xy 8.06704 -234.00004) (xy 8.048752 -233.973116)
			(xy 8.033258 -233.967528) (xy 7.994142 -233.952769) (xy 7.918612 -233.916911) (xy 7.846779 -233.874125)
			(xy 7.779278 -233.824789) (xy 7.716702 -233.769337) (xy 7.659605 -233.708259) (xy 7.60849 -233.642094)
			(xy 7.563808 -233.571425) (xy 7.525953 -233.496876) (xy 7.49526 -233.419104) (xy 7.471998 -233.338796)
			(xy 7.456373 -233.256659) (xy 7.448523 -233.173419) (xy 7.448042 -233.131614) (xy 7.448626 -233.085218)
			(xy 7.45827 -232.99293) (xy 7.477465 -232.902146) (xy 7.506004 -232.813853) (xy 7.524242 -232.771188)
			(xy 7.528053 -232.761245) (xy 7.528058 -232.73998) (xy 7.524242 -232.73004) (xy 7.506005 -232.687375)
			(xy 7.477458 -232.599084) (xy 7.458263 -232.508299) (xy 7.448628 -232.41601) (xy 7.448042 -232.369614)
			(xy 7.448546 -232.327266) (xy 7.456597 -232.242952) (xy 7.472626 -232.159786) (xy 7.496487 -232.078519)
			(xy 7.527966 -231.999889) (xy 7.566777 -231.924608) (xy 7.612567 -231.853356) (xy 7.664923 -231.78678)
			(xy 7.723371 -231.725482) (xy 7.787381 -231.670017) (xy 7.856373 -231.620888) (xy 7.929723 -231.578539)
			(xy 8.006766 -231.543355) (xy 8.086805 -231.515653) (xy 8.169114 -231.495685) (xy 8.252949 -231.483632)
			(xy 8.33755 -231.479602) (xy 8.422151 -231.483632) (xy 8.505986 -231.495685) (xy 8.588295 -231.515653)
			(xy 8.668334 -231.543355) (xy 8.745377 -231.578539) (xy 8.818727 -231.620888) (xy 8.887719 -231.670017)
			(xy 8.951729 -231.725482) (xy 9.010177 -231.78678) (xy 9.062533 -231.853356) (xy 9.108323 -231.924608)
			(xy 9.147134 -231.999889) (xy 9.178613 -232.078519) (xy 9.202474 -232.159786) (xy 9.218503 -232.242952)
			(xy 9.226554 -232.327266) (xy 9.227058 -232.369614) (xy 9.226484 -232.41601) (xy 9.216837 -232.508299)
			(xy 9.197639 -232.599082) (xy 9.169097 -232.687376) (xy 9.150858 -232.73004) (xy 9.147031 -232.739977)
			(xy 9.147036 -232.761248) (xy 9.150858 -232.771188) (xy 9.169104 -232.81385) (xy 9.197649 -232.902142)
			(xy 9.216841 -232.992927) (xy 9.226474 -233.085218) (xy 9.227058 -233.131614) (xy 9.226535 -233.175275)
			(xy 9.217987 -233.262177) (xy 9.200963 -233.347823) (xy 9.175629 -233.431388) (xy 9.142227 -233.512069)
			(xy 9.10108 -233.589088) (xy 9.052583 -233.661704) (xy 8.997204 -233.729218) (xy 8.935475 -233.79098)
			(xy 8.867991 -233.846396) (xy 8.795401 -233.894932) (xy 8.718405 -233.936121) (xy 8.637742 -233.969566)
			(xy 8.596122 -233.982768) (xy 8.580374 -233.987594) (xy 8.560562 -234.013502) (xy 8.55726 -234.142788)
			(xy 8.575548 -234.169712) (xy 8.591042 -234.1753) (xy 8.630161 -234.190052) (xy 8.705691 -234.22591)
			(xy 8.777524 -234.268697) (xy 8.845026 -234.318034) (xy 8.907601 -234.373486) (xy 8.964698 -234.434564)
			(xy 9.015813 -234.50073) (xy 9.060495 -234.5714) (xy 9.098349 -234.64595) (xy 9.129042 -234.723722)
			(xy 9.152304 -234.804031) (xy 9.167928 -234.886168) (xy 9.175778 -234.969409) (xy 9.176258 -235.011214)
			(xy 9.175684 -235.05761) (xy 9.166037 -235.149899) (xy 9.146839 -235.240682) (xy 9.118297 -235.328976)
			(xy 9.100058 -235.37164) (xy 9.096231 -235.381577) (xy 9.096236 -235.402848) (xy 9.100058 -235.412788)
			(xy 9.118304 -235.45545) (xy 9.146849 -235.543742) (xy 9.166041 -235.634527) (xy 9.175674 -235.726818)
			(xy 9.176258 -235.773214) (xy 9.175754 -235.815562) (xy 9.167703 -235.899876) (xy 9.151674 -235.983042)
			(xy 9.127813 -236.064309) (xy 9.096334 -236.142939) (xy 9.057523 -236.21822) (xy 9.011733 -236.289472)
			(xy 8.959377 -236.356048) (xy 8.900929 -236.417346) (xy 8.836919 -236.472811) (xy 8.767927 -236.52194)
			(xy 8.694577 -236.564289) (xy 8.617534 -236.599473) (xy 8.537495 -236.627175) (xy 8.455186 -236.647143)
			(xy 8.371351 -236.659196) (xy 8.28675 -236.663227) (xy 8.202149 -236.659196) (xy 8.118314 -236.647143)
			(xy 8.036005 -236.627175) (xy 7.955966 -236.599473) (xy 7.878923 -236.564289) (xy 7.805573 -236.52194)
			(xy 7.736581 -236.472811) (xy 7.672571 -236.417346) (xy 7.614123 -236.356048) (xy 7.561767 -236.289472)
			(xy 7.515977 -236.21822) (xy 7.477166 -236.142939) (xy 7.445687 -236.064309) (xy 7.421826 -235.983042)
			(xy 7.405797 -235.899876) (xy 7.397746 -235.815562) (xy 7.397242 -235.773214) (xy 3.330318 -235.773214)
			(xy 3.344058 -235.817173) (xy 3.35278 -235.874345) (xy 3.353308 -235.903262) (xy 3.352822 -235.930513)
			(xy 3.345065 -235.984461) (xy 3.32971 -236.036755) (xy 3.307069 -236.086332) (xy 3.277602 -236.132182)
			(xy 3.241911 -236.173372) (xy 3.200721 -236.209064) (xy 3.15487 -236.23853) (xy 3.105293 -236.261171)
			(xy 3.052999 -236.276526) (xy 2.999051 -236.284282) (xy 2.9718 -236.28477) (xy 2.935986 -236.320584)
			(xy 2.929143 -236.327983) (xy 2.921426 -236.346582) (xy 2.921 -236.356652) (xy 2.921 -236.822488)
			(xy 2.921525 -236.833) (xy 2.92992 -236.852278) (xy 2.937256 -236.859826) (xy 3.000248 -236.917738)
			(xy 3.02006 -236.924596) (xy 3.030728 -236.923834) (xy 3.061462 -236.922564) (xy 3.088713 -236.92305)
			(xy 3.142661 -236.930807) (xy 3.194955 -236.946162) (xy 3.244532 -236.968803) (xy 3.290382 -236.99827)
			(xy 3.331572 -237.033961) (xy 3.367263 -237.075151) (xy 3.396729 -237.121002) (xy 3.419369 -237.170579)
			(xy 3.434724 -237.222873) (xy 3.44248 -237.276821) (xy 3.44297 -237.304072) (xy 3.442435 -237.332988)
			(xy 3.433706 -237.390157) (xy 3.41645 -237.445355) (xy 3.391061 -237.497316) (xy 3.358122 -237.544851)
			(xy 3.318387 -237.586871) (xy 3.295904 -237.605062) (xy 3.287111 -237.6126) (xy 3.276923 -237.633373)
			(xy 3.276346 -237.64494) (xy 3.276346 -237.725204) (xy 3.276957 -237.736762) (xy 3.287139 -237.757523)
			(xy 3.295904 -237.765082) (xy 3.318387 -237.783273) (xy 3.358122 -237.825291) (xy 3.391059 -237.872826)
			(xy 3.416443 -237.924788) (xy 3.433692 -237.979987) (xy 3.442412 -238.037156) (xy 3.44297 -238.066072)
			(xy 3.442484 -238.093323) (xy 3.434727 -238.147271) (xy 3.419372 -238.199565) (xy 3.416885 -238.20501)
			(xy 6.11759 -238.20501) (xy 6.118177 -238.158615) (xy 6.127821 -238.066326) (xy 6.147015 -237.975542)
			(xy 6.175553 -237.887249) (xy 6.19379 -237.844584) (xy 6.197689 -237.83466) (xy 6.197693 -237.813358)
			(xy 6.19379 -237.803436) (xy 6.175548 -237.760773) (xy 6.147004 -237.672481) (xy 6.12781 -237.581696)
			(xy 6.118175 -237.489406) (xy 6.11759 -237.44301) (xy 6.118094 -237.400662) (xy 6.126145 -237.316348)
			(xy 6.142174 -237.233182) (xy 6.166035 -237.151915) (xy 6.197514 -237.073285) (xy 6.236325 -236.998004)
			(xy 6.282115 -236.926752) (xy 6.334471 -236.860176) (xy 6.392919 -236.798878) (xy 6.456929 -236.743413)
			(xy 6.525921 -236.694284) (xy 6.599271 -236.651935) (xy 6.676314 -236.616751) (xy 6.756353 -236.589049)
			(xy 6.838662 -236.569081) (xy 6.922497 -236.557028) (xy 7.007098 -236.552998) (xy 7.091699 -236.557028)
			(xy 7.175534 -236.569081) (xy 7.257843 -236.589049) (xy 7.337882 -236.616751) (xy 7.414925 -236.651935)
			(xy 7.488275 -236.694284) (xy 7.557267 -236.743413) (xy 7.621277 -236.798878) (xy 7.679725 -236.860176)
			(xy 7.732081 -236.926752) (xy 7.777871 -236.998004) (xy 7.816682 -237.073285) (xy 7.848161 -237.151915)
			(xy 7.872022 -237.233182) (xy 7.888051 -237.316348) (xy 7.896102 -237.400662) (xy 7.896606 -237.44301)
			(xy 7.896027 -237.489406) (xy 7.886381 -237.581694) (xy 7.867184 -237.672478) (xy 7.838644 -237.760771)
			(xy 7.820406 -237.803436) (xy 7.816495 -237.813356) (xy 7.816499 -237.834662) (xy 7.820406 -237.844584)
			(xy 7.838654 -237.887245) (xy 7.867197 -237.975538) (xy 7.886389 -238.066323) (xy 7.896022 -238.158614)
			(xy 7.896606 -238.20501) (xy 7.896102 -238.247358) (xy 7.888051 -238.331672) (xy 7.872022 -238.414838)
			(xy 7.848161 -238.496105) (xy 7.816682 -238.574735) (xy 7.777871 -238.650016) (xy 7.732081 -238.721268)
			(xy 7.679725 -238.787844) (xy 7.621277 -238.849142) (xy 7.557267 -238.904607) (xy 7.488275 -238.953736)
			(xy 7.414925 -238.996085) (xy 7.337882 -239.031269) (xy 7.257843 -239.058971) (xy 7.175534 -239.078939)
			(xy 7.091699 -239.090992) (xy 7.007098 -239.095023) (xy 6.922497 -239.090992) (xy 6.838662 -239.078939)
			(xy 6.756353 -239.058971) (xy 6.676314 -239.031269) (xy 6.599271 -238.996085) (xy 6.525921 -238.953736)
			(xy 6.456929 -238.904607) (xy 6.392919 -238.849142) (xy 6.334471 -238.787844) (xy 6.282115 -238.721268)
			(xy 6.236325 -238.650016) (xy 6.197514 -238.574735) (xy 6.166035 -238.496105) (xy 6.142174 -238.414838)
			(xy 6.126145 -238.331672) (xy 6.118094 -238.247358) (xy 6.11759 -238.20501) (xy 3.416885 -238.20501)
			(xy 3.396731 -238.249143) (xy 3.367265 -238.294993) (xy 3.331573 -238.336183) (xy 3.290383 -238.371875)
			(xy 3.244533 -238.401341) (xy 3.194955 -238.423982) (xy 3.142661 -238.439337) (xy 3.088713 -238.447094)
			(xy 3.061462 -238.44758) (xy 3.030728 -238.44631) (xy 3.02006 -238.445548) (xy 3.000248 -238.452406)
			(xy 2.937256 -238.510318) (xy 2.92989 -238.517844) (xy 2.921504 -238.537136) (xy 2.921 -238.547656)
			(xy 2.921 -240.647982) (xy 2.920562 -240.658046) (xy 2.912826 -240.676628) (xy 2.906014 -240.68405)
			(xy 2.83464 -240.755424) (xy 2.827897 -240.762794) (xy 2.820307 -240.781256) (xy 2.819908 -240.791238)
			(xy 2.819908 -242.272312) (xy 2.820438 -242.282842) (xy 2.82891 -242.302122) (xy 2.84442 -242.316368)
			(xy 2.854198 -242.320318) (xy 2.960624 -242.35664) (xy 2.991612 -242.347496) (xy 3.001772 -242.334288)
			(xy 3.026963 -242.302488) (xy 3.08227 -242.243128) (xy 3.142752 -242.189051) (xy 3.207908 -242.140707)
			(xy 3.277196 -242.098497) (xy 3.35004 -242.062772) (xy 3.425834 -242.03383) (xy 3.50395 -242.01191)
			(xy 3.583736 -241.997195) (xy 3.664532 -241.989807) (xy 3.705098 -241.989356) (xy 3.744029 -241.989797)
			(xy 3.82159 -241.996649) (xy 3.898256 -242.010247) (xy 3.973442 -242.030489) (xy 4.010152 -242.043458)
			(xy 4.018701 -242.046222) (xy 4.036655 -242.046222) (xy 4.045204 -242.043458) (xy 4.08191 -242.030476)
			(xy 4.157095 -242.010228) (xy 4.233763 -241.996636) (xy 4.311326 -241.989802) (xy 4.350258 -241.989356)
			(xy 4.389189 -241.989796) (xy 4.466751 -241.996644) (xy 4.543419 -242.010239) (xy 4.618606 -242.030477)
			(xy 4.655312 -242.043458) (xy 4.663861 -242.046222) (xy 4.681815 -242.046222) (xy 4.690364 -242.043458)
			(xy 4.72707 -242.030474) (xy 4.802254 -242.010223) (xy 4.878922 -241.996627) (xy 4.956486 -241.98979)
			(xy 4.995418 -241.989356) (xy 5.036521 -241.989831) (xy 5.118375 -241.997418) (xy 5.19918 -242.012524)
			(xy 5.278247 -242.035021) (xy 5.354901 -242.064718) (xy 5.428488 -242.10136) (xy 5.49838 -242.144635)
			(xy 5.563981 -242.194174) (xy 5.624732 -242.249555) (xy 5.680114 -242.310305) (xy 5.729655 -242.375905)
			(xy 5.772932 -242.445797) (xy 5.809575 -242.519383) (xy 5.839273 -242.596036) (xy 5.861772 -242.675102)
			(xy 5.87688 -242.755907) (xy 5.884468 -242.837761) (xy 5.884926 -242.878864) (xy 5.884517 -242.917154)
			(xy 5.877911 -242.993448) (xy 5.864763 -243.06889) (xy 5.845169 -243.142921) (xy 5.832602 -243.179092)
			(xy 5.829954 -243.18753) (xy 5.829942 -243.205203) (xy 5.832602 -243.213636) (xy 5.839714 -243.233702)
			(xy 5.84454 -243.24818) (xy 5.868162 -243.266976) (xy 5.991098 -243.278152) (xy 6.017768 -243.263928)
			(xy 6.025134 -243.25072) (xy 6.046382 -243.213075) (xy 6.095132 -243.141684) (xy 6.150579 -243.075359)
			(xy 6.212199 -243.014726) (xy 6.27941 -242.960357) (xy 6.351579 -242.912765) (xy 6.428024 -242.872399)
			(xy 6.508026 -242.83964) (xy 6.590827 -242.814796) (xy 6.675649 -242.798103) (xy 6.76169 -242.789718)
			(xy 6.804914 -242.789202) (xy 6.843845 -242.789644) (xy 6.921405 -242.796497) (xy 6.998071 -242.810098)
			(xy 7.073256 -242.830341) (xy 7.109968 -242.843304) (xy 7.118517 -242.846068) (xy 7.136471 -242.846068)
			(xy 7.14502 -242.843304) (xy 7.181725 -242.830318) (xy 7.256909 -242.810062) (xy 7.333578 -242.796461)
			(xy 7.411142 -242.789621) (xy 7.450074 -242.789202) (xy 7.489005 -242.789642) (xy 7.566567 -242.796492)
			(xy 7.643233 -242.810089) (xy 7.718419 -242.83033) (xy 7.755128 -242.843304) (xy 7.763677 -242.846068)
			(xy 7.781631 -242.846068) (xy 7.79018 -242.843304) (xy 7.826886 -242.83032) (xy 7.90207 -242.810069)
			(xy 7.978738 -242.796474) (xy 8.056302 -242.789638) (xy 8.095234 -242.789202) (xy 8.136015 -242.789659)
			(xy 8.217235 -242.797122) (xy 8.29743 -242.81199) (xy 8.375926 -242.834139) (xy 8.452065 -242.863384)
			(xy 8.525206 -242.899477) (xy 8.594735 -242.942116) (xy 8.660067 -242.990943) (xy 8.720653 -243.045547)
			(xy 8.775985 -243.10547) (xy 8.825597 -243.170207) (xy 8.869073 -243.239215) (xy 8.887968 -243.275358)
			(xy 8.895588 -243.29009) (xy 8.923782 -243.304822) (xy 9.05129 -243.288058) (xy 9.074658 -243.266214)
			(xy 9.07796 -243.250212) (xy 9.087395 -243.207933) (xy 9.113408 -243.125298) (xy 9.147332 -243.045584)
			(xy 9.188846 -242.969546) (xy 9.237556 -242.897905) (xy 9.293 -242.831339) (xy 9.354654 -242.770479)
			(xy 9.421934 -242.715902) (xy 9.494201 -242.668125) (xy 9.57077 -242.6276) (xy 9.650917 -242.594712)
			(xy 9.733882 -242.569773) (xy 9.818879 -242.553018) (xy 9.905102 -242.544606) (xy 9.948418 -242.544092)
			(xy 9.994814 -242.544678) (xy 10.087104 -242.554313) (xy 10.177888 -242.573508) (xy 10.266179 -242.602053)
			(xy 10.308844 -242.620292) (xy 10.318784 -242.624112) (xy 10.340052 -242.624112) (xy 10.349992 -242.620292)
			(xy 10.392657 -242.602055) (xy 10.480951 -242.573519) (xy 10.571734 -242.554324) (xy 10.664023 -242.544681)
			(xy 10.710418 -242.544092) (xy 10.751232 -242.544554) (xy 10.832517 -242.552038) (xy 10.912773 -242.566939)
			(xy 10.991326 -242.589134) (xy 11.067514 -242.618435) (xy 11.140696 -242.654595) (xy 11.210256 -242.697311)
			(xy 11.275608 -242.746222) (xy 11.336202 -242.800917) (xy 11.364214 -242.830604) (xy 11.373612 -242.84051)
			(xy 11.398758 -242.848638) (xy 11.511026 -242.824762) (xy 11.530838 -242.807236) (xy 11.535156 -242.794282)
			(xy 11.549291 -242.754121) (xy 11.584197 -242.676461) (xy 11.626365 -242.602491) (xy 11.675409 -242.53289)
			(xy 11.730881 -242.468295) (xy 11.792272 -242.409297) (xy 11.859021 -242.356436) (xy 11.930515 -242.310196)
			(xy 12.006102 -242.271) (xy 12.085089 -242.239207) (xy 12.166752 -242.215109) (xy 12.250345 -242.198926)
			(xy 12.335101 -242.190805) (xy 12.377674 -242.19027) (xy 12.418778 -242.190729) (xy 12.500636 -242.198312)
			(xy 12.581446 -242.213415) (xy 12.660517 -242.235911) (xy 12.737175 -242.265606) (xy 12.810766 -242.302247)
			(xy 12.880662 -242.345522) (xy 12.946267 -242.395062) (xy 13.007022 -242.450444) (xy 13.062407 -242.511196)
			(xy 13.111951 -242.576798) (xy 13.15523 -242.646692) (xy 13.191875 -242.720281) (xy 13.221574 -242.796938)
			(xy 13.244074 -242.876008) (xy 13.259182 -242.956816) (xy 13.266769 -243.038674) (xy 13.267182 -243.079778)
			(xy 13.266772 -243.118068) (xy 13.260165 -243.194361) (xy 13.247015 -243.269803) (xy 13.22742 -243.343833)
			(xy 13.214858 -243.380006) (xy 13.212214 -243.388444) (xy 13.212207 -243.406115) (xy 13.214858 -243.41455)
			(xy 13.227402 -243.450728) (xy 13.246977 -243.52476) (xy 13.260124 -243.6002) (xy 13.266744 -243.67649)
			(xy 13.267182 -243.714778) (xy 13.266634 -243.758994) (xy 13.257862 -243.846991) (xy 13.240411 -243.933685)
			(xy 13.214453 -244.018222) (xy 13.19784 -244.059202) (xy 13.194659 -244.067764) (xy 13.193993 -244.086001)
			(xy 13.19657 -244.094762) (xy 13.210947 -244.140096) (xy 13.231078 -244.233051) (xy 13.241186 -244.327623)
			(xy 13.241782 -244.375178) (xy 13.241372 -244.413468) (xy 13.234765 -244.489761) (xy 13.221615 -244.565203)
			(xy 13.20202 -244.639233) (xy 13.189458 -244.675406) (xy 13.186814 -244.683844) (xy 13.186807 -244.701515)
			(xy 13.189458 -244.70995) (xy 13.202002 -244.746128) (xy 13.221577 -244.82016) (xy 13.234724 -244.8956)
			(xy 13.241344 -244.97189) (xy 13.241782 -245.010178) (xy 13.241332 -245.050087) (xy 13.23418 -245.129584)
			(xy 13.21994 -245.208122) (xy 13.198726 -245.28507) (xy 13.18514 -245.322598) (xy 13.182295 -245.331265)
			(xy 13.182287 -245.349494) (xy 13.18514 -245.358158) (xy 13.198755 -245.395677) (xy 13.219985 -245.472624)
			(xy 13.234229 -245.551165) (xy 13.241372 -245.630667) (xy 13.241782 -245.670578) (xy 13.241372 -245.708868)
			(xy 13.234765 -245.785161) (xy 13.221615 -245.860603) (xy 13.20202 -245.934633) (xy 13.189458 -245.970806)
			(xy 13.186814 -245.979244) (xy 13.186807 -245.996915) (xy 13.189458 -246.00535) (xy 13.202002 -246.041528)
			(xy 13.221577 -246.11556) (xy 13.234724 -246.191) (xy 13.241344 -246.26729) (xy 13.241782 -246.305578)
			(xy 13.241195 -246.353135) (xy 13.231104 -246.44771) (xy 13.21097 -246.540667) (xy 13.19657 -246.585994)
			(xy 13.194048 -246.594765) (xy 13.194687 -246.612991) (xy 13.19784 -246.621554) (xy 13.214463 -246.662532)
			(xy 13.240447 -246.747064) (xy 13.257905 -246.833759) (xy 13.266663 -246.92176) (xy 13.267182 -246.965978)
			(xy 13.266772 -247.004268) (xy 13.260165 -247.080561) (xy 13.247015 -247.156003) (xy 13.22742 -247.230033)
			(xy 13.214858 -247.266206) (xy 13.212214 -247.274644) (xy 13.212207 -247.292315) (xy 13.214858 -247.30075)
			(xy 13.227402 -247.336928) (xy 13.246977 -247.41096) (xy 13.260124 -247.4864) (xy 13.266744 -247.56269)
			(xy 13.267182 -247.600978) (xy 13.266678 -247.643326) (xy 13.258627 -247.72764) (xy 13.242598 -247.810806)
			(xy 13.218737 -247.892073) (xy 13.187258 -247.970703) (xy 13.148447 -248.045984) (xy 13.102657 -248.117236)
			(xy 13.050301 -248.183812) (xy 12.991853 -248.24511) (xy 12.927843 -248.300575) (xy 12.858851 -248.349704)
			(xy 12.785501 -248.392053) (xy 12.708458 -248.427237) (xy 12.628419 -248.454939) (xy 12.54611 -248.474907)
			(xy 12.462275 -248.48696) (xy 12.377674 -248.490991) (xy 12.293073 -248.48696) (xy 12.209238 -248.474907)
			(xy 12.126929 -248.454939) (xy 12.04689 -248.427237) (xy 11.969847 -248.392053) (xy 11.896497 -248.349704)
			(xy 11.827505 -248.300575) (xy 11.763495 -248.24511) (xy 11.705047 -248.183812) (xy 11.652691 -248.117236)
			(xy 11.606901 -248.045984) (xy 11.56809 -247.970703) (xy 11.536611 -247.892073) (xy 11.51275 -247.810806)
			(xy 11.496721 -247.72764) (xy 11.48867 -247.643326) (xy 11.488166 -247.600978) (xy 11.488573 -247.562688)
			(xy 11.495176 -247.486393) (xy 11.50832 -247.410949) (xy 11.52791 -247.336917) (xy 11.54049 -247.30075)
			(xy 11.543128 -247.292312) (xy 11.543121 -247.274647) (xy 11.54049 -247.266206) (xy 11.527945 -247.230029)
			(xy 11.508366 -247.155996) (xy 11.495215 -247.080557) (xy 11.488591 -247.004266) (xy 11.488166 -246.965978)
			(xy 11.488755 -246.918422) (xy 11.498851 -246.823848) (xy 11.51899 -246.730893) (xy 11.533378 -246.685562)
			(xy 11.535893 -246.676792) (xy 11.53524 -246.658572) (xy 11.532108 -246.650002) (xy 11.515487 -246.609024)
			(xy 11.489505 -246.524492) (xy 11.47205 -246.437796) (xy 11.463296 -246.349796) (xy 11.462766 -246.305578)
			(xy 11.463173 -246.267288) (xy 11.469776 -246.190993) (xy 11.48292 -246.115549) (xy 11.50251 -246.041517)
			(xy 11.51509 -246.00535) (xy 11.517728 -245.996912) (xy 11.517721 -245.979247) (xy 11.51509 -245.970806)
			(xy 11.502545 -245.934629) (xy 11.482966 -245.860596) (xy 11.469815 -245.785157) (xy 11.463191 -245.708866)
			(xy 11.462766 -245.670578) (xy 11.463213 -245.630668) (xy 11.47036 -245.55117) (xy 11.484595 -245.47263)
			(xy 11.505803 -245.39568) (xy 11.519408 -245.358158) (xy 11.522244 -245.349491) (xy 11.522236 -245.331268)
			(xy 11.519408 -245.322598) (xy 11.505795 -245.285078) (xy 11.48457 -245.208131) (xy 11.470331 -245.12959)
			(xy 11.463193 -245.050089) (xy 11.462766 -245.010178) (xy 11.463173 -244.971888) (xy 11.469776 -244.895593)
			(xy 11.48292 -244.820149) (xy 11.50251 -244.746117) (xy 11.51509 -244.70995) (xy 11.517728 -244.701512)
			(xy 11.517721 -244.683847) (xy 11.51509 -244.675406) (xy 11.502545 -244.639229) (xy 11.482966 -244.565196)
			(xy 11.469815 -244.489757) (xy 11.463191 -244.413466) (xy 11.462766 -244.375178) (xy 11.463315 -244.330962)
			(xy 11.472091 -244.242967) (xy 11.489545 -244.156274) (xy 11.515505 -244.071738) (xy 11.532108 -244.030754)
			(xy 11.535279 -244.022192) (xy 11.535929 -244.003961) (xy 11.533378 -243.995194) (xy 11.533378 -243.994686)
			(xy 11.53011 -243.986058) (xy 11.518488 -243.97175) (xy 11.502535 -243.962513) (xy 11.4935 -243.96065)
			(xy 11.465052 -243.955824) (xy 11.455919 -243.954642) (xy 11.437852 -243.958136) (xy 11.422203 -243.967818)
			(xy 11.416284 -243.974874) (xy 11.391108 -244.006951) (xy 11.33577 -244.066851) (xy 11.275182 -244.121435)
			(xy 11.209852 -244.170243) (xy 11.140328 -244.212867) (xy 11.067195 -244.248948) (xy 10.991067 -244.278183)
			(xy 10.912582 -244.300328) (xy 10.832399 -244.315196) (xy 10.751193 -244.322662) (xy 10.710418 -244.323108)
			(xy 10.664022 -244.322524) (xy 10.571731 -244.312893) (xy 10.480945 -244.293701) (xy 10.392652 -244.265159)
			(xy 10.349992 -244.246908) (xy 10.340052 -244.243088) (xy 10.318784 -244.243088) (xy 10.308844 -244.246908)
			(xy 10.266179 -244.265147) (xy 10.177886 -244.293687) (xy 10.087102 -244.312885) (xy 9.994814 -244.322531)
			(xy 9.948418 -244.323108) (xy 9.907638 -244.322649) (xy 9.826421 -244.315182) (xy 9.746228 -244.30031)
			(xy 9.667735 -244.278158) (xy 9.591599 -244.248912) (xy 9.518461 -244.212816) (xy 9.448936 -244.170176)
			(xy 9.383607 -244.121348) (xy 9.323023 -244.066744) (xy 9.267694 -244.006821) (xy 9.218085 -243.942085)
			(xy 9.174611 -243.873077) (xy 9.155684 -243.836952) (xy 9.148064 -243.82222) (xy 9.11987 -243.807488)
			(xy 8.992362 -243.824252) (xy 8.968994 -243.846096) (xy 8.965692 -243.862098) (xy 8.959134 -243.891782)
			(xy 8.942484 -243.950254) (xy 8.932418 -243.978938) (xy 8.929777 -243.987376) (xy 8.92978 -244.005043)
			(xy 8.932418 -244.013482) (xy 8.944964 -244.049659) (xy 8.964543 -244.123691) (xy 8.977695 -244.199131)
			(xy 8.98432 -244.275422) (xy 8.984742 -244.31371) (xy 8.984267 -244.354813) (xy 8.976682 -244.436667)
			(xy 8.961577 -244.517472) (xy 8.939081 -244.596539) (xy 8.909385 -244.673193) (xy 8.872743 -244.746781)
			(xy 8.829468 -244.816673) (xy 8.779928 -244.882274) (xy 8.724547 -244.943024) (xy 8.663797 -244.998406)
			(xy 8.598196 -245.047946) (xy 8.528304 -245.091221) (xy 8.454717 -245.127863) (xy 8.378063 -245.15756)
			(xy 8.298996 -245.180056) (xy 8.218191 -245.195162) (xy 8.136337 -245.202747) (xy 8.095234 -245.203218)
			(xy 8.055665 -245.202797) (xy 7.976837 -245.195788) (xy 7.898943 -245.181805) (xy 7.8226 -245.160959)
			(xy 7.785354 -245.147592) (xy 7.776687 -245.144752) (xy 7.758461 -245.144752) (xy 7.749794 -245.147592)
			(xy 7.712549 -245.16096) (xy 7.636205 -245.181807) (xy 7.558311 -245.195789) (xy 7.479483 -245.202795)
			(xy 7.439914 -245.203218) (xy 7.401624 -245.202808) (xy 7.325331 -245.1962) (xy 7.249889 -245.18305)
			(xy 7.175859 -245.163455) (xy 7.139686 -245.150894) (xy 7.131248 -245.148252) (xy 7.11358 -245.148252)
			(xy 7.105142 -245.150894) (xy 7.068964 -245.163437) (xy 6.994932 -245.183011) (xy 6.919492 -245.196156)
			(xy 6.843202 -245.202775) (xy 6.804914 -245.203218) (xy 6.76381 -245.202758) (xy 6.681953 -245.195175)
			(xy 6.601145 -245.18007) (xy 6.522076 -245.157574) (xy 6.445419 -245.127879) (xy 6.371829 -245.091237)
			(xy 6.301935 -245.047961) (xy 6.236331 -244.998421) (xy 6.175578 -244.943039) (xy 6.120195 -244.882288)
			(xy 6.070653 -244.816685) (xy 6.027375 -244.746792) (xy 5.990731 -244.673203) (xy 5.961033 -244.596547)
			(xy 5.938535 -244.517478) (xy 5.923429 -244.43667) (xy 5.915843 -244.354814) (xy 5.915406 -244.31371)
			(xy 5.915816 -244.27542) (xy 5.922424 -244.199127) (xy 5.935575 -244.123685) (xy 5.955171 -244.049656)
			(xy 5.96773 -244.013482) (xy 5.970372 -244.005044) (xy 5.970375 -243.987375) (xy 5.96773 -243.978938)
			(xy 5.960618 -243.958872) (xy 5.955792 -243.944394) (xy 5.93217 -243.925598) (xy 5.809234 -243.914422)
			(xy 5.782564 -243.928646) (xy 5.775198 -243.941854) (xy 5.753951 -243.979499) (xy 5.7052 -244.050891)
			(xy 5.649754 -244.117217) (xy 5.588134 -244.17785) (xy 5.520923 -244.23222) (xy 5.448754 -244.279812)
			(xy 5.372308 -244.320178) (xy 5.292307 -244.352938) (xy 5.209505 -244.377782) (xy 5.124683 -244.394475)
			(xy 5.038642 -244.402861) (xy 4.995418 -244.403372) (xy 4.955849 -244.40295) (xy 4.877022 -244.39594)
			(xy 4.799129 -244.381955) (xy 4.722786 -244.361106) (xy 4.685538 -244.347746) (xy 4.676871 -244.344906)
			(xy 4.658645 -244.344906) (xy 4.649978 -244.347746) (xy 4.612733 -244.361113) (xy 4.536389 -244.381958)
			(xy 4.458495 -244.395937) (xy 4.379667 -244.402941) (xy 4.340098 -244.403372) (xy 4.301809 -244.402961)
			(xy 4.225515 -244.396353) (xy 4.150073 -244.383202) (xy 4.076044 -244.363607) (xy 4.03987 -244.351048)
			(xy 4.031432 -244.348406) (xy 4.013764 -244.348406) (xy 4.005326 -244.351048) (xy 3.969148 -244.363591)
			(xy 3.895116 -244.383165) (xy 3.819676 -244.396309) (xy 3.743386 -244.402927) (xy 3.705098 -244.403372)
			(xy 3.664532 -244.402922) (xy 3.583736 -244.395534) (xy 3.503948 -244.380819) (xy 3.425832 -244.3589)
			(xy 3.350037 -244.329958) (xy 3.277192 -244.294235) (xy 3.207902 -244.252026) (xy 3.142744 -244.203684)
			(xy 3.082259 -244.149609) (xy 3.026949 -244.090251) (xy 3.001772 -244.05844) (xy 2.991612 -244.045232)
			(xy 2.960624 -244.036088) (xy 2.854198 -244.07241) (xy 2.844416 -244.076338) (xy 2.828932 -244.090609)
			(xy 2.820463 -244.109888) (xy 2.819908 -244.120416) (xy 2.819908 -246.074692) (xy 8.573768 -246.074692)
			(xy 8.577839 -246.01907) (xy 8.589965 -245.964633) (xy 8.609888 -245.912542) (xy 8.637184 -245.863907)
			(xy 8.67127 -245.819764) (xy 8.711419 -245.781055) (xy 8.756777 -245.748604) (xy 8.806377 -245.723103)
			(xy 8.859161 -245.705096) (xy 8.914004 -245.694966) (xy 8.969738 -245.692929) (xy 9.025175 -245.699029)
			(xy 9.079132 -245.713135) (xy 9.130461 -245.734947) (xy 9.178067 -245.764001) (xy 9.220935 -245.799676)
			(xy 9.258152 -245.841213) (xy 9.288925 -245.887726) (xy 9.312597 -245.938223) (xy 9.328665 -245.99163)
			(xy 9.336785 -246.046806) (xy 9.337294 -246.074692) (xy 9.336785 -246.102578) (xy 9.328665 -246.157754)
			(xy 9.312597 -246.211161) (xy 9.288925 -246.261658) (xy 9.258152 -246.308171) (xy 9.220935 -246.349708)
			(xy 9.178067 -246.385383) (xy 9.130461 -246.414437) (xy 9.079132 -246.436249) (xy 9.025175 -246.450355)
			(xy 8.969738 -246.456455) (xy 8.914004 -246.454418) (xy 8.859161 -246.444288) (xy 8.806377 -246.426281)
			(xy 8.756777 -246.40078) (xy 8.711419 -246.368329) (xy 8.67127 -246.32962) (xy 8.637184 -246.285477)
			(xy 8.609888 -246.236842) (xy 8.589965 -246.184751) (xy 8.577839 -246.130314) (xy 8.573768 -246.074692)
			(xy 2.819908 -246.074692) (xy 2.819908 -247.260364) (xy 2.820394 -247.270326) (xy 2.827982 -247.28875)
			(xy 2.83464 -247.296178) (xy 3.26898 -247.730518) (xy 3.277595 -247.738318) (xy 3.299554 -247.745851)
			(xy 3.311144 -247.744996) (xy 3.402838 -247.733312) (xy 3.422142 -247.720612) (xy 3.428238 -247.710198)
			(xy 3.443056 -247.686078) (xy 3.478696 -247.642099) (xy 3.520444 -247.603871) (xy 3.567384 -247.572233)
			(xy 3.618484 -247.54788) (xy 3.672623 -247.531347) (xy 3.72861 -247.522997) (xy 3.756914 -247.522492)
			(xy 3.785249 -247.523026) (xy 3.841292 -247.531443) (xy 3.895472 -247.548059) (xy 3.921252 -247.55983)
			(xy 3.932428 -247.565164) (xy 3.956812 -247.564402) (xy 4.051046 -247.512332) (xy 4.064508 -247.492012)
			(xy 4.066032 -247.479566) (xy 4.069699 -247.452009) (xy 4.083983 -247.398284) (xy 4.105912 -247.3472)
			(xy 4.135022 -247.29984) (xy 4.170697 -247.257205) (xy 4.21218 -247.220198) (xy 4.258595 -247.189603)
			(xy 4.308958 -247.166066) (xy 4.362204 -247.150088) (xy 4.417204 -247.142005) (xy 4.445 -247.141492)
			(xy 4.472251 -247.141978) (xy 4.526199 -247.149734) (xy 4.578494 -247.165089) (xy 4.628071 -247.187731)
			(xy 4.673921 -247.217197) (xy 4.715112 -247.252888) (xy 4.750803 -247.294079) (xy 4.780269 -247.339929)
			(xy 4.802911 -247.389506) (xy 4.818266 -247.441801) (xy 4.826022 -247.495749) (xy 4.826022 -247.550251)
			(xy 4.818266 -247.604199) (xy 4.802911 -247.656494) (xy 4.780269 -247.706071) (xy 4.750803 -247.751921)
			(xy 4.715112 -247.793112) (xy 4.673921 -247.828803) (xy 4.628071 -247.858269) (xy 4.578494 -247.880911)
			(xy 4.526199 -247.896266) (xy 4.472251 -247.904022) (xy 4.445 -247.904508) (xy 4.416665 -247.903975)
			(xy 4.360621 -247.89556) (xy 4.30644 -247.878945) (xy 4.280662 -247.86717) (xy 4.269486 -247.861836)
			(xy 4.245102 -247.862598) (xy 4.150868 -247.914668) (xy 4.137406 -247.934988) (xy 4.135882 -247.947434)
			(xy 4.131989 -247.976566) (xy 4.116411 -248.033237) (xy 4.092337 -248.086852) (xy 4.060335 -248.136148)
			(xy 4.02116 -248.17996) (xy 3.975736 -248.217254) (xy 3.950716 -248.232676) (xy 3.940302 -248.238772)
			(xy 3.927602 -248.258076) (xy 3.915918 -248.34977) (xy 3.915035 -248.361361) (xy 3.922591 -248.383317)
			(xy 3.930396 -248.391934) (xy 6.280912 -250.742704) (xy 6.301038 -250.763554) (xy 6.335141 -250.810404)
			(xy 6.361493 -250.862012) (xy 6.379447 -250.917108) (xy 6.388558 -250.974335) (xy 6.389116 -251.003308)
			(xy 6.389116 -251.935996) (xy 6.390386 -251.942092) (xy 6.395707 -251.964771) (xy 6.401434 -252.011002)
			(xy 6.401816 -252.034294) (xy 6.401359 -252.061092) (xy 6.393853 -252.114161) (xy 6.378996 -252.165658)
			(xy 6.357081 -252.21457) (xy 6.328538 -252.259935) (xy 6.293929 -252.30086) (xy 6.253935 -252.336541)
			(xy 6.209342 -252.366275) (xy 6.161028 -252.389479) (xy 6.135624 -252.398022) (xy 6.12267 -252.402086)
			(xy 6.104382 -252.422152) (xy 6.079998 -252.535436) (xy 6.08838 -252.561344) (xy 6.098794 -252.570488)
			(xy 6.118415 -252.588655) (xy 6.152887 -252.629533) (xy 6.181311 -252.674825) (xy 6.203132 -252.723642)
			(xy 6.21792 -252.775029) (xy 6.225386 -252.827978) (xy 6.225794 -252.854714) (xy 6.225334 -252.881579)
			(xy 6.217793 -252.934777) (xy 6.202863 -252.986391) (xy 6.180838 -253.035399) (xy 6.152154 -253.080831)
			(xy 6.117379 -253.12179) (xy 6.077202 -253.157464) (xy 6.032416 -253.187148) (xy 6.00837 -253.199138)
			(xy 5.99694 -253.204472) (xy 5.982208 -253.22403) (xy 5.965952 -253.318264) (xy 5.964642 -253.330393)
			(xy 5.972074 -253.353592) (xy 5.980176 -253.362714) (xy 5.982462 -253.365) (xy 6.348982 -253.365)
			(xy 6.353053 -253.309378) (xy 6.365179 -253.254941) (xy 6.385102 -253.20285) (xy 6.412398 -253.154215)
			(xy 6.446484 -253.110072) (xy 6.486633 -253.071363) (xy 6.531991 -253.038912) (xy 6.581591 -253.013411)
			(xy 6.634375 -252.995404) (xy 6.689218 -252.985274) (xy 6.744952 -252.983237) (xy 6.800389 -252.989337)
			(xy 6.854346 -253.003443) (xy 6.905675 -253.025255) (xy 6.953281 -253.054309) (xy 6.996149 -253.089984)
			(xy 7.033366 -253.131521) (xy 7.064139 -253.178034) (xy 7.087811 -253.228531) (xy 7.103879 -253.281938)
			(xy 7.111999 -253.337114) (xy 7.112508 -253.365) (xy 7.111999 -253.392886) (xy 7.103879 -253.448062)
			(xy 7.087811 -253.501469) (xy 7.064139 -253.551966) (xy 7.033366 -253.598479) (xy 6.996149 -253.640016)
			(xy 6.953281 -253.675691) (xy 6.905675 -253.704745) (xy 6.854346 -253.726557) (xy 6.800389 -253.740663)
			(xy 6.744952 -253.746763) (xy 6.689218 -253.744726) (xy 6.634375 -253.734596) (xy 6.581591 -253.716589)
			(xy 6.531991 -253.691088) (xy 6.486633 -253.658637) (xy 6.446484 -253.619928) (xy 6.412398 -253.575785)
			(xy 6.385102 -253.52715) (xy 6.365179 -253.475059) (xy 6.353053 -253.420622) (xy 6.348982 -253.365)
			(xy 5.982462 -253.365) (xy 7.032244 -254.414782) (xy 7.039591 -254.421588) (xy 7.058053 -254.429307)
			(xy 7.068058 -254.429768) (xy 7.342124 -254.429768) (xy 7.351169 -254.429401) (xy 7.368131 -254.423115)
			(xy 7.381858 -254.411333) (xy 7.386574 -254.403606) (xy 7.436612 -254.31369) (xy 7.43585 -254.286258)
			(xy 7.428484 -254.27432) (xy 7.41489 -254.251568) (xy 7.393432 -254.203106) (xy 7.378891 -254.15214)
			(xy 7.371546 -254.099652) (xy 7.37108 -254.073152) (xy 7.371461 -254.04986) (xy 7.377193 -254.00363)
			(xy 7.38251 -253.98095) (xy 7.38378 -253.974854) (xy 7.38378 -253.280926) (xy 7.384341 -253.251953)
			(xy 7.393452 -253.194728) (xy 7.411407 -253.139633) (xy 7.437763 -253.088028) (xy 7.47187 -253.041183)
			(xy 7.491984 -253.020322) (xy 7.842758 -252.669294) (xy 7.849985 -252.66139) (xy 7.857604 -252.641396)
			(xy 7.85749 -252.630686) (xy 7.853172 -252.544326) (xy 7.843266 -252.52553) (xy 7.834884 -252.518418)
			(xy 7.813195 -252.500213) (xy 7.774918 -252.458487) (xy 7.743234 -252.411558) (xy 7.718841 -252.360458)
			(xy 7.702274 -252.306312) (xy 7.693898 -252.250312) (xy 7.693406 -252.222) (xy 7.693869 -252.194748)
			(xy 7.701626 -252.140797) (xy 7.716983 -252.0885) (xy 7.739625 -252.038921) (xy 7.769093 -251.993069)
			(xy 7.804787 -251.951877) (xy 7.84598 -251.916185) (xy 7.891833 -251.886719) (xy 7.941413 -251.864078)
			(xy 7.993711 -251.848723) (xy 8.047661 -251.840968) (xy 8.074914 -251.840492) (xy 8.084902 -251.840544)
			(xy 8.104851 -251.84156) (xy 8.114792 -251.842524) (xy 8.125714 -251.843794) (xy 8.146034 -251.83719)
			(xy 8.210042 -251.779278) (xy 8.217656 -251.77171) (xy 8.226442 -251.75215) (xy 8.22706 -251.741432)
			(xy 8.22706 -248.623836) (xy 8.226528 -248.613846) (xy 8.218819 -248.595409) (xy 8.212074 -248.588022)
			(xy 7.843012 -248.218706) (xy 7.836619 -248.212866) (xy 7.820978 -248.205461) (xy 7.80377 -248.203635)
			(xy 7.79526 -248.205244) (xy 7.698232 -248.228104) (xy 7.678928 -248.245884) (xy 7.67461 -248.25833)
			(xy 7.665806 -248.28329) (xy 7.642274 -248.330696) (xy 7.612409 -248.374391) (xy 7.576787 -248.413535)
			(xy 7.536093 -248.447374) (xy 7.491108 -248.475259) (xy 7.442699 -248.496652) (xy 7.391796 -248.511143)
			(xy 7.339377 -248.518453) (xy 7.312914 -248.518934) (xy 7.284343 -248.518427) (xy 7.22784 -248.50991)
			(xy 7.173238 -248.493064) (xy 7.121758 -248.468265) (xy 7.07455 -248.436069) (xy 7.032671 -248.397194)
			(xy 7.014464 -248.37517) (xy 7.005574 -248.363994) (xy 6.97992 -248.354342) (xy 6.864096 -248.374662)
			(xy 6.843268 -248.392696) (xy 6.838696 -248.406158) (xy 6.829864 -248.431093) (xy 6.806287 -248.478446)
			(xy 6.776395 -248.522088) (xy 6.740762 -248.561183) (xy 6.70007 -248.594982) (xy 6.6551 -248.622836)
			(xy 6.606713 -248.644211) (xy 6.555838 -248.658697) (xy 6.503449 -248.666018) (xy 6.477 -248.666508)
			(xy 6.449749 -248.666022) (xy 6.395801 -248.658266) (xy 6.343506 -248.642911) (xy 6.293929 -248.620269)
			(xy 6.248079 -248.590803) (xy 6.206888 -248.555112) (xy 6.171197 -248.513921) (xy 6.141731 -248.468071)
			(xy 6.119089 -248.418494) (xy 6.103734 -248.366199) (xy 6.095978 -248.312251) (xy 6.095492 -248.285)
			(xy 6.095944 -248.258225) (xy 6.103431 -248.2052) (xy 6.118257 -248.153742) (xy 6.140132 -248.104863)
			(xy 6.168625 -248.059522) (xy 6.203178 -248.01861) (xy 6.243111 -247.98293) (xy 6.28764 -247.953184)
			(xy 6.335891 -247.929955) (xy 6.386915 -247.9137) (xy 6.413246 -247.908826) (xy 6.424168 -247.907048)
			(xy 6.442456 -247.894602) (xy 6.493764 -247.809766) (xy 6.496304 -247.787668) (xy 6.492748 -247.777254)
			(xy 6.483934 -247.748397) (xy 6.474496 -247.688804) (xy 6.473952 -247.658636) (xy 6.474452 -247.630506)
			(xy 6.48271 -247.574855) (xy 6.499053 -247.521021) (xy 6.523127 -247.470171) (xy 6.554408 -247.423409)
			(xy 6.592219 -247.381749) (xy 6.635739 -247.346094) (xy 6.659626 -247.33123) (xy 6.668262 -247.324626)
			(xy 6.683095 -247.311195) (xy 6.715168 -247.287263) (xy 6.73227 -247.276874) (xy 6.741414 -247.27154)
			(xy 6.753606 -247.254776) (xy 6.774942 -247.16232) (xy 6.771132 -247.142) (xy 6.76529 -247.13311)
			(xy 6.750213 -247.109541) (xy 6.726382 -247.058921) (xy 6.710209 -247.00536) (xy 6.702039 -246.950011)
			(xy 6.701536 -246.922036) (xy 6.702022 -246.894785) (xy 6.709778 -246.840837) (xy 6.725133 -246.788542)
			(xy 6.747775 -246.738965) (xy 6.777241 -246.693115) (xy 6.812932 -246.651924) (xy 6.854123 -246.616233)
			(xy 6.899973 -246.586767) (xy 6.94955 -246.564125) (xy 7.001845 -246.54877) (xy 7.055793 -246.541014)
			(xy 7.110295 -246.541014) (xy 7.164243 -246.54877) (xy 7.216538 -246.564125) (xy 7.266115 -246.586767)
			(xy 7.311965 -246.616233) (xy 7.353156 -246.651924) (xy 7.388847 -246.693115) (xy 7.418313 -246.738965)
			(xy 7.440955 -246.788542) (xy 7.45631 -246.840837) (xy 7.464066 -246.894785) (xy 7.464552 -246.922036)
			(xy 7.464059 -246.949481) (xy 7.456164 -247.003801) (xy 7.44057 -247.05643) (xy 7.4295 -247.081548)
			(xy 7.424166 -247.093486) (xy 7.425896 -247.118454) (xy 9.618155 -247.118454) (xy 9.618155 -247.063946)
			(xy 9.625913 -247.009994) (xy 9.64127 -246.957695) (xy 9.663914 -246.908113) (xy 9.693383 -246.862259)
			(xy 9.729079 -246.821066) (xy 9.770274 -246.785372) (xy 9.816129 -246.755905) (xy 9.865711 -246.733263)
			(xy 9.918011 -246.717909) (xy 9.971964 -246.710154) (xy 9.999218 -246.709692) (xy 10.028134 -246.710234)
			(xy 10.085306 -246.718954) (xy 10.140506 -246.736204) (xy 10.192469 -246.761591) (xy 10.240003 -246.794533)
			(xy 10.282019 -246.834273) (xy 10.300208 -246.856758) (xy 10.307761 -246.865529) (xy 10.328527 -246.875705)
			(xy 10.340086 -246.876316) (xy 10.42035 -246.876316) (xy 10.431913 -246.875711) (xy 10.452684 -246.86554)
			(xy 10.460228 -246.856758) (xy 10.478393 -246.834252) (xy 10.520419 -246.79452) (xy 10.56796 -246.761585)
			(xy 10.619926 -246.736201) (xy 10.675128 -246.718949) (xy 10.732301 -246.710225) (xy 10.761218 -246.709692)
			(xy 10.788468 -246.710179) (xy 10.842414 -246.717938) (xy 10.894707 -246.733294) (xy 10.944282 -246.755936)
			(xy 10.99013 -246.785403) (xy 11.031318 -246.821095) (xy 11.067008 -246.862285) (xy 11.096472 -246.908134)
			(xy 11.119112 -246.95771) (xy 11.134466 -247.010003) (xy 11.142222 -247.06395) (xy 11.142222 -247.11845)
			(xy 11.134466 -247.172397) (xy 11.119112 -247.22469) (xy 11.096472 -247.274266) (xy 11.067008 -247.320115)
			(xy 11.031318 -247.361305) (xy 10.99013 -247.396997) (xy 10.944282 -247.426464) (xy 10.894707 -247.449106)
			(xy 10.842414 -247.464462) (xy 10.788468 -247.472221) (xy 10.761218 -247.472708) (xy 10.7323 -247.472212)
			(xy 10.675126 -247.463483) (xy 10.619925 -247.446223) (xy 10.567963 -247.420827) (xy 10.52043 -247.387878)
			(xy 10.478416 -247.348131) (xy 10.460228 -247.325642) (xy 10.45266 -247.316887) (xy 10.431905 -247.306702)
			(xy 10.42035 -247.306084) (xy 10.340086 -247.306084) (xy 10.328518 -247.306652) (xy 10.307748 -247.316849)
			(xy 10.300208 -247.325642) (xy 10.282023 -247.34813) (xy 10.240001 -247.387863) (xy 10.192464 -247.420801)
			(xy 10.140502 -247.446188) (xy 10.085304 -247.463443) (xy 10.028134 -247.472173) (xy 9.999218 -247.472708)
			(xy 9.971964 -247.472246) (xy 9.918011 -247.464491) (xy 9.865711 -247.449137) (xy 9.816129 -247.426495)
			(xy 9.770274 -247.397028) (xy 9.729079 -247.361334) (xy 9.693383 -247.320141) (xy 9.663914 -247.274287)
			(xy 9.64127 -247.224705) (xy 9.625913 -247.172406) (xy 9.618155 -247.118454) (xy 7.425896 -247.118454)
			(xy 7.425944 -247.11914) (xy 7.47903 -247.202198) (xy 7.483882 -247.209236) (xy 7.497275 -247.219845)
			(xy 7.513413 -247.225452) (xy 7.521956 -247.22582) (xy 7.739888 -247.22582) (xy 7.768851 -247.226358)
			(xy 7.826065 -247.235419) (xy 7.881155 -247.253321) (xy 7.932767 -247.279622) (xy 7.979627 -247.313675)
			(xy 8.000492 -247.33377) (xy 8.856218 -248.189496) (xy 8.874534 -248.208546) (xy 9.396982 -248.208546)
			(xy 9.401053 -248.152924) (xy 9.413179 -248.098487) (xy 9.433102 -248.046396) (xy 9.460398 -247.997761)
			(xy 9.494484 -247.953618) (xy 9.534633 -247.914909) (xy 9.579991 -247.882458) (xy 9.629591 -247.856957)
			(xy 9.682375 -247.83895) (xy 9.737218 -247.82882) (xy 9.792952 -247.826783) (xy 9.848389 -247.832883)
			(xy 9.902346 -247.846989) (xy 9.953675 -247.868801) (xy 10.001281 -247.897855) (xy 10.044149 -247.93353)
			(xy 10.081366 -247.975067) (xy 10.112139 -248.02158) (xy 10.135811 -248.072077) (xy 10.151879 -248.125484)
			(xy 10.159999 -248.18066) (xy 10.160508 -248.208546) (xy 10.159999 -248.236432) (xy 10.151879 -248.291608)
			(xy 10.135811 -248.345015) (xy 10.112139 -248.395512) (xy 10.081366 -248.442025) (xy 10.044149 -248.483562)
			(xy 10.001281 -248.519237) (xy 9.953675 -248.548291) (xy 9.902346 -248.570103) (xy 9.848389 -248.584209)
			(xy 9.792952 -248.590309) (xy 9.737218 -248.588272) (xy 9.682375 -248.578142) (xy 9.629591 -248.560135)
			(xy 9.579991 -248.534634) (xy 9.534633 -248.502183) (xy 9.494484 -248.463474) (xy 9.460398 -248.419331)
			(xy 9.433102 -248.370696) (xy 9.413179 -248.318605) (xy 9.401053 -248.264168) (xy 9.396982 -248.208546)
			(xy 8.874534 -248.208546) (xy 8.876294 -248.210376) (xy 8.910338 -248.257236) (xy 8.936633 -248.308845)
			(xy 8.954531 -248.363931) (xy 8.963592 -248.421139) (xy 8.964168 -248.4501) (xy 8.964168 -251.743206)
			(xy 11.978673 -251.743206) (xy 11.982401 -251.689957) (xy 11.993515 -251.637748) (xy 12.011798 -251.587597)
			(xy 12.036893 -251.540484) (xy 12.068309 -251.497329) (xy 12.105434 -251.458975) (xy 12.126214 -251.44222)
			(xy 12.134965 -251.434648) (xy 12.145154 -251.413897) (xy 12.145772 -251.402342) (xy 12.145772 -251.322078)
			(xy 12.145166 -251.310514) (xy 12.134998 -251.289742) (xy 12.126214 -251.2822) (xy 12.105443 -251.265434)
			(xy 12.068317 -251.22708) (xy 12.036899 -251.183926) (xy 12.011803 -251.136814) (xy 11.993519 -251.086664)
			(xy 11.982403 -251.034455) (xy 11.978673 -250.981206) (xy 11.982401 -250.927957) (xy 11.993515 -250.875748)
			(xy 12.011798 -250.825597) (xy 12.036893 -250.778484) (xy 12.068309 -250.735329) (xy 12.105434 -250.696975)
			(xy 12.126214 -250.68022) (xy 12.134965 -250.672648) (xy 12.145154 -250.651897) (xy 12.145772 -250.640342)
			(xy 12.145772 -250.560078) (xy 12.145166 -250.548514) (xy 12.134998 -250.527742) (xy 12.126214 -250.5202)
			(xy 12.103733 -250.502005) (xy 12.063997 -250.459987) (xy 12.031058 -250.412453) (xy 12.005669 -250.360492)
			(xy 11.988412 -250.305295) (xy 11.979683 -250.248126) (xy 11.979148 -250.21921) (xy 11.979687 -250.191961)
			(xy 11.987441 -250.138018) (xy 12.002793 -250.085727) (xy 12.02543 -250.036152) (xy 12.054891 -249.990304)
			(xy 12.090577 -249.949115) (xy 12.131761 -249.913423) (xy 12.177605 -249.883956) (xy 12.227176 -249.861312)
			(xy 12.279465 -249.845953) (xy 12.333407 -249.838191) (xy 12.360656 -249.837702) (xy 12.388025 -249.838193)
			(xy 12.442203 -249.846005) (xy 12.494706 -249.861488) (xy 12.544453 -249.884324) (xy 12.590421 -249.914043)
			(xy 12.611354 -249.931682) (xy 12.618466 -249.937778) (xy 12.635484 -249.944128) (xy 12.720828 -249.944128)
			(xy 12.737846 -249.937778) (xy 12.744958 -249.931682) (xy 12.765893 -249.914046) (xy 12.811865 -249.884335)
			(xy 12.861612 -249.861498) (xy 12.914112 -249.846006) (xy 12.968287 -249.838177) (xy 12.995656 -249.837702)
			(xy 13.022908 -249.838196) (xy 13.076859 -249.845948) (xy 13.129156 -249.861298) (xy 13.178737 -249.883937)
			(xy 13.224591 -249.913401) (xy 13.265784 -249.949092) (xy 13.301479 -249.990282) (xy 13.330947 -250.036133)
			(xy 13.35359 -250.085712) (xy 13.368945 -250.138008) (xy 13.376701 -250.191958) (xy 13.377164 -250.21921)
			(xy 13.376594 -250.248125) (xy 13.367878 -250.305295) (xy 13.350631 -250.360493) (xy 13.325249 -250.412455)
			(xy 13.292314 -250.45999) (xy 13.25258 -250.502009) (xy 13.230098 -250.5202) (xy 13.22134 -250.527766)
			(xy 13.211155 -250.548522) (xy 13.21054 -250.560078) (xy 13.21054 -250.640342) (xy 13.21113 -250.651908)
			(xy 13.221309 -250.67268) (xy 13.230098 -250.68022) (xy 13.250893 -250.69696) (xy 13.288027 -250.735313)
			(xy 13.319452 -250.778469) (xy 13.344554 -250.825583) (xy 13.362842 -250.875738) (xy 13.37396 -250.927952)
			(xy 13.377689 -250.981206) (xy 13.373958 -251.03446) (xy 13.362839 -251.086674) (xy 13.344549 -251.136828)
			(xy 13.319446 -251.183942) (xy 13.288019 -251.227096) (xy 13.250884 -251.265448) (xy 13.230098 -251.2822)
			(xy 13.22134 -251.289766) (xy 13.211155 -251.310522) (xy 13.21054 -251.322078) (xy 13.21054 -251.402342)
			(xy 13.21113 -251.413908) (xy 13.221309 -251.43468) (xy 13.230098 -251.44222) (xy 13.250893 -251.45896)
			(xy 13.288027 -251.497313) (xy 13.319452 -251.540469) (xy 13.344554 -251.587583) (xy 13.362842 -251.637738)
			(xy 13.37396 -251.689952) (xy 13.377689 -251.743206) (xy 13.373958 -251.79646) (xy 13.362839 -251.848674)
			(xy 13.344549 -251.898828) (xy 13.319446 -251.945942) (xy 13.288019 -251.989096) (xy 13.250884 -252.027448)
			(xy 13.230098 -252.0442) (xy 13.22134 -252.051766) (xy 13.211155 -252.072522) (xy 13.21054 -252.084078)
			(xy 13.21054 -252.164342) (xy 13.21113 -252.175908) (xy 13.221309 -252.19668) (xy 13.230098 -252.20422)
			(xy 13.252591 -252.2224) (xy 13.292325 -252.264422) (xy 13.325263 -252.311959) (xy 13.35065 -252.363923)
			(xy 13.367904 -252.419122) (xy 13.376631 -252.476293) (xy 13.377164 -252.50521) (xy 13.376754 -252.532465)
			(xy 13.368995 -252.58642) (xy 13.353635 -252.638722) (xy 13.330988 -252.688305) (xy 13.301515 -252.73416)
			(xy 13.265816 -252.775354) (xy 13.224617 -252.811048) (xy 13.178758 -252.840514) (xy 13.129171 -252.863154)
			(xy 13.076867 -252.878506) (xy 13.022911 -252.886258) (xy 12.995656 -252.886718) (xy 12.968286 -252.886239)
			(xy 12.914107 -252.878427) (xy 12.861603 -252.862942) (xy 12.811856 -252.840103) (xy 12.765889 -252.810379)
			(xy 12.744958 -252.792738) (xy 12.737846 -252.786642) (xy 12.720828 -252.780292) (xy 12.635484 -252.780292)
			(xy 12.618466 -252.786642) (xy 12.611354 -252.792738) (xy 12.590418 -252.810372) (xy 12.544445 -252.840083)
			(xy 12.494699 -252.86292) (xy 12.442199 -252.878412) (xy 12.388025 -252.886243) (xy 12.360656 -252.886718)
			(xy 12.333404 -252.886263) (xy 12.279456 -252.878501) (xy 12.227161 -252.863141) (xy 12.177584 -252.840495)
			(xy 12.131735 -252.811025) (xy 12.090545 -252.775331) (xy 12.054854 -252.734138) (xy 12.025389 -252.688286)
			(xy 12.002747 -252.638707) (xy 11.987392 -252.586411) (xy 11.979634 -252.532462) (xy 11.979148 -252.50521)
			(xy 11.979655 -252.476292) (xy 11.988384 -252.41912) (xy 12.005643 -252.36392) (xy 12.031037 -252.311958)
			(xy 12.063983 -252.264425) (xy 12.103727 -252.222409) (xy 12.126214 -252.20422) (xy 12.134965 -252.196648)
			(xy 12.145154 -252.175897) (xy 12.145772 -252.164342) (xy 12.145772 -252.084078) (xy 12.145166 -252.072514)
			(xy 12.134998 -252.051742) (xy 12.126214 -252.0442) (xy 12.105443 -252.027434) (xy 12.068317 -251.98908)
			(xy 12.036899 -251.945926) (xy 12.011803 -251.898814) (xy 11.993519 -251.848664) (xy 11.982403 -251.796455)
			(xy 11.978673 -251.743206) (xy 8.964168 -251.743206) (xy 8.964168 -252.4379) (xy 8.9636 -252.466861)
			(xy 8.954539 -252.524071) (xy 8.936641 -252.579158) (xy 8.910346 -252.630768) (xy 8.876301 -252.677629)
			(xy 8.856218 -252.698504) (xy 8.824733 -252.73) (xy 9.904982 -252.73) (xy 9.909053 -252.674378) (xy 9.921179 -252.619941)
			(xy 9.941102 -252.56785) (xy 9.968398 -252.519215) (xy 10.002484 -252.475072) (xy 10.042633 -252.436363)
			(xy 10.087991 -252.403912) (xy 10.137591 -252.378411) (xy 10.190375 -252.360404) (xy 10.245218 -252.350274)
			(xy 10.300952 -252.348237) (xy 10.356389 -252.354337) (xy 10.410346 -252.368443) (xy 10.461675 -252.390255)
			(xy 10.509281 -252.419309) (xy 10.552149 -252.454984) (xy 10.589366 -252.496521) (xy 10.620139 -252.543034)
			(xy 10.643811 -252.593531) (xy 10.659879 -252.646938) (xy 10.667999 -252.702114) (xy 10.668508 -252.73)
			(xy 10.667999 -252.757886) (xy 10.659879 -252.813062) (xy 10.643811 -252.866469) (xy 10.620139 -252.916966)
			(xy 10.589366 -252.963479) (xy 10.552149 -253.005016) (xy 10.509281 -253.040691) (xy 10.461675 -253.069745)
			(xy 10.410346 -253.091557) (xy 10.356389 -253.105663) (xy 10.300952 -253.111763) (xy 10.245218 -253.109726)
			(xy 10.190375 -253.099596) (xy 10.137591 -253.081589) (xy 10.087991 -253.056088) (xy 10.042633 -253.023637)
			(xy 10.002484 -252.984928) (xy 9.968398 -252.940785) (xy 9.941102 -252.89215) (xy 9.921179 -252.840059)
			(xy 9.909053 -252.785622) (xy 9.904982 -252.73) (xy 8.824733 -252.73) (xy 8.442014 -253.112854) (xy 13.936155 -253.112854)
			(xy 13.936155 -253.058346) (xy 13.943913 -253.004394) (xy 13.95927 -252.952095) (xy 13.981914 -252.902513)
			(xy 14.011383 -252.856659) (xy 14.047079 -252.815466) (xy 14.088274 -252.779772) (xy 14.134129 -252.750305)
			(xy 14.183711 -252.727663) (xy 14.236011 -252.712309) (xy 14.289964 -252.704554) (xy 14.317218 -252.704092)
			(xy 14.346134 -252.704634) (xy 14.403306 -252.713354) (xy 14.458506 -252.730604) (xy 14.510469 -252.755991)
			(xy 14.558003 -252.788933) (xy 14.600019 -252.828673) (xy 14.618208 -252.851158) (xy 14.625761 -252.859929)
			(xy 14.646527 -252.870105) (xy 14.658086 -252.870716) (xy 14.73835 -252.870716) (xy 14.749913 -252.870111)
			(xy 14.770684 -252.85994) (xy 14.778228 -252.851158) (xy 14.794981 -252.830375) (xy 14.833335 -252.793245)
			(xy 14.876489 -252.761823) (xy 14.923603 -252.736724) (xy 14.973755 -252.718438) (xy 15.025966 -252.707321)
			(xy 15.079218 -252.703591) (xy 15.13247 -252.707321) (xy 15.184681 -252.718438) (xy 15.234833 -252.736724)
			(xy 15.281947 -252.761823) (xy 15.325101 -252.793245) (xy 15.363455 -252.830375) (xy 15.380208 -252.851158)
			(xy 15.387761 -252.859929) (xy 15.408527 -252.870105) (xy 15.420086 -252.870716) (xy 15.50035 -252.870716)
			(xy 15.511913 -252.870111) (xy 15.532684 -252.85994) (xy 15.540228 -252.851158) (xy 15.556981 -252.830375)
			(xy 15.595335 -252.793245) (xy 15.638489 -252.761823) (xy 15.685603 -252.736724) (xy 15.735755 -252.718438)
			(xy 15.787966 -252.707321) (xy 15.841218 -252.703591) (xy 15.89447 -252.707321) (xy 15.946681 -252.718438)
			(xy 15.996833 -252.736724) (xy 16.043947 -252.761823) (xy 16.087101 -252.793245) (xy 16.125455 -252.830375)
			(xy 16.142208 -252.851158) (xy 16.149761 -252.859929) (xy 16.170527 -252.870105) (xy 16.182086 -252.870716)
			(xy 16.26235 -252.870716) (xy 16.273913 -252.870111) (xy 16.294684 -252.85994) (xy 16.302228 -252.851158)
			(xy 16.320393 -252.828652) (xy 16.362419 -252.78892) (xy 16.40996 -252.755985) (xy 16.461926 -252.730601)
			(xy 16.517128 -252.713349) (xy 16.574301 -252.704625) (xy 16.603218 -252.704092) (xy 16.630468 -252.704579)
			(xy 16.684414 -252.712338) (xy 16.736707 -252.727694) (xy 16.786282 -252.750336) (xy 16.83213 -252.779803)
			(xy 16.873318 -252.815495) (xy 16.909008 -252.856685) (xy 16.938472 -252.902534) (xy 16.961112 -252.95211)
			(xy 16.976466 -253.004403) (xy 16.984222 -253.05835) (xy 16.984222 -253.11285) (xy 16.976466 -253.166797)
			(xy 16.961112 -253.21909) (xy 16.938472 -253.268666) (xy 16.909008 -253.314515) (xy 16.873318 -253.355705)
			(xy 16.83213 -253.391397) (xy 16.786282 -253.420864) (xy 16.736707 -253.443506) (xy 16.684414 -253.458862)
			(xy 16.630468 -253.466621) (xy 16.603218 -253.467108) (xy 16.5743 -253.466612) (xy 16.517126 -253.457883)
			(xy 16.461925 -253.440623) (xy 16.409963 -253.415227) (xy 16.36243 -253.382278) (xy 16.320416 -253.342531)
			(xy 16.302228 -253.320042) (xy 16.29466 -253.311287) (xy 16.273905 -253.301102) (xy 16.26235 -253.300484)
			(xy 16.182086 -253.300484) (xy 16.170518 -253.301052) (xy 16.149748 -253.311249) (xy 16.142208 -253.320042)
			(xy 16.125455 -253.340825) (xy 16.087101 -253.377955) (xy 16.043947 -253.409377) (xy 15.996833 -253.434476)
			(xy 15.946681 -253.452762) (xy 15.89447 -253.463879) (xy 15.841218 -253.467609) (xy 15.787966 -253.463879)
			(xy 15.735755 -253.452762) (xy 15.685603 -253.434476) (xy 15.638489 -253.409377) (xy 15.595335 -253.377955)
			(xy 15.556981 -253.340825) (xy 15.540228 -253.320042) (xy 15.53266 -253.311287) (xy 15.511905 -253.301102)
			(xy 15.50035 -253.300484) (xy 15.420086 -253.300484) (xy 15.408518 -253.301052) (xy 15.387748 -253.311249)
			(xy 15.380208 -253.320042) (xy 15.363455 -253.340825) (xy 15.325101 -253.377955) (xy 15.281947 -253.409377)
			(xy 15.234833 -253.434476) (xy 15.184681 -253.452762) (xy 15.13247 -253.463879) (xy 15.079218 -253.467609)
			(xy 15.025966 -253.463879) (xy 14.973755 -253.452762) (xy 14.923603 -253.434476) (xy 14.876489 -253.409377)
			(xy 14.833335 -253.377955) (xy 14.794981 -253.340825) (xy 14.778228 -253.320042) (xy 14.77066 -253.311287)
			(xy 14.749905 -253.301102) (xy 14.73835 -253.300484) (xy 14.658086 -253.300484) (xy 14.646518 -253.301052)
			(xy 14.625748 -253.311249) (xy 14.618208 -253.320042) (xy 14.600023 -253.34253) (xy 14.558001 -253.382263)
			(xy 14.510464 -253.415201) (xy 14.458502 -253.440588) (xy 14.403304 -253.457843) (xy 14.346134 -253.466573)
			(xy 14.317218 -253.467108) (xy 14.289964 -253.466646) (xy 14.236011 -253.458891) (xy 14.183711 -253.443537)
			(xy 14.134129 -253.420895) (xy 14.088274 -253.391428) (xy 14.047079 -253.355734) (xy 14.011383 -253.314541)
			(xy 13.981914 -253.268687) (xy 13.95927 -253.219105) (xy 13.943913 -253.166806) (xy 13.936155 -253.112854)
			(xy 8.442014 -253.112854) (xy 8.136128 -253.418848) (xy 8.129433 -253.426254) (xy 8.121827 -253.44469)
			(xy 8.121396 -253.454662) (xy 8.121396 -253.974854) (xy 8.122666 -253.98095) (xy 8.127989 -254.003629)
			(xy 8.133722 -254.04986) (xy 8.134096 -254.073152) (xy 8.133643 -254.099653) (xy 8.126305 -254.152145)
			(xy 8.111764 -254.203114) (xy 8.0903 -254.251575) (xy 8.076692 -254.27432) (xy 8.069326 -254.286258)
			(xy 8.068564 -254.31369) (xy 8.118602 -254.403606) (xy 8.123308 -254.411341) (xy 8.137035 -254.423128)
			(xy 8.154005 -254.429404) (xy 8.163052 -254.429768) (xy 8.581898 -254.429768) (xy 8.591885 -254.42923)
			(xy 8.610315 -254.421514) (xy 8.617712 -254.414782) (xy 8.828532 -254.204216) (xy 8.849382 -254.184091)
			(xy 8.896232 -254.149989) (xy 8.94784 -254.123638) (xy 9.002937 -254.105687) (xy 9.060163 -254.096579)
			(xy 9.089136 -254.096012) (xy 16.620236 -254.096012) (xy 16.64921 -254.09657) (xy 16.706438 -254.105677)
			(xy 16.761535 -254.123628) (xy 16.813143 -254.149982) (xy 16.859991 -254.184089) (xy 16.88084 -254.204216)
			(xy 17.92097 -255.244092) (xy 17.926304 -255.247394) (xy 17.950094 -255.262284) (xy 17.993431 -255.297945)
			(xy 18.031077 -255.339569) (xy 18.062221 -255.386258) (xy 18.08619 -255.437005) (xy 18.102468 -255.490715)
			(xy 18.110704 -255.546231) (xy 18.111216 -255.574292) (xy 18.110731 -255.601544) (xy 18.102975 -255.655493)
			(xy 18.087621 -255.707789) (xy 18.06498 -255.757368) (xy 18.035514 -255.80322) (xy 17.999823 -255.844412)
			(xy 17.958633 -255.880105) (xy 17.912782 -255.909573) (xy 17.863204 -255.932215) (xy 17.810909 -255.947572)
			(xy 17.75696 -255.95533) (xy 17.729708 -255.9558) (xy 17.701646 -255.955303) (xy 17.646128 -255.947077)
			(xy 17.592415 -255.930801) (xy 17.541669 -255.906828) (xy 17.494985 -255.875675) (xy 17.453372 -255.838015)
			(xy 17.417729 -255.794662) (xy 17.40281 -255.770888) (xy 17.399508 -255.765554) (xy 16.482314 -254.84836)
			(xy 16.474903 -254.841678) (xy 16.456468 -254.834097) (xy 16.4465 -254.833628) (xy 14.76248 -254.833628)
			(xy 14.751394 -254.834122) (xy 14.731237 -254.843341) (xy 14.723618 -254.851408) (xy 14.666214 -254.91948)
			(xy 14.660372 -254.940816) (xy 14.662404 -254.951992) (xy 14.664914 -254.967874) (xy 14.667583 -254.999921)
			(xy 14.667738 -255.016) (xy 14.667252 -255.043251) (xy 14.659496 -255.097199) (xy 14.644141 -255.149494)
			(xy 14.621499 -255.199071) (xy 14.592033 -255.244921) (xy 14.556342 -255.286112) (xy 14.515151 -255.321803)
			(xy 14.469301 -255.351269) (xy 14.419724 -255.373911) (xy 14.367429 -255.389266) (xy 14.313481 -255.397022)
			(xy 14.258979 -255.397022) (xy 14.205031 -255.389266) (xy 14.152736 -255.373911) (xy 14.103159 -255.351269)
			(xy 14.057309 -255.321803) (xy 14.016118 -255.286112) (xy 13.980427 -255.244921) (xy 13.950961 -255.199071)
			(xy 13.928319 -255.149494) (xy 13.912964 -255.097199) (xy 13.905208 -255.043251) (xy 13.904722 -255.016)
			(xy 13.904866 -254.999921) (xy 13.907536 -254.967873) (xy 13.910056 -254.951992) (xy 13.912088 -254.940816)
			(xy 13.906246 -254.91948) (xy 13.848842 -254.851408) (xy 13.841222 -254.843337) (xy 13.821068 -254.834097)
			(xy 13.80998 -254.833628) (xy 10.269728 -254.833628) (xy 10.259828 -254.834104) (xy 10.241504 -254.841604)
			(xy 10.227366 -254.855467) (xy 10.222992 -254.864362) (xy 10.18032 -254.964438) (xy 10.185908 -254.99441)
			(xy 10.196322 -255.005586) (xy 10.216223 -255.027013) (xy 10.249884 -255.074831) (xy 10.27585 -255.127227)
			(xy 10.293511 -255.182973) (xy 10.302455 -255.240762) (xy 10.303002 -255.27) (xy 10.302516 -255.297251)
			(xy 10.29476 -255.351199) (xy 10.279405 -255.403494) (xy 10.256763 -255.453071) (xy 10.227297 -255.498921)
			(xy 10.191606 -255.540112) (xy 10.150415 -255.575803) (xy 10.104565 -255.605269) (xy 10.054988 -255.627911)
			(xy 10.002693 -255.643266) (xy 9.948745 -255.651022) (xy 9.894243 -255.651022) (xy 9.840295 -255.643266)
			(xy 9.788 -255.627911) (xy 9.738423 -255.605269) (xy 9.692573 -255.575803) (xy 9.651382 -255.540112)
			(xy 9.615691 -255.498921) (xy 9.586225 -255.453071) (xy 9.563583 -255.403494) (xy 9.548228 -255.351199)
			(xy 9.540472 -255.297251) (xy 9.539986 -255.27) (xy 9.540566 -255.240765) (xy 9.549526 -255.182985)
			(xy 9.567191 -255.127247) (xy 9.593148 -255.074854) (xy 9.626789 -255.027031) (xy 9.646666 -255.005586)
			(xy 9.65708 -254.99441) (xy 9.662668 -254.964438) (xy 9.619996 -254.864362) (xy 9.615663 -254.855436)
			(xy 9.601527 -254.841543) (xy 9.583172 -254.834063) (xy 9.57326 -254.833628) (xy 9.262872 -254.833628)
			(xy 9.252907 -254.834108) (xy 9.234476 -254.841689) (xy 9.227058 -254.84836) (xy 9.016238 -255.058926)
			(xy 8.995358 -255.079004) (xy 8.948499 -255.113052) (xy 8.896891 -255.139351) (xy 8.841804 -255.157253)
			(xy 8.784595 -255.166319) (xy 8.755634 -255.166876) (xy 6.894322 -255.166876) (xy 6.86536 -255.16631)
			(xy 6.808149 -255.157252) (xy 6.753059 -255.139357) (xy 6.701446 -255.113064) (xy 6.654582 -255.07902)
			(xy 6.633718 -255.058926) (xy 4.45389 -252.879098) (xy 4.437075 -252.861805) (xy 4.407655 -252.823583)
			(xy 4.383483 -252.781844) (xy 4.37388 -252.759718) (xy 4.16179 -252.2474) (xy 4.15677 -252.236794)
			(xy 4.139138 -252.221352) (xy 4.116482 -252.21535) (xy 4.104894 -252.217174) (xy 4.08686 -252.22073)
			(xy 4.064 -252.24867) (xy 4.064 -252.2982) (xy 4.063512 -252.308208) (xy 4.055852 -252.326699) (xy 4.041699 -252.340852)
			(xy 4.023208 -252.348512) (xy 4.0132 -252.349) (xy 3.655568 -252.349) (xy 3.645565 -252.349494) (xy 3.627084 -252.357159)
			(xy 3.612941 -252.371311) (xy 3.605287 -252.389796) (xy 3.604768 -252.3998) (xy 3.604768 -252.40615)
			(xy 3.605373 -252.418575) (xy 3.616939 -252.440568) (xy 3.626866 -252.44806) (xy 3.706368 -252.50267)
			(xy 3.731006 -252.505464) (xy 3.742944 -252.500892) (xy 3.764863 -252.492849) (xy 3.810164 -252.481547)
			(xy 3.856505 -252.47585) (xy 3.87985 -252.475492) (xy 3.907101 -252.475978) (xy 3.961049 -252.483734)
			(xy 4.013344 -252.499089) (xy 4.062921 -252.521731) (xy 4.108771 -252.551197) (xy 4.149962 -252.586888)
			(xy 4.185653 -252.628079) (xy 4.215119 -252.673929) (xy 4.237761 -252.723506) (xy 4.253116 -252.775801)
			(xy 4.260872 -252.829749) (xy 4.261358 -252.857) (xy 4.260888 -252.884406) (xy 4.253049 -252.938654)
			(xy 4.237523 -252.991221) (xy 4.21463 -253.041022) (xy 4.184841 -253.087032) (xy 4.148771 -253.128303)
			(xy 4.107163 -253.163983) (xy 4.060874 -253.193337) (xy 4.03606 -253.20498) (xy 4.024376 -253.210314)
			(xy 4.009136 -253.229618) (xy 3.991864 -253.324614) (xy 3.990381 -253.336842) (xy 3.997696 -253.360321)
			(xy 4.005834 -253.369572) (xy 4.070604 -253.434596) (xy 4.090731 -253.455446) (xy 4.124835 -253.502295)
			(xy 4.151189 -253.553903) (xy 4.169144 -253.608999) (xy 4.178258 -253.666226) (xy 4.178808 -253.6952)
			(xy 4.178808 -254.231902) (xy 4.180078 -254.237998) (xy 4.185398 -254.260677) (xy 4.191125 -254.306908)
			(xy 4.191508 -254.3302) (xy 4.191022 -254.357451) (xy 4.183266 -254.411399) (xy 4.167911 -254.463694)
			(xy 4.145269 -254.513271) (xy 4.115803 -254.559121) (xy 4.080112 -254.600312) (xy 4.038921 -254.636003)
			(xy 3.993071 -254.665469) (xy 3.943494 -254.688111) (xy 3.891199 -254.703466) (xy 3.837251 -254.711222)
			(xy 3.782749 -254.711222) (xy 3.728801 -254.703466) (xy 3.676506 -254.688111) (xy 3.626929 -254.665469)
			(xy 3.581079 -254.636003) (xy 3.539888 -254.600312) (xy 3.504197 -254.559121) (xy 3.474731 -254.513271)
			(xy 3.452089 -254.463694) (xy 3.436734 -254.411399) (xy 3.428978 -254.357451) (xy 3.428492 -254.3302)
			(xy 3.42887 -254.306908) (xy 3.434597 -254.260676) (xy 3.439922 -254.237998) (xy 3.441192 -254.231902)
			(xy 3.441192 -253.868936) (xy 3.440706 -253.858974) (xy 3.433118 -253.84055) (xy 3.42646 -253.833122)
			(xy 2.97561 -253.382018) (xy 2.955509 -253.361158) (xy 2.921458 -253.314295) (xy 2.895157 -253.262683)
			(xy 2.877254 -253.207592) (xy 2.86819 -253.150378) (xy 2.86766 -253.121414) (xy 2.86766 -249.91695)
			(xy 2.86713 -249.906959) (xy 2.859425 -249.888518) (xy 2.852674 -249.881136) (xy 1.356868 -248.38533)
			(xy 1.349503 -248.378503) (xy 1.33099 -248.370756) (xy 1.310922 -248.370694) (xy 1.301496 -248.374154)
			(xy 1.287018 -248.38025) (xy 1.27 -248.405396) (xy 1.27 -255.741424) (xy 11.93546 -255.741424) (xy 11.936 -255.714175)
			(xy 11.943753 -255.660231) (xy 11.959103 -255.607939) (xy 11.981739 -255.558364) (xy 12.0112 -255.512515)
			(xy 12.046886 -255.471326) (xy 12.08807 -255.435634) (xy 12.133915 -255.406166) (xy 12.183487 -255.383523)
			(xy 12.235776 -255.368165) (xy 12.289719 -255.360404) (xy 12.316968 -255.359916) (xy 12.345029 -255.360413)
			(xy 12.400544 -255.368656) (xy 12.454253 -255.384939) (xy 12.504999 -255.408912) (xy 12.551687 -255.440057)
			(xy 12.593311 -255.477703) (xy 12.628974 -255.521039) (xy 12.643866 -255.544828) (xy 12.647168 -255.550162)
			(xy 13.029133 -255.932251) (xy 13.881078 -255.932251) (xy 13.881078 -255.877749) (xy 13.888834 -255.823801)
			(xy 13.904189 -255.771506) (xy 13.926831 -255.721929) (xy 13.956297 -255.676079) (xy 13.991988 -255.634888)
			(xy 14.033179 -255.599197) (xy 14.079029 -255.569731) (xy 14.128606 -255.547089) (xy 14.180901 -255.531734)
			(xy 14.234849 -255.523978) (xy 14.2621 -255.523492) (xy 14.291027 -255.524027) (xy 14.348218 -255.532762)
			(xy 14.403435 -255.550033) (xy 14.455411 -255.575442) (xy 14.502954 -255.608408) (xy 14.544975 -255.648175)
			(xy 14.58051 -255.69383) (xy 14.595094 -255.718818) (xy 14.602315 -255.730912) (xy 14.622246 -255.750805)
			(xy 14.646854 -255.764495) (xy 14.674266 -255.77094) (xy 14.702397 -255.76965) (xy 14.729104 -255.760723)
			(xy 14.752356 -255.744838) (xy 14.761718 -255.734312) (xy 14.779964 -255.713373) (xy 14.821436 -255.676434)
			(xy 14.867826 -255.645899) (xy 14.918153 -255.622414) (xy 14.971354 -255.606474) (xy 15.026303 -255.598417)
			(xy 15.054072 -255.597914) (xy 15.081328 -255.598331) (xy 15.135285 -255.606085) (xy 15.187589 -255.62144)
			(xy 15.237176 -255.644082) (xy 15.247942 -255.651) (xy 15.901414 -255.651) (xy 15.905485 -255.595378)
			(xy 15.917611 -255.540941) (xy 15.937534 -255.48885) (xy 15.96483 -255.440215) (xy 15.998916 -255.396072)
			(xy 16.039065 -255.357363) (xy 16.084423 -255.324912) (xy 16.134023 -255.299411) (xy 16.186807 -255.281404)
			(xy 16.24165 -255.271274) (xy 16.297384 -255.269237) (xy 16.352821 -255.275337) (xy 16.406778 -255.289443)
			(xy 16.458107 -255.311255) (xy 16.505713 -255.340309) (xy 16.548581 -255.375984) (xy 16.585798 -255.417521)
			(xy 16.616571 -255.464034) (xy 16.640243 -255.514531) (xy 16.656311 -255.567938) (xy 16.664431 -255.623114)
			(xy 16.66494 -255.651) (xy 16.664431 -255.678886) (xy 16.656311 -255.734062) (xy 16.640243 -255.787469)
			(xy 16.616571 -255.837966) (xy 16.585798 -255.884479) (xy 16.548581 -255.926016) (xy 16.505713 -255.961691)
			(xy 16.458107 -255.990745) (xy 16.406778 -256.012557) (xy 16.352821 -256.026663) (xy 16.297384 -256.032763)
			(xy 16.24165 -256.030726) (xy 16.186807 -256.020596) (xy 16.134023 -256.002589) (xy 16.084423 -255.977088)
			(xy 16.039065 -255.944637) (xy 15.998916 -255.905928) (xy 15.96483 -255.861785) (xy 15.937534 -255.81315)
			(xy 15.917611 -255.761059) (xy 15.905485 -255.706622) (xy 15.901414 -255.651) (xy 15.247942 -255.651)
			(xy 15.283035 -255.673551) (xy 15.324234 -255.709247) (xy 15.359932 -255.750442) (xy 15.389405 -255.7963)
			(xy 15.412051 -255.845885) (xy 15.427409 -255.898188) (xy 15.435167 -255.952144) (xy 15.435167 -256.006656)
			(xy 15.427409 -256.060612) (xy 15.412051 -256.112915) (xy 15.389405 -256.1625) (xy 15.359932 -256.208358)
			(xy 15.324234 -256.249553) (xy 15.283035 -256.285249) (xy 15.237176 -256.314718) (xy 15.187589 -256.33736)
			(xy 15.135285 -256.352715) (xy 15.081328 -256.360469) (xy 15.054072 -256.36093) (xy 15.025145 -256.360406)
			(xy 14.967953 -256.351668) (xy 14.912737 -256.334394) (xy 14.860762 -256.308982) (xy 14.813218 -256.276015)
			(xy 14.771198 -256.236247) (xy 14.735662 -256.190592) (xy 14.721078 -256.165604) (xy 14.713767 -256.153573)
			(xy 14.693848 -256.133697) (xy 14.66926 -256.120016) (xy 14.64187 -256.113569) (xy 14.61376 -256.114845)
			(xy 14.587067 -256.123748) (xy 14.563819 -256.139601) (xy 14.554454 -256.15011) (xy 14.536228 -256.171067)
			(xy 14.494751 -256.208004) (xy 14.448357 -256.238536) (xy 14.398026 -256.262018) (xy 14.344822 -256.277954)
			(xy 14.28987 -256.286007) (xy 14.2621 -256.286508) (xy 14.234849 -256.286022) (xy 14.180901 -256.278266)
			(xy 14.128606 -256.262911) (xy 14.079029 -256.240269) (xy 14.033179 -256.210803) (xy 13.991988 -256.175112)
			(xy 13.956297 -256.133921) (xy 13.926831 -256.088071) (xy 13.904189 -256.038494) (xy 13.888834 -255.986199)
			(xy 13.881078 -255.932251) (xy 13.029133 -255.932251) (xy 13.431012 -256.33426) (xy 13.451144 -256.355105)
			(xy 13.485249 -256.401954) (xy 13.511601 -256.453564) (xy 13.529552 -256.508662) (xy 13.538658 -256.56589)
			(xy 13.539216 -256.594864) (xy 13.539216 -256.93751) (xy 13.539683 -256.947478) (xy 13.547266 -256.965913)
			(xy 13.553948 -256.973324) (xy 14.00948 -257.429) (xy 17.905982 -257.429) (xy 17.910053 -257.373378)
			(xy 17.922179 -257.318941) (xy 17.942102 -257.26685) (xy 17.969398 -257.218215) (xy 18.003484 -257.174072)
			(xy 18.043633 -257.135363) (xy 18.088991 -257.102912) (xy 18.138591 -257.077411) (xy 18.191375 -257.059404)
			(xy 18.246218 -257.049274) (xy 18.301952 -257.047237) (xy 18.357389 -257.053337) (xy 18.411346 -257.067443)
			(xy 18.462675 -257.089255) (xy 18.510281 -257.118309) (xy 18.553149 -257.153984) (xy 18.590366 -257.195521)
			(xy 18.621139 -257.242034) (xy 18.644811 -257.292531) (xy 18.660879 -257.345938) (xy 18.668999 -257.401114)
			(xy 18.669508 -257.429) (xy 18.668999 -257.456886) (xy 18.660879 -257.512062) (xy 18.644811 -257.565469)
			(xy 18.621139 -257.615966) (xy 18.590366 -257.662479) (xy 18.553149 -257.704016) (xy 18.510281 -257.739691)
			(xy 18.462675 -257.768745) (xy 18.411346 -257.790557) (xy 18.357389 -257.804663) (xy 18.301952 -257.810763)
			(xy 18.246218 -257.808726) (xy 18.191375 -257.798596) (xy 18.138591 -257.780589) (xy 18.088991 -257.755088)
			(xy 18.043633 -257.722637) (xy 18.003484 -257.683928) (xy 17.969398 -257.639785) (xy 17.942102 -257.59115)
			(xy 17.922179 -257.539059) (xy 17.910053 -257.484622) (xy 17.905982 -257.429) (xy 14.00948 -257.429)
			(xy 14.357604 -257.777234) (xy 14.377722 -257.798092) (xy 14.411829 -257.844937) (xy 14.438184 -257.896544)
			(xy 14.456138 -257.951639) (xy 14.465248 -258.008865) (xy 14.465808 -258.037838) (xy 14.465808 -259.969)
			(xy 14.465258 -259.997974) (xy 14.456144 -260.055201) (xy 14.438189 -260.110297) (xy 14.411835 -260.161905)
			(xy 14.377731 -260.208754) (xy 14.357604 -260.229604) (xy 14.110319 -260.477) (xy 15.492982 -260.477)
			(xy 15.497053 -260.421378) (xy 15.509179 -260.366941) (xy 15.529102 -260.31485) (xy 15.556398 -260.266215)
			(xy 15.590484 -260.222072) (xy 15.630633 -260.183363) (xy 15.675991 -260.150912) (xy 15.725591 -260.125411)
			(xy 15.778375 -260.107404) (xy 15.833218 -260.097274) (xy 15.888952 -260.095237) (xy 15.944389 -260.101337)
			(xy 15.998346 -260.115443) (xy 16.049675 -260.137255) (xy 16.097281 -260.166309) (xy 16.140149 -260.201984)
			(xy 16.177366 -260.243521) (xy 16.208139 -260.290034) (xy 16.231811 -260.340531) (xy 16.23466 -260.35)
			(xy 16.381982 -260.35) (xy 16.386053 -260.294378) (xy 16.398179 -260.239941) (xy 16.418102 -260.18785)
			(xy 16.445398 -260.139215) (xy 16.479484 -260.095072) (xy 16.519633 -260.056363) (xy 16.564991 -260.023912)
			(xy 16.614591 -259.998411) (xy 16.667375 -259.980404) (xy 16.722218 -259.970274) (xy 16.777952 -259.968237)
			(xy 16.833389 -259.974337) (xy 16.887346 -259.988443) (xy 16.938675 -260.010255) (xy 16.986281 -260.039309)
			(xy 17.029149 -260.074984) (xy 17.066366 -260.116521) (xy 17.097139 -260.163034) (xy 17.120811 -260.213531)
			(xy 17.136879 -260.266938) (xy 17.144999 -260.322114) (xy 17.145508 -260.35) (xy 17.144999 -260.377886)
			(xy 17.136879 -260.433062) (xy 17.120811 -260.486469) (xy 17.097139 -260.536966) (xy 17.066366 -260.583479)
			(xy 17.047979 -260.604) (xy 18.413982 -260.604) (xy 18.418053 -260.548378) (xy 18.430179 -260.493941)
			(xy 18.450102 -260.44185) (xy 18.477398 -260.393215) (xy 18.511484 -260.349072) (xy 18.551633 -260.310363)
			(xy 18.596991 -260.277912) (xy 18.646591 -260.252411) (xy 18.699375 -260.234404) (xy 18.754218 -260.224274)
			(xy 18.809952 -260.222237) (xy 18.865389 -260.228337) (xy 18.919346 -260.242443) (xy 18.970675 -260.264255)
			(xy 19.018281 -260.293309) (xy 19.061149 -260.328984) (xy 19.098366 -260.370521) (xy 19.129139 -260.417034)
			(xy 19.152811 -260.467531) (xy 19.168879 -260.520938) (xy 19.176999 -260.576114) (xy 19.177508 -260.604)
			(xy 19.176999 -260.631886) (xy 19.168879 -260.687062) (xy 19.152811 -260.740469) (xy 19.129139 -260.790966)
			(xy 19.098366 -260.837479) (xy 19.061149 -260.879016) (xy 19.018281 -260.914691) (xy 18.970675 -260.943745)
			(xy 18.919346 -260.965557) (xy 18.865389 -260.979663) (xy 18.809952 -260.985763) (xy 18.754218 -260.983726)
			(xy 18.699375 -260.973596) (xy 18.646591 -260.955589) (xy 18.596991 -260.930088) (xy 18.551633 -260.897637)
			(xy 18.511484 -260.858928) (xy 18.477398 -260.814785) (xy 18.450102 -260.76615) (xy 18.430179 -260.714059)
			(xy 18.418053 -260.659622) (xy 18.413982 -260.604) (xy 17.047979 -260.604) (xy 17.029149 -260.625016)
			(xy 16.986281 -260.660691) (xy 16.938675 -260.689745) (xy 16.887346 -260.711557) (xy 16.833389 -260.725663)
			(xy 16.777952 -260.731763) (xy 16.722218 -260.729726) (xy 16.667375 -260.719596) (xy 16.614591 -260.701589)
			(xy 16.564991 -260.676088) (xy 16.519633 -260.643637) (xy 16.479484 -260.604928) (xy 16.445398 -260.560785)
			(xy 16.418102 -260.51215) (xy 16.398179 -260.460059) (xy 16.386053 -260.405622) (xy 16.381982 -260.35)
			(xy 16.23466 -260.35) (xy 16.247879 -260.393938) (xy 16.255999 -260.449114) (xy 16.256508 -260.477)
			(xy 16.255999 -260.504886) (xy 16.247879 -260.560062) (xy 16.231811 -260.613469) (xy 16.208139 -260.663966)
			(xy 16.177366 -260.710479) (xy 16.140149 -260.752016) (xy 16.097281 -260.787691) (xy 16.049675 -260.816745)
			(xy 15.998346 -260.838557) (xy 15.944389 -260.852663) (xy 15.888952 -260.858763) (xy 15.833218 -260.856726)
			(xy 15.778375 -260.846596) (xy 15.725591 -260.828589) (xy 15.675991 -260.803088) (xy 15.630633 -260.770637)
			(xy 15.590484 -260.731928) (xy 15.556398 -260.687785) (xy 15.529102 -260.63915) (xy 15.509179 -260.587059)
			(xy 15.497053 -260.532622) (xy 15.492982 -260.477) (xy 14.110319 -260.477) (xy 13.7922 -260.795262)
			(xy 13.788898 -260.800596) (xy 13.773977 -260.824368) (xy 13.738334 -260.867721) (xy 13.696721 -260.905381)
			(xy 13.650037 -260.936534) (xy 13.599291 -260.960507) (xy 13.545579 -260.976783) (xy 13.490062 -260.98501)
			(xy 13.462 -260.985508) (xy 13.434749 -260.985022) (xy 13.380801 -260.977266) (xy 13.328506 -260.961911)
			(xy 13.278929 -260.939269) (xy 13.233079 -260.909803) (xy 13.191888 -260.874112) (xy 13.156197 -260.832921)
			(xy 13.126731 -260.787071) (xy 13.104089 -260.737494) (xy 13.088734 -260.685199) (xy 13.080978 -260.631251)
			(xy 13.080492 -260.604) (xy 13.081006 -260.575939) (xy 13.089241 -260.520423) (xy 13.105519 -260.466713)
			(xy 13.129487 -260.415966) (xy 13.160631 -260.369277) (xy 13.198277 -260.327653) (xy 13.241614 -260.291992)
			(xy 13.265404 -260.277102) (xy 13.270738 -260.2738) (xy 13.528802 -260.01599) (xy 13.535484 -260.008595)
			(xy 13.543056 -259.990177) (xy 13.543064 -259.970264) (xy 13.539724 -259.960872) (xy 13.498576 -259.85978)
			(xy 13.47343 -259.842762) (xy 13.457936 -259.842508) (xy 13.429054 -259.841675) (xy 13.37203 -259.832365)
			(xy 13.317064 -259.814559) (xy 13.265413 -259.788664) (xy 13.241528 -259.772404) (xy 13.230098 -259.764276)
			(xy 13.202158 -259.76199) (xy 13.096748 -259.814822) (xy 13.081762 -259.838444) (xy 13.081254 -259.852414)
			(xy 13.080101 -259.87917) (xy 13.071189 -259.931979) (xy 13.054976 -259.983021) (xy 13.03178 -260.031293)
			(xy 13.002057 -260.075843) (xy 12.966393 -260.115797) (xy 12.92549 -260.150367) (xy 12.880152 -260.178873)
			(xy 12.83127 -260.200755) (xy 12.779808 -260.215582) (xy 12.726778 -260.223062) (xy 12.7 -260.223508)
			(xy 12.672749 -260.223022) (xy 12.618801 -260.215266) (xy 12.566506 -260.199911) (xy 12.516929 -260.177269)
			(xy 12.471079 -260.147803) (xy 12.429888 -260.112112) (xy 12.394197 -260.070921) (xy 12.364731 -260.025071)
			(xy 12.342089 -259.975494) (xy 12.326734 -259.923199) (xy 12.318978 -259.869251) (xy 12.318978 -259.814749)
			(xy 12.326734 -259.760801) (xy 12.342089 -259.708506) (xy 12.364731 -259.658929) (xy 12.394197 -259.613079)
			(xy 12.429888 -259.571888) (xy 12.471079 -259.536197) (xy 12.516929 -259.506731) (xy 12.566506 -259.484089)
			(xy 12.618801 -259.468734) (xy 12.672749 -259.460978) (xy 12.7 -259.460492) (xy 12.729396 -259.461046)
			(xy 12.787494 -259.470059) (xy 12.843523 -259.487871) (xy 12.89616 -259.514063) (xy 12.920472 -259.530596)
			(xy 12.931902 -259.538724) (xy 12.959842 -259.54101) (xy 13.065252 -259.488178) (xy 13.080238 -259.464556)
			(xy 13.080746 -259.450586) (xy 13.081899 -259.42383) (xy 13.090811 -259.371021) (xy 13.107024 -259.319979)
			(xy 13.13022 -259.271707) (xy 13.159943 -259.227157) (xy 13.195607 -259.187203) (xy 13.23651 -259.152633)
			(xy 13.281848 -259.124127) (xy 13.33073 -259.102245) (xy 13.382192 -259.087418) (xy 13.435222 -259.079938)
			(xy 13.462 -259.079492) (xy 13.495199 -259.080216) (xy 13.560595 -259.091705) (xy 13.592048 -259.102352)
			(xy 13.603732 -259.10667) (xy 13.62837 -259.103368) (xy 13.706602 -259.048504) (xy 13.716203 -259.040859)
			(xy 13.727477 -259.0191) (xy 13.728192 -259.006848) (xy 13.728192 -258.211574) (xy 13.727758 -258.201602)
			(xy 13.720155 -258.183166) (xy 13.71346 -258.17576) (xy 12.979146 -257.441446) (xy 12.973812 -257.438144)
			(xy 12.950017 -257.423257) (xy 12.906664 -257.387609) (xy 12.869005 -257.34599) (xy 12.837855 -257.299301)
			(xy 12.813885 -257.248549) (xy 12.797614 -257.194832) (xy 12.789394 -257.13931) (xy 12.7889 -257.111246)
			(xy 12.789273 -257.087954) (xy 12.795006 -257.041723) (xy 12.80033 -257.019044) (xy 12.8016 -257.012948)
			(xy 12.8016 -256.7686) (xy 12.80115 -256.75863) (xy 12.793558 -256.740193) (xy 12.786868 -256.732786)
			(xy 12.125706 -256.071624) (xy 12.120372 -256.068322) (xy 12.096558 -256.053464) (xy 12.053207 -256.01781)
			(xy 12.015551 -255.976185) (xy 11.984403 -255.929491) (xy 11.960437 -255.878735) (xy 11.944169 -255.825014)
			(xy 11.935953 -255.769489) (xy 11.93546 -255.741424) (xy 1.27 -255.741424) (xy 1.27 -258.0132) (xy 3.932682 -258.0132)
			(xy 3.933169 -257.984282) (xy 3.9419 -257.927107) (xy 3.959162 -257.871907) (xy 3.98456 -257.819944)
			(xy 4.01751 -257.772412) (xy 4.057259 -257.730398) (xy 4.079748 -257.71221) (xy 4.088509 -257.704648)
			(xy 4.098691 -257.683889) (xy 4.099306 -257.672332) (xy 4.099306 -257.592068) (xy 4.098694 -257.580506)
			(xy 4.088529 -257.559734) (xy 4.079748 -257.55219) (xy 4.057249 -257.534018) (xy 4.017517 -257.491993)
			(xy 3.984581 -257.444453) (xy 3.959196 -257.392489) (xy 3.941943 -257.337288) (xy 3.933216 -257.280117)
			(xy 3.932682 -257.2512) (xy 3.933178 -257.223949) (xy 3.940934 -257.170002) (xy 3.956289 -257.117708)
			(xy 3.978929 -257.068132) (xy 4.008394 -257.022282) (xy 4.044085 -256.981092) (xy 4.085274 -256.9454)
			(xy 4.131123 -256.915934) (xy 4.180699 -256.893292) (xy 4.232993 -256.877936) (xy 4.286939 -256.870178)
			(xy 4.31419 -256.869692) (xy 4.343108 -256.870183) (xy 4.400282 -256.878912) (xy 4.455483 -256.896173)
			(xy 4.507446 -256.92157) (xy 4.554979 -256.95452) (xy 4.596992 -256.994269) (xy 4.61518 -257.016758)
			(xy 4.622745 -257.025516) (xy 4.643502 -257.035699) (xy 4.655058 -257.036316) (xy 4.735322 -257.036316)
			(xy 4.746883 -257.035695) (xy 4.767654 -257.025536) (xy 4.7752 -257.016758) (xy 4.791953 -256.995975)
			(xy 4.830307 -256.958845) (xy 4.873461 -256.927423) (xy 4.920575 -256.902324) (xy 4.970727 -256.884038)
			(xy 5.022938 -256.872921) (xy 5.07619 -256.869191) (xy 5.129442 -256.872921) (xy 5.181653 -256.884038)
			(xy 5.231805 -256.902324) (xy 5.278919 -256.927423) (xy 5.322073 -256.958845) (xy 5.360427 -256.995975)
			(xy 5.37718 -257.016758) (xy 5.384745 -257.025516) (xy 5.405502 -257.035699) (xy 5.417058 -257.036316)
			(xy 5.497322 -257.036316) (xy 5.508883 -257.035695) (xy 5.529654 -257.025536) (xy 5.5372 -257.016758)
			(xy 5.553953 -256.995975) (xy 5.592307 -256.958845) (xy 5.635461 -256.927423) (xy 5.682575 -256.902324)
			(xy 5.732727 -256.884038) (xy 5.784938 -256.872921) (xy 5.83819 -256.869191) (xy 5.891442 -256.872921)
			(xy 5.943653 -256.884038) (xy 5.993805 -256.902324) (xy 6.040919 -256.927423) (xy 6.084073 -256.958845)
			(xy 6.122427 -256.995975) (xy 6.13918 -257.016758) (xy 6.146745 -257.025516) (xy 6.167502 -257.035699)
			(xy 6.179058 -257.036316) (xy 6.259322 -257.036316) (xy 6.270883 -257.035695) (xy 6.291654 -257.025536)
			(xy 6.2992 -257.016758) (xy 6.31738 -256.994266) (xy 6.359404 -256.954533) (xy 6.406941 -256.921596)
			(xy 6.458904 -256.89621) (xy 6.514103 -256.878955) (xy 6.571274 -256.870227) (xy 6.60019 -256.869692)
			(xy 6.627443 -256.870165) (xy 6.681393 -256.87792) (xy 6.733691 -256.893275) (xy 6.783271 -256.915916)
			(xy 6.829124 -256.945383) (xy 6.870317 -256.981076) (xy 6.906011 -257.022268) (xy 6.928751 -257.057652)
			(xy 11.811252 -257.057652) (xy 11.815323 -257.00203) (xy 11.827449 -256.947593) (xy 11.847372 -256.895502)
			(xy 11.874668 -256.846867) (xy 11.908754 -256.802724) (xy 11.948903 -256.764015) (xy 11.994261 -256.731564)
			(xy 12.043861 -256.706063) (xy 12.096645 -256.688056) (xy 12.151488 -256.677926) (xy 12.207222 -256.675889)
			(xy 12.262659 -256.681989) (xy 12.316616 -256.696095) (xy 12.367945 -256.717907) (xy 12.415551 -256.746961)
			(xy 12.458419 -256.782636) (xy 12.495636 -256.824173) (xy 12.526409 -256.870686) (xy 12.550081 -256.921183)
			(xy 12.566149 -256.97459) (xy 12.574269 -257.029766) (xy 12.574778 -257.057652) (xy 12.574269 -257.085538)
			(xy 12.566149 -257.140714) (xy 12.550081 -257.194121) (xy 12.526409 -257.244618) (xy 12.495636 -257.291131)
			(xy 12.458419 -257.332668) (xy 12.415551 -257.368343) (xy 12.367945 -257.397397) (xy 12.316616 -257.419209)
			(xy 12.262659 -257.433315) (xy 12.207222 -257.439415) (xy 12.151488 -257.437378) (xy 12.096645 -257.427248)
			(xy 12.043861 -257.409241) (xy 11.994261 -257.38374) (xy 11.948903 -257.351289) (xy 11.908754 -257.31258)
			(xy 11.874668 -257.268437) (xy 11.847372 -257.219802) (xy 11.827449 -257.167711) (xy 11.815323 -257.113274)
			(xy 11.811252 -257.057652) (xy 6.928751 -257.057652) (xy 6.935479 -257.06812) (xy 6.958121 -257.1177)
			(xy 6.973478 -257.169997) (xy 6.981235 -257.223947) (xy 6.981698 -257.2512) (xy 6.98118 -257.280117)
			(xy 6.972451 -257.337288) (xy 6.955193 -257.392487) (xy 6.929801 -257.444449) (xy 6.896858 -257.491983)
			(xy 6.857117 -257.534) (xy 6.834632 -257.55219) (xy 6.825868 -257.559749) (xy 6.815688 -257.58051)
			(xy 6.815074 -257.592068) (xy 6.815074 -257.672332) (xy 6.815658 -257.683899) (xy 6.82584 -257.704672)
			(xy 6.834632 -257.71221) (xy 6.857127 -257.730387) (xy 6.89686 -257.772411) (xy 6.929797 -257.819949)
			(xy 6.955183 -257.871913) (xy 6.972437 -257.927112) (xy 6.981164 -257.984283) (xy 6.981698 -258.0132)
			(xy 6.981245 -258.040453) (xy 6.973487 -258.094405) (xy 6.958131 -258.146704) (xy 6.935488 -258.196285)
			(xy 6.906019 -258.242138) (xy 6.870324 -258.283331) (xy 6.82913 -258.319025) (xy 6.783276 -258.348492)
			(xy 6.733694 -258.371134) (xy 6.681395 -258.38649) (xy 6.627443 -258.394245) (xy 6.60019 -258.394708)
			(xy 6.571274 -258.39416) (xy 6.514102 -258.385442) (xy 6.458903 -258.368192) (xy 6.40694 -258.342806)
			(xy 6.359406 -258.309866) (xy 6.31739 -258.270127) (xy 6.2992 -258.247642) (xy 6.291644 -258.238875)
			(xy 6.27088 -258.228697) (xy 6.259322 -258.228084) (xy 6.179058 -258.228084) (xy 6.167495 -258.228693)
			(xy 6.146724 -258.238861) (xy 6.13918 -258.247642) (xy 6.122427 -258.268425) (xy 6.084073 -258.305555)
			(xy 6.040919 -258.336977) (xy 5.993805 -258.362076) (xy 5.943653 -258.380362) (xy 5.891442 -258.391479)
			(xy 5.83819 -258.395209) (xy 5.784938 -258.391479) (xy 5.732727 -258.380362) (xy 5.682575 -258.362076)
			(xy 5.635461 -258.336977) (xy 5.592307 -258.305555) (xy 5.553953 -258.268425) (xy 5.5372 -258.247642)
			(xy 5.529644 -258.238875) (xy 5.50888 -258.228697) (xy 5.497322 -258.228084) (xy 5.417058 -258.228084)
			(xy 5.405495 -258.228693) (xy 5.384724 -258.238861) (xy 5.37718 -258.247642) (xy 5.360427 -258.268425)
			(xy 5.322073 -258.305555) (xy 5.278919 -258.336977) (xy 5.231805 -258.362076) (xy 5.181653 -258.380362)
			(xy 5.129442 -258.391479) (xy 5.07619 -258.395209) (xy 5.022938 -258.391479) (xy 4.970727 -258.380362)
			(xy 4.920575 -258.362076) (xy 4.873461 -258.336977) (xy 4.830307 -258.305555) (xy 4.791953 -258.268425)
			(xy 4.7752 -258.247642) (xy 4.767644 -258.238875) (xy 4.74688 -258.228697) (xy 4.735322 -258.228084)
			(xy 4.655058 -258.228084) (xy 4.643495 -258.228693) (xy 4.622724 -258.238861) (xy 4.61518 -258.247642)
			(xy 4.597011 -258.270144) (xy 4.554985 -258.309876) (xy 4.507445 -258.342812) (xy 4.45548 -258.368196)
			(xy 4.400279 -258.385449) (xy 4.343107 -258.394175) (xy 4.31419 -258.394708) (xy 4.286939 -258.394232)
			(xy 4.23299 -258.386474) (xy 4.180696 -258.371117) (xy 4.131118 -258.348475) (xy 4.085268 -258.319008)
			(xy 4.044078 -258.283315) (xy 4.008386 -258.242124) (xy 3.97892 -258.196273) (xy 3.956279 -258.146695)
			(xy 3.940924 -258.0944) (xy 3.933168 -258.040452) (xy 3.932682 -258.0132) (xy 1.27 -258.0132) (xy 1.27 -259.842)
			(xy 10.285982 -259.842) (xy 10.290053 -259.786378) (xy 10.302179 -259.731941) (xy 10.322102 -259.67985)
			(xy 10.349398 -259.631215) (xy 10.383484 -259.587072) (xy 10.423633 -259.548363) (xy 10.468991 -259.515912)
			(xy 10.518591 -259.490411) (xy 10.571375 -259.472404) (xy 10.626218 -259.462274) (xy 10.681952 -259.460237)
			(xy 10.737389 -259.466337) (xy 10.791346 -259.480443) (xy 10.842675 -259.502255) (xy 10.890281 -259.531309)
			(xy 10.933149 -259.566984) (xy 10.970366 -259.608521) (xy 11.001139 -259.655034) (xy 11.024811 -259.705531)
			(xy 11.040879 -259.758938) (xy 11.048999 -259.814114) (xy 11.049508 -259.842) (xy 11.048999 -259.869886)
			(xy 11.040879 -259.925062) (xy 11.024811 -259.978469) (xy 11.001139 -260.028966) (xy 10.970366 -260.075479)
			(xy 10.933149 -260.117016) (xy 10.890281 -260.152691) (xy 10.842675 -260.181745) (xy 10.791346 -260.203557)
			(xy 10.737389 -260.217663) (xy 10.681952 -260.223763) (xy 10.626218 -260.221726) (xy 10.571375 -260.211596)
			(xy 10.518591 -260.193589) (xy 10.468991 -260.168088) (xy 10.423633 -260.135637) (xy 10.383484 -260.096928)
			(xy 10.349398 -260.052785) (xy 10.322102 -260.00415) (xy 10.302179 -259.952059) (xy 10.290053 -259.897622)
			(xy 10.285982 -259.842) (xy 1.27 -259.842) (xy 1.27 -260.927921) (xy 9.15795 -260.927921) (xy 9.15795 -260.873419)
			(xy 9.165706 -260.819471) (xy 9.181061 -260.767177) (xy 9.203702 -260.7176) (xy 9.233168 -260.67175)
			(xy 9.26886 -260.63056) (xy 9.31005 -260.594868) (xy 9.3559 -260.565402) (xy 9.405477 -260.542761)
			(xy 9.457771 -260.527406) (xy 9.511719 -260.51965) (xy 9.53897 -260.519164) (xy 9.567887 -260.519679)
			(xy 9.62506 -260.528406) (xy 9.68026 -260.545663) (xy 9.732222 -260.571055) (xy 9.779756 -260.604)
			(xy 9.821771 -260.643743) (xy 9.83996 -260.66623) (xy 9.847538 -260.674974) (xy 9.868285 -260.685166)
			(xy 9.879838 -260.685788) (xy 9.960102 -260.685788) (xy 9.971671 -260.685223) (xy 9.992442 -260.675025)
			(xy 9.99998 -260.66623) (xy 10.01819 -260.643762) (xy 10.060205 -260.604025) (xy 10.107736 -260.571083)
			(xy 10.159693 -260.545692) (xy 10.214888 -260.528432) (xy 10.272055 -260.5197) (xy 10.30097 -260.519164)
			(xy 10.328221 -260.519646) (xy 10.382169 -260.527402) (xy 10.434464 -260.542758) (xy 10.484042 -260.565399)
			(xy 10.529893 -260.594865) (xy 10.571083 -260.630557) (xy 10.606775 -260.671747) (xy 10.636241 -260.717598)
			(xy 10.658882 -260.767176) (xy 10.674238 -260.819471) (xy 10.681994 -260.873419) (xy 10.681994 -260.927921)
			(xy 10.674238 -260.981869) (xy 10.658882 -261.034164) (xy 10.640736 -261.0739) (xy 10.819382 -261.0739)
			(xy 10.823453 -261.018278) (xy 10.835579 -260.963841) (xy 10.855502 -260.91175) (xy 10.882798 -260.863115)
			(xy 10.916884 -260.818972) (xy 10.957033 -260.780263) (xy 11.002391 -260.747812) (xy 11.051991 -260.722311)
			(xy 11.104775 -260.704304) (xy 11.159618 -260.694174) (xy 11.215352 -260.692137) (xy 11.270789 -260.698237)
			(xy 11.324746 -260.712343) (xy 11.376075 -260.734155) (xy 11.423681 -260.763209) (xy 11.466549 -260.798884)
			(xy 11.503766 -260.840421) (xy 11.534539 -260.886934) (xy 11.558211 -260.937431) (xy 11.574279 -260.990838)
			(xy 11.582399 -261.046014) (xy 11.582908 -261.0739) (xy 11.582399 -261.101786) (xy 11.574279 -261.156962)
			(xy 11.558211 -261.210369) (xy 11.534539 -261.260866) (xy 11.503766 -261.307379) (xy 11.466549 -261.348916)
			(xy 11.423681 -261.384591) (xy 11.376075 -261.413645) (xy 11.324746 -261.435457) (xy 11.270789 -261.449563)
			(xy 11.215352 -261.455663) (xy 11.159618 -261.453626) (xy 11.104775 -261.443496) (xy 11.051991 -261.425489)
			(xy 11.002391 -261.399988) (xy 10.957033 -261.367537) (xy 10.916884 -261.328828) (xy 10.882798 -261.284685)
			(xy 10.855502 -261.23605) (xy 10.835579 -261.183959) (xy 10.823453 -261.129522) (xy 10.819382 -261.0739)
			(xy 10.640736 -261.0739) (xy 10.636241 -261.083742) (xy 10.606775 -261.129593) (xy 10.571083 -261.170783)
			(xy 10.529893 -261.206475) (xy 10.484042 -261.235941) (xy 10.434464 -261.258582) (xy 10.382169 -261.273938)
			(xy 10.328221 -261.281694) (xy 10.30097 -261.28218) (xy 10.272055 -261.281619) (xy 10.214885 -261.2729)
			(xy 10.159687 -261.255651) (xy 10.107725 -261.230267) (xy 10.06019 -261.197331) (xy 10.018171 -261.157597)
			(xy 9.99998 -261.135114) (xy 9.99242 -261.12635) (xy 9.97166 -261.116167) (xy 9.960102 -261.115556)
			(xy 9.879838 -261.115556) (xy 9.86827 -261.116129) (xy 9.847498 -261.12632) (xy 9.83996 -261.135114)
			(xy 9.821795 -261.15762) (xy 9.77977 -261.197353) (xy 9.732229 -261.230289) (xy 9.680263 -261.255673)
			(xy 9.625061 -261.272925) (xy 9.567887 -261.281648) (xy 9.53897 -261.28218) (xy 9.511719 -261.28169)
			(xy 9.457771 -261.273934) (xy 9.405477 -261.258579) (xy 9.3559 -261.235938) (xy 9.31005 -261.206472)
			(xy 9.26886 -261.17078) (xy 9.233168 -261.12959) (xy 9.203702 -261.08374) (xy 9.181061 -261.034163)
			(xy 9.165706 -260.981869) (xy 9.15795 -260.927921) (xy 1.27 -260.927921) (xy 1.27 -261.342451) (xy 3.933168 -261.342451)
			(xy 3.933168 -261.287949) (xy 3.940924 -261.234001) (xy 3.956279 -261.181706) (xy 3.978921 -261.132129)
			(xy 4.008387 -261.086279) (xy 4.044078 -261.045088) (xy 4.085269 -261.009397) (xy 4.131119 -260.979931)
			(xy 4.180696 -260.957289) (xy 4.232991 -260.941934) (xy 4.286939 -260.934178) (xy 4.31419 -260.933692)
			(xy 4.343108 -260.934183) (xy 4.400282 -260.942912) (xy 4.455483 -260.960173) (xy 4.507446 -260.98557)
			(xy 4.554979 -261.01852) (xy 4.596992 -261.058269) (xy 4.61518 -261.080758) (xy 4.622745 -261.089516)
			(xy 4.643502 -261.099699) (xy 4.655058 -261.100316) (xy 4.735322 -261.100316) (xy 4.746883 -261.099695)
			(xy 4.767654 -261.089536) (xy 4.7752 -261.080758) (xy 4.791953 -261.059975) (xy 4.830307 -261.022845)
			(xy 4.873461 -260.991423) (xy 4.920575 -260.966324) (xy 4.970727 -260.948038) (xy 5.022938 -260.936921)
			(xy 5.07619 -260.933191) (xy 5.129442 -260.936921) (xy 5.181653 -260.948038) (xy 5.231805 -260.966324)
			(xy 5.278919 -260.991423) (xy 5.322073 -261.022845) (xy 5.360427 -261.059975) (xy 5.37718 -261.080758)
			(xy 5.384745 -261.089516) (xy 5.405502 -261.099699) (xy 5.417058 -261.100316) (xy 5.497322 -261.100316)
			(xy 5.508883 -261.099695) (xy 5.529654 -261.089536) (xy 5.5372 -261.080758) (xy 5.553953 -261.059975)
			(xy 5.592307 -261.022845) (xy 5.635461 -260.991423) (xy 5.682575 -260.966324) (xy 5.732727 -260.948038)
			(xy 5.784938 -260.936921) (xy 5.83819 -260.933191) (xy 5.891442 -260.936921) (xy 5.943653 -260.948038)
			(xy 5.993805 -260.966324) (xy 6.040919 -260.991423) (xy 6.084073 -261.022845) (xy 6.122427 -261.059975)
			(xy 6.13918 -261.080758) (xy 6.146745 -261.089516) (xy 6.167502 -261.099699) (xy 6.179058 -261.100316)
			(xy 6.259322 -261.100316) (xy 6.270883 -261.099695) (xy 6.291654 -261.089536) (xy 6.2992 -261.080758)
			(xy 6.31738 -261.058266) (xy 6.359404 -261.018533) (xy 6.406941 -260.985596) (xy 6.458904 -260.96021)
			(xy 6.514103 -260.942955) (xy 6.571274 -260.934227) (xy 6.60019 -260.933692) (xy 6.627443 -260.934155)
			(xy 6.681395 -260.94191) (xy 6.733694 -260.957266) (xy 6.783276 -260.979908) (xy 6.82913 -261.009375)
			(xy 6.870324 -261.045069) (xy 6.906019 -261.086262) (xy 6.935488 -261.132115) (xy 6.958131 -261.181696)
			(xy 6.973487 -261.233995) (xy 6.981245 -261.287947) (xy 6.981245 -261.342453) (xy 6.973487 -261.396405)
			(xy 6.958131 -261.448704) (xy 6.935488 -261.498285) (xy 6.906019 -261.544138) (xy 6.870324 -261.585331)
			(xy 6.82913 -261.621025) (xy 6.783276 -261.650492) (xy 6.733694 -261.673134) (xy 6.681395 -261.68849)
			(xy 6.627443 -261.696245) (xy 6.60019 -261.696708) (xy 6.571274 -261.69616) (xy 6.514102 -261.687442)
			(xy 6.458903 -261.670192) (xy 6.40694 -261.644806) (xy 6.359406 -261.611866) (xy 6.31739 -261.572127)
			(xy 6.2992 -261.549642) (xy 6.291644 -261.540875) (xy 6.27088 -261.530697) (xy 6.259322 -261.530084)
			(xy 6.179058 -261.530084) (xy 6.167495 -261.530693) (xy 6.146724 -261.540861) (xy 6.13918 -261.549642)
			(xy 6.122427 -261.570425) (xy 6.084073 -261.607555) (xy 6.040919 -261.638977) (xy 5.993805 -261.664076)
			(xy 5.943653 -261.682362) (xy 5.891442 -261.693479) (xy 5.83819 -261.697209) (xy 5.784938 -261.693479)
			(xy 5.732727 -261.682362) (xy 5.682575 -261.664076) (xy 5.635461 -261.638977) (xy 5.592307 -261.607555)
			(xy 5.553953 -261.570425) (xy 5.5372 -261.549642) (xy 5.529644 -261.540875) (xy 5.50888 -261.530697)
			(xy 5.497322 -261.530084) (xy 5.417058 -261.530084) (xy 5.405495 -261.530693) (xy 5.384724 -261.540861)
			(xy 5.37718 -261.549642) (xy 5.360427 -261.570425) (xy 5.322073 -261.607555) (xy 5.278919 -261.638977)
			(xy 5.231805 -261.664076) (xy 5.181653 -261.682362) (xy 5.129442 -261.693479) (xy 5.07619 -261.697209)
			(xy 5.022938 -261.693479) (xy 4.970727 -261.682362) (xy 4.920575 -261.664076) (xy 4.873461 -261.638977)
			(xy 4.830307 -261.607555) (xy 4.791953 -261.570425) (xy 4.7752 -261.549642) (xy 4.767644 -261.540875)
			(xy 4.74688 -261.530697) (xy 4.735322 -261.530084) (xy 4.655058 -261.530084) (xy 4.643495 -261.530693)
			(xy 4.622724 -261.540861) (xy 4.61518 -261.549642) (xy 4.597011 -261.572144) (xy 4.554985 -261.611876)
			(xy 4.507445 -261.644812) (xy 4.45548 -261.670196) (xy 4.400279 -261.687449) (xy 4.343107 -261.696175)
			(xy 4.31419 -261.696708) (xy 4.286939 -261.696222) (xy 4.232991 -261.688466) (xy 4.180696 -261.673111)
			(xy 4.131119 -261.650469) (xy 4.085269 -261.621003) (xy 4.044078 -261.585312) (xy 4.008387 -261.544121)
			(xy 3.978921 -261.498271) (xy 3.956279 -261.448694) (xy 3.940924 -261.396399) (xy 3.933168 -261.342451)
			(xy 1.27 -261.342451) (xy 1.27 -267.146024) (xy 2.53746 -267.146024) (xy 2.537886 -267.107736) (xy 2.54451 -267.031445)
			(xy 2.55766 -266.956006) (xy 2.577239 -266.881973) (xy 2.589784 -266.845796) (xy 2.592415 -266.837355)
			(xy 2.592422 -266.81969) (xy 2.589784 -266.811252) (xy 2.577216 -266.775081) (xy 2.557623 -266.70105)
			(xy 2.544475 -266.625608) (xy 2.537869 -266.549314) (xy 2.53746 -266.511024) (xy 2.537865 -266.471454)
			(xy 2.544876 -266.392626) (xy 2.558863 -266.314732) (xy 2.579715 -266.238389) (xy 2.593086 -266.201144)
			(xy 2.595945 -266.192482) (xy 2.595933 -266.174251) (xy 2.593086 -266.165584) (xy 2.579718 -266.128339)
			(xy 2.558871 -266.051995) (xy 2.544889 -265.974101) (xy 2.537881 -265.895273) (xy 2.53746 -265.855704)
			(xy 2.537926 -265.814601) (xy 2.545511 -265.732746) (xy 2.560616 -265.651939) (xy 2.583112 -265.572871)
			(xy 2.612808 -265.496216) (xy 2.64945 -265.422628) (xy 2.692726 -265.352735) (xy 2.742266 -265.287133)
			(xy 2.797647 -265.226382) (xy 2.858398 -265.171) (xy 2.924 -265.121459) (xy 2.993893 -265.078183)
			(xy 3.067481 -265.04154) (xy 3.144135 -265.011844) (xy 3.223203 -264.989347) (xy 3.30401 -264.974241)
			(xy 3.385865 -264.966656) (xy 3.426968 -264.966196) (xy 3.462142 -264.966527) (xy 3.532271 -264.972075)
			(xy 3.601741 -264.983153) (xy 3.63601 -264.991088) (xy 3.649218 -264.99439) (xy 3.674618 -264.987024)
			(xy 3.754882 -264.90549) (xy 3.761486 -264.879836) (xy 3.758184 -264.866882) (xy 3.749032 -264.830211)
			(xy 3.736256 -264.755711) (xy 3.72986 -264.680394) (xy 3.729482 -264.6426) (xy 3.730066 -264.596204)
			(xy 3.739711 -264.503916) (xy 3.758906 -264.413132) (xy 3.787444 -264.324839) (xy 3.805682 -264.282174)
			(xy 3.809587 -264.272252) (xy 3.809587 -264.250948) (xy 3.805682 -264.241026) (xy 3.787437 -264.198364)
			(xy 3.758893 -264.110072) (xy 3.7397 -264.019286) (xy 3.730067 -263.926996) (xy 3.729482 -263.8806)
			(xy 3.729967 -263.839498) (xy 3.737551 -263.757644) (xy 3.752656 -263.676839) (xy 3.775152 -263.597773)
			(xy 3.804848 -263.52112) (xy 3.841489 -263.447533) (xy 3.884764 -263.377641) (xy 3.934303 -263.312041)
			(xy 3.989683 -263.251291) (xy 4.050433 -263.195909) (xy 4.116033 -263.14637) (xy 4.185924 -263.103094)
			(xy 4.25951 -263.066452) (xy 4.336164 -263.036756) (xy 4.41523 -263.014259) (xy 4.496034 -262.999153)
			(xy 4.577888 -262.991567) (xy 4.61899 -262.991092) (xy 4.658763 -262.991534) (xy 4.737994 -262.998615)
			(xy 4.816274 -263.01275) (xy 4.892978 -263.033824) (xy 4.967492 -263.06167) (xy 5.003546 -263.078468)
			(xy 5.014047 -263.0828) (xy 5.036733 -263.0828) (xy 5.047234 -263.078468) (xy 5.083294 -263.061684)
			(xy 5.157812 -263.033856) (xy 5.234515 -263.012786) (xy 5.312791 -262.998642) (xy 5.392018 -262.991537)
			(xy 5.43179 -262.991092) (xy 5.470218 -262.991526) (xy 5.546787 -262.998168) (xy 5.622496 -263.011393)
			(xy 5.696782 -263.031104) (xy 5.769089 -263.057153) (xy 5.804154 -263.07288) (xy 5.81513 -263.077233)
			(xy 5.838702 -263.076428) (xy 5.849366 -263.071356) (xy 5.888227 -263.051102) (xy 5.969164 -263.017487)
			(xy 6.05301 -262.991984) (xy 6.138956 -262.97484) (xy 6.22617 -262.966221) (xy 6.26999 -262.965692)
			(xy 6.311093 -262.966162) (xy 6.392948 -262.973746) (xy 6.473755 -262.98885) (xy 6.552823 -263.011346)
			(xy 6.629478 -263.041042) (xy 6.703066 -263.077684) (xy 6.772959 -263.120959) (xy 6.838561 -263.170499)
			(xy 6.899313 -263.22588) (xy 6.954695 -263.286631) (xy 7.004235 -263.352232) (xy 7.047511 -263.422125)
			(xy 7.084154 -263.495713) (xy 7.11385 -263.572368) (xy 7.136347 -263.651435) (xy 7.151453 -263.732242)
			(xy 7.159038 -263.814097) (xy 7.159498 -263.8552) (xy 7.158916 -263.901596) (xy 7.149271 -263.993884)
			(xy 7.130075 -264.084668) (xy 7.101536 -264.172961) (xy 7.083298 -264.215626) (xy 7.079393 -264.225548)
			(xy 7.079393 -264.246852) (xy 7.083298 -264.256774) (xy 7.101542 -264.299436) (xy 7.130087 -264.387729)
			(xy 7.14928 -264.478514) (xy 7.1505 -264.4902) (xy 8.656578 -264.4902) (xy 8.660608 -264.405599)
			(xy 8.672661 -264.321764) (xy 8.692629 -264.239455) (xy 8.720331 -264.159416) (xy 8.755515 -264.082373)
			(xy 8.797864 -264.009023) (xy 8.846993 -263.940031) (xy 8.902458 -263.876021) (xy 8.963756 -263.817573)
			(xy 9.030332 -263.765217) (xy 9.101584 -263.719427) (xy 9.176865 -263.680616) (xy 9.255495 -263.649137)
			(xy 9.336762 -263.625276) (xy 9.419928 -263.609247) (xy 9.504242 -263.601196) (xy 9.54659 -263.600692)
			(xy 9.592985 -263.601278) (xy 9.685274 -263.610922) (xy 9.776058 -263.630117) (xy 9.864351 -263.658655)
			(xy 9.907016 -263.676892) (xy 9.916956 -263.680712) (xy 9.938224 -263.680712) (xy 9.948164 -263.676892)
			(xy 9.990828 -263.658651) (xy 10.079119 -263.630106) (xy 10.169904 -263.610912) (xy 10.262194 -263.601277)
			(xy 10.30859 -263.600692) (xy 10.350938 -263.601196) (xy 10.435252 -263.609247) (xy 10.518418 -263.625276)
			(xy 10.599685 -263.649137) (xy 10.678315 -263.680616) (xy 10.753596 -263.719427) (xy 10.824848 -263.765217)
			(xy 10.891424 -263.817573) (xy 10.952722 -263.876021) (xy 11.008187 -263.940031) (xy 11.057316 -264.009023)
			(xy 11.099665 -264.082373) (xy 11.134849 -264.159416) (xy 11.162551 -264.239455) (xy 11.182404 -264.32129)
			(xy 11.297666 -264.32129) (xy 11.298111 -264.283002) (xy 11.30473 -264.206712) (xy 11.317874 -264.131272)
			(xy 11.337448 -264.05724) (xy 11.34999 -264.021062) (xy 11.352637 -264.012625) (xy 11.352634 -263.994956)
			(xy 11.34999 -263.986518) (xy 11.33743 -263.950345) (xy 11.317834 -263.876315) (xy 11.304684 -263.800873)
			(xy 11.298076 -263.72458) (xy 11.297666 -263.68629) (xy 11.298157 -263.645188) (xy 11.305743 -263.563335)
			(xy 11.320848 -263.482531) (xy 11.343344 -263.403465) (xy 11.37304 -263.326813) (xy 11.409681 -263.253227)
			(xy 11.452956 -263.183336) (xy 11.502494 -263.117735) (xy 11.557874 -263.056986) (xy 11.618623 -263.001605)
			(xy 11.684222 -262.952065) (xy 11.754113 -262.908789) (xy 11.827698 -262.872147) (xy 11.90435 -262.84245)
			(xy 11.983415 -262.819952) (xy 12.064219 -262.804845) (xy 12.146072 -262.797258) (xy 12.187174 -262.796782)
			(xy 12.226744 -262.797187) (xy 12.305572 -262.804198) (xy 12.383466 -262.818185) (xy 12.459809 -262.839037)
			(xy 12.497054 -262.852408) (xy 12.505721 -262.855248) (xy 12.523947 -262.855248) (xy 12.532614 -262.852408)
			(xy 12.569854 -262.839024) (xy 12.6462 -262.818182) (xy 12.724095 -262.804204) (xy 12.802924 -262.7972)
			(xy 12.842494 -262.796782) (xy 12.880782 -262.797231) (xy 12.957072 -262.803848) (xy 13.032511 -262.816992)
			(xy 13.106544 -262.836564) (xy 13.142722 -262.849106) (xy 13.15116 -262.851748) (xy 13.168828 -262.851748)
			(xy 13.177266 -262.849106) (xy 13.213441 -262.836551) (xy 13.28747 -262.816954) (xy 13.362911 -262.803802)
			(xy 13.439205 -262.797193) (xy 13.477494 -262.796782) (xy 13.518596 -262.797272) (xy 13.60045 -262.804857)
			(xy 13.681254 -262.819961) (xy 13.760321 -262.842457) (xy 13.836974 -262.872152) (xy 13.91056 -262.908793)
			(xy 13.980452 -262.952067) (xy 14.046053 -263.001605) (xy 14.106803 -263.056986) (xy 14.162184 -263.117735)
			(xy 14.211724 -263.183335) (xy 14.255 -263.253226) (xy 14.291642 -263.326811) (xy 14.321338 -263.403464)
			(xy 14.343835 -263.48253) (xy 14.358941 -263.563334) (xy 14.366527 -263.645188) (xy 14.367002 -263.68629)
			(xy 14.366582 -263.724579) (xy 14.359957 -263.800869) (xy 14.346805 -263.876309) (xy 14.327224 -263.950341)
			(xy 14.314678 -263.986518) (xy 14.312042 -263.994957) (xy 14.312039 -264.012624) (xy 14.314678 -264.021062)
			(xy 14.32179 -264.041128) (xy 14.326616 -264.055606) (xy 14.350238 -264.074402) (xy 14.473174 -264.085578)
			(xy 14.499844 -264.071354) (xy 14.50721 -264.058146) (xy 14.528442 -264.020493) (xy 14.577197 -263.949103)
			(xy 14.632647 -263.882781) (xy 14.694269 -263.822149) (xy 14.761482 -263.767782) (xy 14.833652 -263.720191)
			(xy 14.910099 -263.679826) (xy 14.990101 -263.647067) (xy 15.072903 -263.622223) (xy 15.157724 -263.605529)
			(xy 15.243766 -263.597142) (xy 15.28699 -263.596628) (xy 15.326559 -263.597061) (xy 15.405387 -263.604065)
			(xy 15.483281 -263.618043) (xy 15.559625 -263.638887) (xy 15.59687 -263.652254) (xy 15.605537 -263.655094)
			(xy 15.623763 -263.655094) (xy 15.63243 -263.652254) (xy 15.669679 -263.638896) (xy 15.746021 -263.618047)
			(xy 15.823914 -263.604061) (xy 15.902741 -263.59705) (xy 15.94231 -263.596628) (xy 15.980598 -263.597069)
			(xy 16.056888 -263.603688) (xy 16.132328 -263.616834) (xy 16.20636 -263.636409) (xy 16.242538 -263.648952)
			(xy 16.250976 -263.651594) (xy 16.268644 -263.651594) (xy 16.277082 -263.648952) (xy 16.313255 -263.63639)
			(xy 16.387285 -263.616796) (xy 16.462727 -263.603646) (xy 16.53902 -263.597038) (xy 16.57731 -263.596628)
			(xy 16.618412 -263.597107) (xy 16.700266 -263.604692) (xy 16.781072 -263.619797) (xy 16.860138 -263.642293)
			(xy 16.936792 -263.671989) (xy 17.010379 -263.70863) (xy 17.080271 -263.751905) (xy 17.145871 -263.801445)
			(xy 17.206622 -263.856826) (xy 17.262003 -263.917575) (xy 17.311542 -263.983176) (xy 17.354818 -264.053068)
			(xy 17.39146 -264.126654) (xy 17.421156 -264.203308) (xy 17.443653 -264.282375) (xy 17.458758 -264.36318)
			(xy 17.466343 -264.445034) (xy 17.466818 -264.486136) (xy 17.466382 -264.524424) (xy 17.459761 -264.600714)
			(xy 17.446614 -264.676154) (xy 17.427038 -264.750186) (xy 17.414494 -264.786364) (xy 17.411835 -264.794798)
			(xy 17.411846 -264.81247) (xy 17.414494 -264.820908) (xy 17.427061 -264.857079) (xy 17.446655 -264.93111)
			(xy 17.459803 -265.006552) (xy 17.466409 -265.082846) (xy 17.466818 -265.121136) (xy 17.466368 -265.162239)
			(xy 17.45878 -265.244093) (xy 17.443672 -265.324899) (xy 17.421173 -265.403966) (xy 17.391474 -265.480619)
			(xy 17.35483 -265.554206) (xy 17.311553 -265.624097) (xy 17.262012 -265.689698) (xy 17.206629 -265.750448)
			(xy 17.145878 -265.805828) (xy 17.080276 -265.855368) (xy 17.010383 -265.898643) (xy 16.936795 -265.935285)
			(xy 16.860141 -265.964981) (xy 16.781073 -265.987478) (xy 16.700268 -266.002583) (xy 16.618413 -266.010169)
			(xy 16.57731 -266.010644) (xy 16.538378 -266.010212) (xy 16.460814 -266.003375) (xy 16.384146 -265.989778)
			(xy 16.308962 -265.969526) (xy 16.272256 -265.956542) (xy 16.263707 -265.953778) (xy 16.245753 -265.953778)
			(xy 16.237204 -265.956542) (xy 16.200499 -265.969525) (xy 16.125311 -265.989763) (xy 16.048643 -266.003357)
			(xy 15.971082 -266.010205) (xy 15.93215 -266.010644) (xy 15.893218 -266.0102) (xy 15.815655 -266.003366)
			(xy 15.738987 -265.989773) (xy 15.663802 -265.969524) (xy 15.627096 -265.956542) (xy 15.618547 -265.953778)
			(xy 15.600593 -265.953778) (xy 15.592044 -265.956542) (xy 15.555335 -265.969513) (xy 15.480149 -265.989754)
			(xy 15.403482 -266.003352) (xy 15.325921 -266.010203) (xy 15.28699 -266.010644) (xy 15.245887 -266.010188)
			(xy 15.164031 -266.002603) (xy 15.083224 -265.987497) (xy 15.004156 -265.965) (xy 14.9275 -265.935304)
			(xy 14.853912 -265.898661) (xy 14.784019 -265.855385) (xy 14.718417 -265.805844) (xy 14.657665 -265.750462)
			(xy 14.602283 -265.68971) (xy 14.552743 -265.624108) (xy 14.509467 -265.554214) (xy 14.472825 -265.480626)
			(xy 14.443128 -265.403971) (xy 14.420632 -265.324902) (xy 14.405527 -265.244095) (xy 14.397942 -265.162239)
			(xy 14.397482 -265.121136) (xy 14.39791 -265.082848) (xy 14.404533 -265.006557) (xy 14.417683 -264.931118)
			(xy 14.437261 -264.857086) (xy 14.449806 -264.820908) (xy 14.45243 -264.812466) (xy 14.452441 -264.794802)
			(xy 14.449806 -264.786364) (xy 14.442694 -264.766298) (xy 14.437868 -264.75182) (xy 14.414246 -264.733024)
			(xy 14.29131 -264.721848) (xy 14.26464 -264.736072) (xy 14.257274 -264.74928) (xy 14.236023 -264.786923)
			(xy 14.187273 -264.858314) (xy 14.131826 -264.92464) (xy 14.070207 -264.985273) (xy 14.002996 -265.039642)
			(xy 13.930828 -265.087234) (xy 13.854382 -265.127601) (xy 13.774382 -265.160361) (xy 13.69158 -265.185205)
			(xy 13.606759 -265.201898) (xy 13.520718 -265.210285) (xy 13.477494 -265.210798) (xy 13.438562 -265.210374)
			(xy 13.360998 -265.203534) (xy 13.28433 -265.189936) (xy 13.209145 -265.169681) (xy 13.17244 -265.156696)
			(xy 13.163891 -265.153932) (xy 13.145937 -265.153932) (xy 13.137388 -265.156696) (xy 13.100683 -265.169681)
			(xy 13.025496 -265.189919) (xy 12.948828 -265.203513) (xy 12.871266 -265.210359) (xy 12.832334 -265.210798)
			(xy 12.793402 -265.210362) (xy 12.715838 -265.203526) (xy 12.63917 -265.189931) (xy 12.563986 -265.16968)
			(xy 12.52728 -265.156696) (xy 12.518731 -265.153932) (xy 12.500777 -265.153932) (xy 12.492228 -265.156696)
			(xy 12.455519 -265.16967) (xy 12.380333 -265.189911) (xy 12.303667 -265.203508) (xy 12.226105 -265.210358)
			(xy 12.187174 -265.210798) (xy 12.146071 -265.210358) (xy 12.064215 -265.202771) (xy 11.983409 -265.187663)
			(xy 11.904341 -265.165164) (xy 11.827687 -265.135466) (xy 11.754099 -265.098822) (xy 11.684207 -265.055544)
			(xy 11.618606 -265.006002) (xy 11.557856 -264.950619) (xy 11.502475 -264.889866) (xy 11.452936 -264.824263)
			(xy 11.409661 -264.754369) (xy 11.373019 -264.68078) (xy 11.343324 -264.604125) (xy 11.320829 -264.525056)
			(xy 11.305724 -264.444249) (xy 11.29814 -264.362393) (xy 11.297666 -264.32129) (xy 11.182404 -264.32129)
			(xy 11.182519 -264.321764) (xy 11.194572 -264.405599) (xy 11.198603 -264.4902) (xy 11.194572 -264.574801)
			(xy 11.182519 -264.658636) (xy 11.162551 -264.740945) (xy 11.134849 -264.820984) (xy 11.099665 -264.898027)
			(xy 11.057316 -264.971377) (xy 11.008187 -265.040369) (xy 10.952722 -265.104379) (xy 10.891424 -265.162827)
			(xy 10.824848 -265.215183) (xy 10.753596 -265.260973) (xy 10.678315 -265.299784) (xy 10.599685 -265.331263)
			(xy 10.518418 -265.355124) (xy 10.435252 -265.371153) (xy 10.350938 -265.379204) (xy 10.30859 -265.379708)
			(xy 10.262194 -265.379129) (xy 10.169906 -265.369483) (xy 10.079122 -265.350286) (xy 9.990829 -265.321746)
			(xy 9.948164 -265.303508) (xy 9.938224 -265.299688) (xy 9.916956 -265.299688) (xy 9.907016 -265.303508)
			(xy 9.864355 -265.321756) (xy 9.776062 -265.350299) (xy 9.685277 -265.369491) (xy 9.592986 -265.379124)
			(xy 9.54659 -265.379708) (xy 9.504242 -265.379204) (xy 9.419928 -265.371153) (xy 9.336762 -265.355124)
			(xy 9.255495 -265.331263) (xy 9.176865 -265.299784) (xy 9.101584 -265.260973) (xy 9.030332 -265.215183)
			(xy 8.963756 -265.162827) (xy 8.902458 -265.104379) (xy 8.846993 -265.040369) (xy 8.797864 -264.971377)
			(xy 8.755515 -264.898027) (xy 8.720331 -264.820984) (xy 8.692629 -264.740945) (xy 8.672661 -264.658636)
			(xy 8.660608 -264.574801) (xy 8.656578 -264.4902) (xy 7.1505 -264.4902) (xy 7.158913 -264.570804)
			(xy 7.159498 -264.6172) (xy 7.159048 -264.658303) (xy 7.151463 -264.74016) (xy 7.136357 -264.820967)
			(xy 7.11386 -264.900036) (xy 7.084163 -264.976691) (xy 7.04752 -265.05028) (xy 7.004244 -265.120173)
			(xy 6.954702 -265.185775) (xy 6.89932 -265.246527) (xy 6.838568 -265.301909) (xy 6.772965 -265.351449)
			(xy 6.703071 -265.394725) (xy 6.629482 -265.431367) (xy 6.552826 -265.461063) (xy 6.473757 -265.483559)
			(xy 6.39295 -265.498664) (xy 6.311093 -265.506248) (xy 6.26999 -265.506708) (xy 6.231562 -265.506281)
			(xy 6.154993 -265.499638) (xy 6.079283 -265.486411) (xy 6.004998 -265.466698) (xy 5.932691 -265.440648)
			(xy 5.897626 -265.42492) (xy 5.886654 -265.420554) (xy 5.863078 -265.421368) (xy 5.852414 -265.426444)
			(xy 5.813556 -265.446705) (xy 5.732619 -265.480319) (xy 5.648772 -265.50582) (xy 5.562825 -265.522962)
			(xy 5.47561 -265.53158) (xy 5.43179 -265.532108) (xy 5.392017 -265.531674) (xy 5.312786 -265.524591)
			(xy 5.234505 -265.510454) (xy 5.157801 -265.489378) (xy 5.083288 -265.461531) (xy 5.047234 -265.444732)
			(xy 5.036733 -265.4404) (xy 5.014047 -265.4404) (xy 5.003546 -265.444732) (xy 4.967489 -265.461524)
			(xy 4.892971 -265.48935) (xy 4.816267 -265.510418) (xy 4.737989 -265.524561) (xy 4.658762 -265.531664)
			(xy 4.61899 -265.532108) (xy 4.583816 -265.531765) (xy 4.513688 -265.526222) (xy 4.444217 -265.515148)
			(xy 4.409948 -265.507216) (xy 4.39674 -265.503914) (xy 4.37134 -265.51128) (xy 4.291076 -265.592814)
			(xy 4.284472 -265.618468) (xy 4.287774 -265.631422) (xy 4.296925 -265.668093) (xy 4.309702 -265.742593)
			(xy 4.316098 -265.81791) (xy 4.316476 -265.855704) (xy 4.316047 -265.895273) (xy 4.309042 -265.974101)
			(xy 4.295062 -266.051995) (xy 4.274218 -266.128339) (xy 4.26085 -266.165584) (xy 4.258027 -266.174256)
			(xy 4.258015 -266.192477) (xy 4.26085 -266.201144) (xy 4.274212 -266.238392) (xy 4.29506 -266.314734)
			(xy 4.309044 -266.392627) (xy 4.316054 -266.471455) (xy 4.316476 -266.511024) (xy 4.316039 -266.549312)
			(xy 4.309418 -266.625602) (xy 4.296272 -266.701042) (xy 4.276696 -266.775074) (xy 4.264152 -266.811252)
			(xy 4.2615 -266.819687) (xy 4.261508 -266.837358) (xy 4.264152 -266.845796) (xy 4.276718 -266.881967)
			(xy 4.296311 -266.955998) (xy 4.30946 -267.03144) (xy 4.316066 -267.107734) (xy 4.316476 -267.146024)
			(xy 4.315972 -267.188372) (xy 4.307921 -267.272686) (xy 4.291892 -267.355852) (xy 4.268031 -267.437119)
			(xy 4.236552 -267.515749) (xy 4.197741 -267.59103) (xy 4.151951 -267.662282) (xy 4.099595 -267.728858)
			(xy 4.041147 -267.790156) (xy 3.977137 -267.845621) (xy 3.908145 -267.89475) (xy 3.834795 -267.937099)
			(xy 3.757752 -267.972283) (xy 3.677713 -267.999985) (xy 3.595404 -268.019953) (xy 3.511569 -268.032006)
			(xy 3.426968 -268.036037) (xy 3.342367 -268.032006) (xy 3.258532 -268.019953) (xy 3.176223 -267.999985)
			(xy 3.096184 -267.972283) (xy 3.019141 -267.937099) (xy 2.945791 -267.89475) (xy 2.876799 -267.845621)
			(xy 2.812789 -267.790156) (xy 2.754341 -267.728858) (xy 2.701985 -267.662282) (xy 2.656195 -267.59103)
			(xy 2.617384 -267.515749) (xy 2.585905 -267.437119) (xy 2.562044 -267.355852) (xy 2.546015 -267.272686)
			(xy 2.537964 -267.188372) (xy 2.53746 -267.146024) (xy 1.27 -267.146024) (xy 1.27 -269.958131) (xy 3.174978 -269.958131)
			(xy 3.174978 -269.903629) (xy 3.182734 -269.849681) (xy 3.198089 -269.797386) (xy 3.220731 -269.747809)
			(xy 3.250197 -269.701959) (xy 3.285888 -269.660768) (xy 3.327079 -269.625077) (xy 3.372929 -269.595611)
			(xy 3.422506 -269.572969) (xy 3.474801 -269.557614) (xy 3.528749 -269.549858) (xy 3.556 -269.549372)
			(xy 3.584918 -269.549863) (xy 3.642092 -269.558594) (xy 3.697293 -269.575855) (xy 3.749255 -269.601252)
			(xy 3.796788 -269.634202) (xy 3.838802 -269.673949) (xy 3.85699 -269.696438) (xy 3.864554 -269.705197)
			(xy 3.885311 -269.715381) (xy 3.896868 -269.715996) (xy 3.977132 -269.715996) (xy 3.988695 -269.715388)
			(xy 4.009467 -269.70522) (xy 4.01701 -269.696438) (xy 4.033763 -269.675655) (xy 4.072117 -269.638525)
			(xy 4.115271 -269.607103) (xy 4.162385 -269.582004) (xy 4.212537 -269.563718) (xy 4.264748 -269.552601)
			(xy 4.318 -269.548871) (xy 4.371252 -269.552601) (xy 4.423463 -269.563718) (xy 4.473615 -269.582004)
			(xy 4.520729 -269.607103) (xy 4.563883 -269.638525) (xy 4.602237 -269.675655) (xy 4.61899 -269.696438)
			(xy 4.626554 -269.705197) (xy 4.647311 -269.715381) (xy 4.658868 -269.715996) (xy 4.739132 -269.715996)
			(xy 4.750695 -269.715388) (xy 4.771467 -269.70522) (xy 4.77901 -269.696438) (xy 4.795763 -269.675655)
			(xy 4.834117 -269.638525) (xy 4.877271 -269.607103) (xy 4.924385 -269.582004) (xy 4.974537 -269.563718)
			(xy 5.026748 -269.552601) (xy 5.08 -269.548871) (xy 5.133252 -269.552601) (xy 5.185463 -269.563718)
			(xy 5.235615 -269.582004) (xy 5.282729 -269.607103) (xy 5.325883 -269.638525) (xy 5.364237 -269.675655)
			(xy 5.38099 -269.696438) (xy 5.388554 -269.705197) (xy 5.409311 -269.715381) (xy 5.420868 -269.715996)
			(xy 5.501132 -269.715996) (xy 5.512695 -269.715388) (xy 5.533467 -269.70522) (xy 5.54101 -269.696438)
			(xy 5.557763 -269.675655) (xy 5.596117 -269.638525) (xy 5.639271 -269.607103) (xy 5.686385 -269.582004)
			(xy 5.736537 -269.563718) (xy 5.788748 -269.552601) (xy 5.842 -269.548871) (xy 5.895252 -269.552601)
			(xy 5.947463 -269.563718) (xy 5.997615 -269.582004) (xy 6.044729 -269.607103) (xy 6.087883 -269.638525)
			(xy 6.126237 -269.675655) (xy 6.14299 -269.696438) (xy 6.150554 -269.705197) (xy 6.171311 -269.715381)
			(xy 6.182868 -269.715996) (xy 6.263132 -269.715996) (xy 6.274695 -269.715388) (xy 6.295467 -269.70522)
			(xy 6.30301 -269.696438) (xy 6.321205 -269.673958) (xy 6.363223 -269.634221) (xy 6.410756 -269.60128)
			(xy 6.462717 -269.575891) (xy 6.517915 -269.558634) (xy 6.575084 -269.549906) (xy 6.604 -269.549372)
			(xy 6.631251 -269.549858) (xy 6.685199 -269.557614) (xy 6.737494 -269.572969) (xy 6.787071 -269.595611)
			(xy 6.832921 -269.625077) (xy 6.874112 -269.660768) (xy 6.909803 -269.701959) (xy 6.939269 -269.747809)
			(xy 6.961911 -269.797386) (xy 6.977266 -269.849681) (xy 6.985022 -269.903629) (xy 6.985022 -269.958131)
			(xy 6.977266 -270.012079) (xy 6.961911 -270.064374) (xy 6.939269 -270.113951) (xy 6.909803 -270.159801)
			(xy 6.874112 -270.200992) (xy 6.832921 -270.236683) (xy 6.787071 -270.266149) (xy 6.737494 -270.288791)
			(xy 6.685199 -270.304146) (xy 6.631251 -270.311902) (xy 6.604 -270.312388) (xy 6.575083 -270.311874)
			(xy 6.517911 -270.303145) (xy 6.462712 -270.285886) (xy 6.41075 -270.260494) (xy 6.363217 -270.227549)
			(xy 6.3212 -270.187808) (xy 6.30301 -270.165322) (xy 6.295453 -270.156556) (xy 6.27469 -270.146378)
			(xy 6.263132 -270.145764) (xy 6.182868 -270.145764) (xy 6.171302 -270.146351) (xy 6.150529 -270.156532)
			(xy 6.14299 -270.165322) (xy 6.126237 -270.186105) (xy 6.087883 -270.223235) (xy 6.044729 -270.254657)
			(xy 5.997615 -270.279756) (xy 5.947463 -270.298042) (xy 5.895252 -270.309159) (xy 5.842 -270.312889)
			(xy 5.788748 -270.309159) (xy 5.736537 -270.298042) (xy 5.686385 -270.279756) (xy 5.639271 -270.254657)
			(xy 5.596117 -270.223235) (xy 5.557763 -270.186105) (xy 5.54101 -270.165322) (xy 5.533453 -270.156556)
			(xy 5.51269 -270.146378) (xy 5.501132 -270.145764) (xy 5.420868 -270.145764) (xy 5.409302 -270.146351)
			(xy 5.388529 -270.156532) (xy 5.38099 -270.165322) (xy 5.364237 -270.186105) (xy 5.325883 -270.223235)
			(xy 5.282729 -270.254657) (xy 5.235615 -270.279756) (xy 5.185463 -270.298042) (xy 5.133252 -270.309159)
			(xy 5.08 -270.312889) (xy 5.026748 -270.309159) (xy 4.974537 -270.298042) (xy 4.924385 -270.279756)
			(xy 4.877271 -270.254657) (xy 4.834117 -270.223235) (xy 4.795763 -270.186105) (xy 4.77901 -270.165322)
			(xy 4.771453 -270.156556) (xy 4.75069 -270.146378) (xy 4.739132 -270.145764) (xy 4.658868 -270.145764)
			(xy 4.647302 -270.146351) (xy 4.626529 -270.156532) (xy 4.61899 -270.165322) (xy 4.602237 -270.186105)
			(xy 4.563883 -270.223235) (xy 4.520729 -270.254657) (xy 4.473615 -270.279756) (xy 4.423463 -270.298042)
			(xy 4.371252 -270.309159) (xy 4.318 -270.312889) (xy 4.264748 -270.309159) (xy 4.212537 -270.298042)
			(xy 4.162385 -270.279756) (xy 4.115271 -270.254657) (xy 4.072117 -270.223235) (xy 4.033763 -270.186105)
			(xy 4.01701 -270.165322) (xy 4.009453 -270.156556) (xy 3.98869 -270.146378) (xy 3.977132 -270.145764)
			(xy 3.896868 -270.145764) (xy 3.885302 -270.146351) (xy 3.864529 -270.156532) (xy 3.85699 -270.165322)
			(xy 3.83881 -270.187815) (xy 3.796787 -270.227548) (xy 3.74925 -270.260486) (xy 3.697287 -270.285872)
			(xy 3.642087 -270.303127) (xy 3.584917 -270.311854) (xy 3.556 -270.312388) (xy 3.528749 -270.311902)
			(xy 3.474801 -270.304146) (xy 3.422506 -270.288791) (xy 3.372929 -270.266149) (xy 3.327079 -270.236683)
			(xy 3.285888 -270.200992) (xy 3.250197 -270.159801) (xy 3.220731 -270.113951) (xy 3.198089 -270.064374)
			(xy 3.182734 -270.012079) (xy 3.174978 -269.958131) (xy 1.27 -269.958131) (xy 1.27 -274.139406) (xy 13.258292 -274.139406)
			(xy 13.258802 -274.096817) (xy 13.266957 -274.01203) (xy 13.283183 -273.928412) (xy 13.307332 -273.846729)
			(xy 13.339183 -273.76773) (xy 13.358368 -273.729704) (xy 13.363556 -273.718521) (xy 13.36356 -273.693895)
			(xy 13.358368 -273.682714) (xy 13.339194 -273.644683) (xy 13.307353 -273.565682) (xy 13.283206 -273.484)
			(xy 13.266974 -273.400384) (xy 13.258806 -273.3156) (xy 13.258292 -273.273012) (xy 13.258808 -273.230469)
			(xy 13.266926 -273.145771) (xy 13.283099 -273.062235) (xy 13.307178 -272.980627) (xy 13.338944 -272.901693)
			(xy 13.378105 -272.826154) (xy 13.400786 -272.790158) (xy 13.405737 -272.781744) (xy 13.409469 -272.762599)
			(xy 13.405736 -272.743455) (xy 13.400786 -272.73504) (xy 13.378157 -272.699044) (xy 13.339064 -272.623534)
			(xy 13.307352 -272.544639) (xy 13.28331 -272.463078) (xy 13.267158 -272.379597) (xy 13.259044 -272.294955)
			(xy 13.258546 -272.25244) (xy 13.259033 -272.209851) (xy 13.267194 -272.125063) (xy 13.283426 -272.041445)
			(xy 13.30758 -271.959762) (xy 13.339434 -271.880764) (xy 13.358622 -271.842738) (xy 13.363784 -271.831546)
			(xy 13.363802 -271.806929) (xy 13.358622 -271.795748) (xy 13.339457 -271.757713) (xy 13.307615 -271.678712)
			(xy 13.283466 -271.597031) (xy 13.267232 -271.513417) (xy 13.259062 -271.428634) (xy 13.258546 -271.386046)
			(xy 13.25911 -271.344946) (xy 13.266691 -271.263095) (xy 13.281791 -271.182293) (xy 13.304282 -271.103229)
			(xy 13.333973 -271.026578) (xy 13.370609 -270.952993) (xy 13.413878 -270.883102) (xy 13.463412 -270.817502)
			(xy 13.518787 -270.756752) (xy 13.579531 -270.701371) (xy 13.645126 -270.65183) (xy 13.715012 -270.608554)
			(xy 13.788594 -270.57191) (xy 13.865242 -270.542211) (xy 13.944304 -270.519712) (xy 14.025104 -270.504603)
			(xy 14.106954 -270.497015) (xy 14.148054 -270.496538) (xy 14.191546 -270.497065) (xy 14.278119 -270.505524)
			(xy 14.363451 -270.522394) (xy 14.44673 -270.547515) (xy 14.487144 -270.563594) (xy 14.500098 -270.569182)
			(xy 14.527276 -270.565118) (xy 14.618716 -270.491458) (xy 14.628368 -270.465804) (xy 14.625828 -270.451834)
			(xy 14.619282 -270.412922) (xy 14.612285 -270.334319) (xy 14.611858 -270.294862) (xy 14.612353 -270.252273)
			(xy 14.620512 -270.167486) (xy 14.636742 -270.083867) (xy 14.660894 -270.002185) (xy 14.692747 -269.923186)
			(xy 14.711934 -269.88516) (xy 14.717148 -269.873986) (xy 14.717132 -269.849352) (xy 14.711934 -269.83817)
			(xy 14.692741 -269.800148) (xy 14.660904 -269.721144) (xy 14.636761 -269.63946) (xy 14.620534 -269.555842)
			(xy 14.61237 -269.471057) (xy 14.611858 -269.428468) (xy 14.612362 -269.38612) (xy 14.620413 -269.301806)
			(xy 14.636442 -269.21864) (xy 14.660303 -269.137373) (xy 14.691782 -269.058743) (xy 14.730593 -268.983462)
			(xy 14.776383 -268.91221) (xy 14.828739 -268.845634) (xy 14.887187 -268.784336) (xy 14.951197 -268.728871)
			(xy 15.020189 -268.679742) (xy 15.093539 -268.637393) (xy 15.170582 -268.602209) (xy 15.250621 -268.574507)
			(xy 15.33293 -268.554539) (xy 15.416765 -268.542486) (xy 15.501366 -268.538456) (xy 15.585967 -268.542486)
			(xy 15.669802 -268.554539) (xy 15.752111 -268.574507) (xy 15.83215 -268.602209) (xy 15.909193 -268.637393)
			(xy 15.982543 -268.679742) (xy 16.051535 -268.728871) (xy 16.115545 -268.784336) (xy 16.173993 -268.845634)
			(xy 16.226349 -268.91221) (xy 16.272139 -268.983462) (xy 16.31095 -269.058743) (xy 16.342429 -269.137373)
			(xy 16.36629 -269.21864) (xy 16.382319 -269.301806) (xy 16.39037 -269.38612) (xy 16.390874 -269.428468)
			(xy 16.390346 -269.471056) (xy 16.382194 -269.555842) (xy 16.365972 -269.63946) (xy 16.341827 -269.721143)
			(xy 16.309981 -269.800143) (xy 16.290798 -269.83817) (xy 16.28583 -269.849406) (xy 16.285815 -269.873933)
			(xy 16.290798 -269.88516) (xy 16.309968 -269.923193) (xy 16.341809 -270.002194) (xy 16.365956 -270.083876)
			(xy 16.382189 -270.167491) (xy 16.390359 -270.252274) (xy 16.390874 -270.294862) (xy 16.390412 -270.335966)
			(xy 16.39022 -270.338042) (xy 18.886932 -270.338042) (xy 18.887416 -270.310706) (xy 18.895228 -270.256594)
			(xy 18.910683 -270.204151) (xy 18.933465 -270.154451) (xy 18.963107 -270.108512) (xy 18.999003 -270.067274)
			(xy 19.040418 -270.031581) (xy 19.063208 -270.016478) (xy 19.075111 -270.008289) (xy 19.094158 -269.986584)
			(xy 19.106363 -269.960413) (xy 19.110748 -269.931871) (xy 19.106963 -269.903243) (xy 19.09531 -269.876822)
			(xy 19.076723 -269.854722) (xy 19.064986 -269.846298) (xy 19.042955 -269.831077) (xy 19.003013 -269.795412)
			(xy 18.968452 -269.754511) (xy 18.939952 -269.709177) (xy 18.918074 -269.660303) (xy 18.903247 -269.608848)
			(xy 18.895763 -269.555826) (xy 18.895314 -269.529052) (xy 18.8958 -269.501801) (xy 18.903556 -269.447853)
			(xy 18.918911 -269.395558) (xy 18.941553 -269.345981) (xy 18.971019 -269.300131) (xy 19.00671 -269.25894)
			(xy 19.047901 -269.223249) (xy 19.093751 -269.193783) (xy 19.143328 -269.171141) (xy 19.195623 -269.155786)
			(xy 19.249571 -269.14803) (xy 19.304073 -269.14803) (xy 19.358021 -269.155786) (xy 19.410316 -269.171141)
			(xy 19.459893 -269.193783) (xy 19.505743 -269.223249) (xy 19.546934 -269.25894) (xy 19.582625 -269.300131)
			(xy 19.612091 -269.345981) (xy 19.634733 -269.395558) (xy 19.650088 -269.447853) (xy 19.657844 -269.501801)
			(xy 19.65833 -269.529052) (xy 19.657813 -269.556387) (xy 19.650003 -269.610496) (xy 19.634552 -269.662937)
			(xy 19.611775 -269.712635) (xy 19.582138 -269.758575) (xy 19.546248 -269.799815) (xy 19.504841 -269.835511)
			(xy 19.482054 -269.850616) (xy 19.470151 -269.858809) (xy 19.451093 -269.880509) (xy 19.43888 -269.90668)
			(xy 19.434491 -269.935226) (xy 19.438278 -269.963857) (xy 19.449937 -269.99028) (xy 19.468534 -270.012376)
			(xy 19.480276 -270.020796) (xy 19.502296 -270.036033) (xy 19.54224 -270.071694) (xy 19.576803 -270.112592)
			(xy 19.605305 -270.157923) (xy 19.627185 -270.206795) (xy 19.642013 -270.258248) (xy 19.649498 -270.311269)
			(xy 19.649948 -270.338042) (xy 19.649462 -270.365293) (xy 19.641706 -270.419241) (xy 19.626351 -270.471536)
			(xy 19.603709 -270.521113) (xy 19.574243 -270.566963) (xy 19.538552 -270.608154) (xy 19.497361 -270.643845)
			(xy 19.451511 -270.673311) (xy 19.401934 -270.695953) (xy 19.349639 -270.711308) (xy 19.295691 -270.719064)
			(xy 19.241189 -270.719064) (xy 19.187241 -270.711308) (xy 19.134946 -270.695953) (xy 19.085369 -270.673311)
			(xy 19.039519 -270.643845) (xy 18.998328 -270.608154) (xy 18.962637 -270.566963) (xy 18.933171 -270.521113)
			(xy 18.910529 -270.471536) (xy 18.895174 -270.419241) (xy 18.887418 -270.365293) (xy 18.886932 -270.338042)
			(xy 16.39022 -270.338042) (xy 16.38283 -270.417822) (xy 16.367727 -270.49863) (xy 16.345232 -270.5777)
			(xy 16.315537 -270.654356) (xy 16.278896 -270.727945) (xy 16.23562 -270.79784) (xy 16.18608 -270.863443)
			(xy 16.130698 -270.924195) (xy 16.069946 -270.979578) (xy 16.004343 -271.029118) (xy 15.934449 -271.072394)
			(xy 15.86086 -271.109036) (xy 15.784203 -271.138731) (xy 15.705134 -271.161226) (xy 15.624326 -271.176329)
			(xy 15.54247 -271.183911) (xy 15.501366 -271.18437) (xy 15.457873 -271.183869) (xy 15.3713 -271.175403)
			(xy 15.285967 -271.158524) (xy 15.20269 -271.133396) (xy 15.162276 -271.117314) (xy 15.149322 -271.111726)
			(xy 15.122144 -271.11579) (xy 15.030704 -271.18945) (xy 15.021052 -271.215104) (xy 15.023592 -271.229074)
			(xy 15.030139 -271.267986) (xy 15.037135 -271.346589) (xy 15.037562 -271.386046) (xy 15.037068 -271.428635)
			(xy 15.028908 -271.513422) (xy 15.012678 -271.597041) (xy 14.988526 -271.678723) (xy 14.956673 -271.757722)
			(xy 14.937486 -271.795748) (xy 14.932467 -271.806966) (xy 14.932485 -271.83151) (xy 14.937486 -271.842738)
			(xy 14.956684 -271.880757) (xy 14.98852 -271.959762) (xy 15.012661 -272.041447) (xy 15.028888 -272.125065)
			(xy 15.037051 -272.209851) (xy 15.037562 -272.25244) (xy 15.037079 -272.294984) (xy 15.028956 -272.379684)
			(xy 15.012777 -272.463219) (xy 14.988692 -272.544828) (xy 14.95692 -272.623761) (xy 14.917752 -272.699299)
			(xy 14.895068 -272.735294) (xy 14.890221 -272.743747) (xy 14.88654 -272.76286) (xy 14.890192 -272.781979)
			(xy 14.895068 -272.790412) (xy 14.917726 -272.82639) (xy 14.956814 -272.901905) (xy 14.98852 -272.980804)
			(xy 15.012557 -273.062368) (xy 15.028703 -273.145852) (xy 15.036813 -273.230496) (xy 15.037308 -273.273012)
			(xy 15.036805 -273.315601) (xy 15.028649 -273.400388) (xy 15.012421 -273.484006) (xy 14.98827 -273.565689)
			(xy 14.956418 -273.644688) (xy 14.937232 -273.682714) (xy 14.932239 -273.69394) (xy 14.932243 -273.718475)
			(xy 14.937232 -273.729704) (xy 14.956413 -273.767732) (xy 14.988253 -273.846734) (xy 15.012398 -273.928417)
			(xy 15.028628 -274.012033) (xy 15.036795 -274.096818) (xy 15.036978 -274.111974) (xy 19.040348 -274.111974)
			(xy 19.040832 -274.086011) (xy 19.047873 -274.034566) (xy 19.061821 -273.984549) (xy 19.082419 -273.936884)
			(xy 19.109287 -273.89245) (xy 19.141929 -273.852068) (xy 19.179743 -273.816482) (xy 19.22203 -273.786349)
			(xy 19.244818 -273.7739) (xy 19.257264 -273.76755) (xy 19.271742 -273.743928) (xy 19.274028 -273.626834)
			(xy 19.260566 -273.602704) (xy 19.24812 -273.595846) (xy 19.223485 -273.581185) (xy 19.178554 -273.545581)
			(xy 19.139455 -273.503657) (xy 19.107066 -273.456356) (xy 19.082118 -273.404742) (xy 19.06517 -273.349977)
			(xy 19.056606 -273.293294) (xy 19.056096 -273.26463) (xy 19.056547 -273.237762) (xy 19.064089 -273.184558)
			(xy 19.079028 -273.132941) (xy 19.101067 -273.083933) (xy 19.129771 -273.038505) (xy 19.164569 -272.997559)
			(xy 19.184366 -272.979388) (xy 19.192748 -272.971768) (xy 19.201638 -272.951448) (xy 19.199606 -272.851372)
			(xy 19.189954 -272.83156) (xy 19.181064 -272.824448) (xy 19.15951 -272.806201) (xy 19.121434 -272.764497)
			(xy 19.089924 -272.717635) (xy 19.065666 -272.66664) (xy 19.049192 -272.612626) (xy 19.040861 -272.556773)
			(xy 19.040348 -272.528538) (xy 19.040803 -272.502574) (xy 19.047848 -272.451127) (xy 19.061801 -272.40111)
			(xy 19.082403 -272.353445) (xy 19.109275 -272.309011) (xy 19.141921 -272.268629) (xy 19.179738 -272.233044)
			(xy 19.222029 -272.202912) (xy 19.244818 -272.190464) (xy 19.257264 -272.184114) (xy 19.271742 -272.160492)
			(xy 19.274028 -272.043398) (xy 19.260566 -272.019268) (xy 19.24812 -272.01241) (xy 19.223513 -271.997704)
			(xy 19.178583 -271.962107) (xy 19.139482 -271.920191) (xy 19.107091 -271.872897) (xy 19.082137 -271.821291)
			(xy 19.065183 -271.766533) (xy 19.05661 -271.709855) (xy 19.056096 -271.681194) (xy 19.056582 -271.653943)
			(xy 19.064338 -271.599995) (xy 19.079693 -271.5477) (xy 19.102335 -271.498123) (xy 19.131801 -271.452273)
			(xy 19.167492 -271.411082) (xy 19.208683 -271.375391) (xy 19.254533 -271.345925) (xy 19.30411 -271.323283)
			(xy 19.356405 -271.307928) (xy 19.410353 -271.300172) (xy 19.464855 -271.300172) (xy 19.518803 -271.307928)
			(xy 19.571098 -271.323283) (xy 19.620675 -271.345925) (xy 19.666525 -271.375391) (xy 19.707716 -271.411082)
			(xy 19.743407 -271.452273) (xy 19.772873 -271.498123) (xy 19.795515 -271.5477) (xy 19.81087 -271.599995)
			(xy 19.818626 -271.653943) (xy 19.819112 -271.681194) (xy 19.818705 -271.707159) (xy 19.811654 -271.758609)
			(xy 19.797696 -271.808629) (xy 19.777087 -271.856296) (xy 19.750208 -271.900729) (xy 19.717556 -271.94111)
			(xy 19.679732 -271.976693) (xy 19.637434 -272.006822) (xy 19.614642 -272.019268) (xy 19.602196 -272.025618)
			(xy 19.587718 -272.04924) (xy 19.585432 -272.166334) (xy 19.598894 -272.190464) (xy 19.61134 -272.197322)
			(xy 19.635952 -272.212021) (xy 19.680884 -272.247617) (xy 19.719986 -272.289534) (xy 19.752378 -272.336829)
			(xy 19.777331 -272.388437) (xy 19.794282 -272.443196) (xy 19.802852 -272.499876) (xy 19.803364 -272.528538)
			(xy 19.802905 -272.555406) (xy 19.795366 -272.60861) (xy 19.78043 -272.660228) (xy 19.758392 -272.709236)
			(xy 19.729689 -272.754664) (xy 19.694891 -272.79561) (xy 19.675094 -272.81378) (xy 19.666712 -272.8214)
			(xy 19.657822 -272.84172) (xy 19.659854 -272.941796) (xy 19.669506 -272.961608) (xy 19.678396 -272.96872)
			(xy 19.699995 -272.986916) (xy 19.738065 -273.028632) (xy 19.769568 -273.075505) (xy 19.793818 -273.12651)
			(xy 19.810283 -273.180532) (xy 19.818604 -273.236392) (xy 19.819112 -273.26463) (xy 19.818652 -273.290594)
			(xy 19.81161 -273.342041) (xy 19.79766 -273.39206) (xy 19.777059 -273.439726) (xy 19.750188 -273.48416)
			(xy 19.717542 -273.524542) (xy 19.679724 -273.560127) (xy 19.637432 -273.590257) (xy 19.614642 -273.602704)
			(xy 19.602196 -273.609054) (xy 19.587718 -273.632676) (xy 19.585432 -273.74977) (xy 19.598894 -273.7739)
			(xy 19.61134 -273.780758) (xy 19.635967 -273.795432) (xy 19.6809 -273.831032) (xy 19.720002 -273.872953)
			(xy 19.752392 -273.920252) (xy 19.777342 -273.971864) (xy 19.79429 -274.026628) (xy 19.802855 -274.083311)
			(xy 19.803364 -274.111974) (xy 19.802878 -274.139225) (xy 19.795122 -274.193173) (xy 19.779767 -274.245468)
			(xy 19.757125 -274.295045) (xy 19.727659 -274.340895) (xy 19.691968 -274.382086) (xy 19.650777 -274.417777)
			(xy 19.604927 -274.447243) (xy 19.55535 -274.469885) (xy 19.503055 -274.48524) (xy 19.449107 -274.492996)
			(xy 19.394605 -274.492996) (xy 19.340657 -274.48524) (xy 19.288362 -274.469885) (xy 19.238785 -274.447243)
			(xy 19.192935 -274.417777) (xy 19.151744 -274.382086) (xy 19.116053 -274.340895) (xy 19.086587 -274.295045)
			(xy 19.063945 -274.245468) (xy 19.04859 -274.193173) (xy 19.040834 -274.139225) (xy 19.040348 -274.111974)
			(xy 15.036978 -274.111974) (xy 15.037308 -274.139406) (xy 15.036804 -274.181754) (xy 15.028753 -274.266068)
			(xy 15.012724 -274.349234) (xy 14.988863 -274.430501) (xy 14.957384 -274.509131) (xy 14.918573 -274.584412)
			(xy 14.872783 -274.655664) (xy 14.820427 -274.72224) (xy 14.761979 -274.783538) (xy 14.697969 -274.839003)
			(xy 14.628977 -274.888132) (xy 14.555627 -274.930481) (xy 14.478584 -274.965665) (xy 14.398545 -274.993367)
			(xy 14.316236 -275.013335) (xy 14.232401 -275.025388) (xy 14.1478 -275.029419) (xy 14.063199 -275.025388)
			(xy 13.979364 -275.013335) (xy 13.897055 -274.993367) (xy 13.817016 -274.965665) (xy 13.739973 -274.930481)
			(xy 13.666623 -274.888132) (xy 13.597631 -274.839003) (xy 13.533621 -274.783538) (xy 13.475173 -274.72224)
			(xy 13.422817 -274.655664) (xy 13.377027 -274.584412) (xy 13.338216 -274.509131) (xy 13.306737 -274.430501)
			(xy 13.282876 -274.349234) (xy 13.266847 -274.266068) (xy 13.258796 -274.181754) (xy 13.258292 -274.139406)
			(xy 1.27 -274.139406) (xy 1.27 -277.895304) (xy 13.241782 -277.895304) (xy 13.242292 -277.852715)
			(xy 13.250447 -277.767928) (xy 13.266674 -277.68431) (xy 13.290823 -277.602627) (xy 13.322673 -277.523628)
			(xy 13.341858 -277.485602) (xy 13.347048 -277.474419) (xy 13.347051 -277.449793) (xy 13.341858 -277.438612)
			(xy 13.322682 -277.400582) (xy 13.290842 -277.32158) (xy 13.266695 -277.239898) (xy 13.250464 -277.156282)
			(xy 13.242296 -277.071498) (xy 13.241782 -277.02891) (xy 13.242286 -276.986562) (xy 13.250337 -276.902248)
			(xy 13.266366 -276.819082) (xy 13.290227 -276.737815) (xy 13.321706 -276.659185) (xy 13.360517 -276.583904)
			(xy 13.406307 -276.512652) (xy 13.458663 -276.446076) (xy 13.517111 -276.384778) (xy 13.581121 -276.329313)
			(xy 13.650113 -276.280184) (xy 13.723463 -276.237835) (xy 13.800506 -276.202651) (xy 13.880545 -276.174949)
			(xy 13.962854 -276.154981) (xy 14.046689 -276.142928) (xy 14.13129 -276.138898) (xy 14.215891 -276.142928)
			(xy 14.299726 -276.154981) (xy 14.382035 -276.174949) (xy 14.462074 -276.202651) (xy 14.539117 -276.237835)
			(xy 14.612467 -276.280184) (xy 14.681459 -276.329313) (xy 14.745469 -276.384778) (xy 14.803917 -276.446076)
			(xy 14.856273 -276.512652) (xy 14.902063 -276.583904) (xy 14.940874 -276.659185) (xy 14.972353 -276.737815)
			(xy 14.996214 -276.819082) (xy 15.012243 -276.902248) (xy 15.020294 -276.986562) (xy 15.020798 -277.02891)
			(xy 15.020296 -277.071499) (xy 15.012139 -277.156286) (xy 14.995911 -277.239904) (xy 14.97176 -277.321587)
			(xy 14.939908 -277.400586) (xy 14.920722 -277.438612) (xy 14.915731 -277.449839) (xy 14.915734 -277.474373)
			(xy 14.920722 -277.485602) (xy 14.939901 -277.523631) (xy 14.971741 -277.602632) (xy 14.995887 -277.684315)
			(xy 15.012118 -277.767931) (xy 15.020285 -277.852716) (xy 15.020798 -277.895304) (xy 15.020294 -277.937652)
			(xy 15.012478 -278.01951) (xy 19.031966 -278.01951) (xy 19.032388 -277.993545) (xy 19.039438 -277.942096)
			(xy 19.053395 -277.892078) (xy 19.074002 -277.844412) (xy 19.100878 -277.799978) (xy 19.133529 -277.759597)
			(xy 19.17135 -277.724013) (xy 19.213645 -277.693883) (xy 19.236436 -277.681436) (xy 19.248267 -277.67473)
			(xy 19.268143 -277.656184) (xy 19.282419 -277.633049) (xy 19.290081 -277.606967) (xy 19.290585 -277.579787)
			(xy 19.283896 -277.553438) (xy 19.270489 -277.529789) (xy 19.251314 -277.510519) (xy 19.239738 -277.503382)
			(xy 19.215123 -277.488689) (xy 19.170192 -277.453091) (xy 19.13109 -277.411172) (xy 19.098699 -277.363877)
			(xy 19.073747 -277.312268) (xy 19.056796 -277.257508) (xy 19.048226 -277.200828) (xy 19.047714 -277.172166)
			(xy 19.0482 -277.144915) (xy 19.055956 -277.090967) (xy 19.071311 -277.038672) (xy 19.093953 -276.989095)
			(xy 19.123419 -276.943245) (xy 19.15911 -276.902054) (xy 19.200301 -276.866363) (xy 19.246151 -276.836897)
			(xy 19.295728 -276.814255) (xy 19.348023 -276.7989) (xy 19.401971 -276.791144) (xy 19.456473 -276.791144)
			(xy 19.510421 -276.7989) (xy 19.562716 -276.814255) (xy 19.612293 -276.836897) (xy 19.658143 -276.866363)
			(xy 19.699334 -276.902054) (xy 19.735025 -276.943245) (xy 19.764491 -276.989095) (xy 19.787133 -277.038672)
			(xy 19.802488 -277.090967) (xy 19.810244 -277.144915) (xy 19.81073 -277.172166) (xy 19.81029 -277.19813)
			(xy 19.803244 -277.249578) (xy 19.789289 -277.299597) (xy 19.768685 -277.347263) (xy 19.741811 -277.391696)
			(xy 19.709163 -277.432078) (xy 19.671344 -277.467662) (xy 19.62905 -277.497793) (xy 19.60626 -277.51024)
			(xy 19.594451 -277.516981) (xy 19.574577 -277.535521) (xy 19.560302 -277.558649) (xy 19.55264 -277.584725)
			(xy 19.552132 -277.611899) (xy 19.558816 -277.638243) (xy 19.572218 -277.661888) (xy 19.591386 -277.681157)
			(xy 19.602958 -277.688294) (xy 19.627561 -277.703006) (xy 19.672493 -277.738601) (xy 19.711595 -277.780516)
			(xy 19.743987 -277.827808) (xy 19.768941 -277.879414) (xy 19.785895 -277.934171) (xy 19.794468 -277.990849)
			(xy 19.794982 -278.01951) (xy 19.794496 -278.046761) (xy 19.78674 -278.100709) (xy 19.771385 -278.153004)
			(xy 19.748743 -278.202581) (xy 19.719277 -278.248431) (xy 19.683586 -278.289622) (xy 19.642395 -278.325313)
			(xy 19.596545 -278.354779) (xy 19.546968 -278.377421) (xy 19.494673 -278.392776) (xy 19.440725 -278.400532)
			(xy 19.386223 -278.400532) (xy 19.332275 -278.392776) (xy 19.27998 -278.377421) (xy 19.230403 -278.354779)
			(xy 19.184553 -278.325313) (xy 19.143362 -278.289622) (xy 19.107671 -278.248431) (xy 19.078205 -278.202581)
			(xy 19.055563 -278.153004) (xy 19.040208 -278.100709) (xy 19.032452 -278.046761) (xy 19.031966 -278.01951)
			(xy 15.012478 -278.01951) (xy 15.012243 -278.021966) (xy 14.996214 -278.105132) (xy 14.972353 -278.186399)
			(xy 14.940874 -278.265029) (xy 14.902063 -278.34031) (xy 14.856273 -278.411562) (xy 14.803917 -278.478138)
			(xy 14.745469 -278.539436) (xy 14.681459 -278.594901) (xy 14.612467 -278.64403) (xy 14.539117 -278.686379)
			(xy 14.462074 -278.721563) (xy 14.382035 -278.749265) (xy 14.299726 -278.769233) (xy 14.215891 -278.781286)
			(xy 14.13129 -278.785317) (xy 14.046689 -278.781286) (xy 13.962854 -278.769233) (xy 13.880545 -278.749265)
			(xy 13.800506 -278.721563) (xy 13.723463 -278.686379) (xy 13.650113 -278.64403) (xy 13.581121 -278.594901)
			(xy 13.517111 -278.539436) (xy 13.458663 -278.478138) (xy 13.406307 -278.411562) (xy 13.360517 -278.34031)
			(xy 13.321706 -278.265029) (xy 13.290227 -278.186399) (xy 13.266366 -278.105132) (xy 13.250337 -278.021966)
			(xy 13.242286 -277.937652) (xy 13.241782 -277.895304) (xy 1.27 -277.895304) (xy 1.27 -281.2542) (xy 3.936492 -281.2542)
			(xy 3.937075 -281.207804) (xy 3.94672 -281.115516) (xy 3.965916 -281.024732) (xy 3.994454 -280.936439)
			(xy 4.012692 -280.893774) (xy 4.016597 -280.883852) (xy 4.016597 -280.862548) (xy 4.012692 -280.852626)
			(xy 3.994447 -280.809964) (xy 3.965903 -280.721671) (xy 3.94671 -280.630886) (xy 3.937077 -280.538596)
			(xy 3.936492 -280.4922) (xy 3.936967 -280.451098) (xy 3.944552 -280.369243) (xy 3.959657 -280.288438)
			(xy 3.982153 -280.209371) (xy 4.011849 -280.132717) (xy 4.048491 -280.05913) (xy 4.091766 -279.989238)
			(xy 4.141306 -279.923637) (xy 4.196687 -279.862887) (xy 4.257437 -279.807506) (xy 4.323038 -279.757966)
			(xy 4.39293 -279.714691) (xy 4.466517 -279.678049) (xy 4.543171 -279.648353) (xy 4.622238 -279.625857)
			(xy 4.703043 -279.610752) (xy 4.784898 -279.603167) (xy 4.826 -279.602692) (xy 4.872396 -279.603275)
			(xy 4.964684 -279.61292) (xy 5.055468 -279.632116) (xy 5.143761 -279.660654) (xy 5.186426 -279.678892)
			(xy 5.196366 -279.682712) (xy 5.217634 -279.682712) (xy 5.227574 -279.678892) (xy 5.270236 -279.660647)
			(xy 5.358529 -279.632103) (xy 5.449314 -279.61291) (xy 5.541604 -279.603277) (xy 5.588 -279.602692)
			(xy 5.634396 -279.603275) (xy 5.726684 -279.61292) (xy 5.817468 -279.632116) (xy 5.905761 -279.660654)
			(xy 5.948426 -279.678892) (xy 5.958366 -279.682712) (xy 5.979634 -279.682712) (xy 5.989574 -279.678892)
			(xy 6.032236 -279.660647) (xy 6.120529 -279.632103) (xy 6.211314 -279.61291) (xy 6.303604 -279.603277)
			(xy 6.35 -279.602692) (xy 6.391102 -279.603167) (xy 6.472957 -279.610752) (xy 6.553762 -279.625857)
			(xy 6.632829 -279.648353) (xy 6.709483 -279.678049) (xy 6.78307 -279.714691) (xy 6.852962 -279.757966)
			(xy 6.918563 -279.807506) (xy 6.979313 -279.862887) (xy 7.034694 -279.923637) (xy 7.084234 -279.989238)
			(xy 7.127509 -280.05913) (xy 7.164151 -280.132717) (xy 7.193847 -280.209371) (xy 7.216343 -280.288438)
			(xy 7.231448 -280.369243) (xy 7.239033 -280.451098) (xy 7.239508 -280.4922) (xy 7.238925 -280.538596)
			(xy 7.22928 -280.630884) (xy 7.210084 -280.721668) (xy 7.181546 -280.809961) (xy 7.163308 -280.852626)
			(xy 7.159403 -280.862548) (xy 7.159403 -280.883852) (xy 7.163308 -280.893774) (xy 7.181553 -280.936436)
			(xy 7.210097 -281.024729) (xy 7.22929 -281.115514) (xy 7.238923 -281.207804) (xy 7.239508 -281.2542)
			(xy 7.239033 -281.295302) (xy 7.231448 -281.377157) (xy 7.216343 -281.457962) (xy 7.193847 -281.537029)
			(xy 7.164151 -281.613683) (xy 7.127509 -281.68727) (xy 7.084234 -281.757162) (xy 7.034694 -281.822763)
			(xy 6.979313 -281.883513) (xy 6.918563 -281.938894) (xy 6.852962 -281.988434) (xy 6.78307 -282.031709)
			(xy 6.709483 -282.068351) (xy 6.632829 -282.098047) (xy 6.553762 -282.120543) (xy 6.472957 -282.135648)
			(xy 6.391102 -282.143233) (xy 6.35 -282.143708) (xy 6.303604 -282.143125) (xy 6.211316 -282.13348)
			(xy 6.120532 -282.114284) (xy 6.032239 -282.085746) (xy 5.989574 -282.067508) (xy 5.979634 -282.063688)
			(xy 5.958366 -282.063688) (xy 5.948426 -282.067508) (xy 5.905764 -282.085753) (xy 5.817471 -282.114297)
			(xy 5.726686 -282.13349) (xy 5.634396 -282.143123) (xy 5.588 -282.143708) (xy 5.541604 -282.143125)
			(xy 5.449316 -282.13348) (xy 5.358532 -282.114284) (xy 5.270239 -282.085746) (xy 5.227574 -282.067508)
			(xy 5.217634 -282.063688) (xy 5.196366 -282.063688) (xy 5.186426 -282.067508) (xy 5.143764 -282.085753)
			(xy 5.055471 -282.114297) (xy 4.964686 -282.13349) (xy 4.872396 -282.143123) (xy 4.826 -282.143708)
			(xy 4.784898 -282.143233) (xy 4.703043 -282.135648) (xy 4.622238 -282.120543) (xy 4.543171 -282.098047)
			(xy 4.466517 -282.068351) (xy 4.39293 -282.031709) (xy 4.323038 -281.988434) (xy 4.257437 -281.938894)
			(xy 4.196687 -281.883513) (xy 4.141306 -281.822763) (xy 4.091766 -281.757162) (xy 4.048491 -281.68727)
			(xy 4.011849 -281.613683) (xy 3.982153 -281.537029) (xy 3.959657 -281.457962) (xy 3.944552 -281.377157)
			(xy 3.936967 -281.295302) (xy 3.936492 -281.2542) (xy 1.27 -281.2542) (xy 1.27 -289.349988) (xy 5.887196 -289.349988)
			(xy 5.887196 -289.270126) (xy 5.895024 -289.190649) (xy 5.910605 -289.112322) (xy 5.933787 -289.035899)
			(xy 5.96435 -288.962116) (xy 6.001996 -288.891684) (xy 6.046366 -288.825281) (xy 6.09703 -288.763547)
			(xy 6.153501 -288.707076) (xy 6.215235 -288.656413) (xy 6.281638 -288.612044) (xy 6.35207 -288.574398)
			(xy 6.425853 -288.543836) (xy 6.502276 -288.520653) (xy 6.580604 -288.505073) (xy 6.660081 -288.497246)
			(xy 6.700012 -288.496756) (xy 6.714566 -288.496811) (xy 6.743656 -288.497827) (xy 6.758178 -288.498788)
			(xy 6.774434 -288.500058) (xy 6.801866 -288.483548) (xy 6.853428 -288.3662) (xy 6.847078 -288.334958)
			(xy 6.835394 -288.323782) (xy 6.799432 -288.289067) (xy 6.732509 -288.214811) (xy 6.671691 -288.135476)
			(xy 6.617362 -288.051565) (xy 6.569865 -287.963606) (xy 6.5295 -287.872155) (xy 6.496521 -287.777788)
			(xy 6.471137 -287.681101) (xy 6.453507 -287.582705) (xy 6.443743 -287.483219) (xy 6.441906 -287.383272)
			(xy 6.448009 -287.283495) (xy 6.462012 -287.184517) (xy 6.483827 -287.086963) (xy 6.513317 -286.991449)
			(xy 6.550295 -286.898576) (xy 6.594528 -286.808931) (xy 6.645737 -286.723081) (xy 6.703599 -286.641566)
			(xy 6.767749 -286.564901) (xy 6.837781 -286.49357) (xy 6.913255 -286.428022) (xy 6.993693 -286.368672)
			(xy 7.078588 -286.315894) (xy 7.167405 -286.270022) (xy 7.259583 -286.231343) (xy 7.354539 -286.200104)
			(xy 7.451676 -286.1765) (xy 7.55038 -286.160681) (xy 7.650028 -286.152746) (xy 7.749992 -286.152746)
			(xy 7.84964 -286.160681) (xy 7.948344 -286.1765) (xy 8.045481 -286.200104) (xy 8.140437 -286.231343)
			(xy 8.232615 -286.270022) (xy 8.321432 -286.315894) (xy 8.406327 -286.368672) (xy 8.486765 -286.428022)
			(xy 8.562239 -286.49357) (xy 8.632271 -286.564901) (xy 8.696421 -286.641566) (xy 8.754283 -286.723081)
			(xy 8.805492 -286.808931) (xy 8.849725 -286.898576) (xy 8.886703 -286.991449) (xy 8.916193 -287.086963)
			(xy 8.938008 -287.184517) (xy 8.952011 -287.283495) (xy 8.958114 -287.383272) (xy 8.956277 -287.483219)
			(xy 8.946513 -287.582705) (xy 8.928883 -287.681101) (xy 8.903499 -287.777788) (xy 8.87052 -287.872155)
			(xy 8.830155 -287.963606) (xy 8.782658 -288.051565) (xy 8.728329 -288.135476) (xy 8.667511 -288.214811)
			(xy 8.600588 -288.289067) (xy 8.564626 -288.323782) (xy 8.552942 -288.334958) (xy 8.546592 -288.3662)
			(xy 8.598154 -288.483548) (xy 8.625586 -288.500058) (xy 8.641842 -288.498788) (xy 8.656364 -288.497822)
			(xy 8.685454 -288.496807) (xy 8.700008 -288.496756) (xy 8.739939 -288.49724) (xy 8.819417 -288.505067)
			(xy 8.897745 -288.520648) (xy 8.974169 -288.54383) (xy 9.047953 -288.574392) (xy 9.118385 -288.612039)
			(xy 9.184789 -288.656408) (xy 9.246523 -288.707072) (xy 9.302995 -288.763543) (xy 9.353659 -288.825278)
			(xy 9.398029 -288.891681) (xy 9.435676 -288.962113) (xy 9.466238 -289.035896) (xy 9.489421 -289.11232)
			(xy 9.505002 -289.190648) (xy 9.51283 -289.270126) (xy 9.51283 -289.349989) (xy 9.505003 -289.429467)
			(xy 9.489423 -289.507795) (xy 9.46624 -289.584218) (xy 9.435678 -289.658002) (xy 9.398031 -289.728435)
			(xy 9.353662 -289.794838) (xy 9.302998 -289.856573) (xy 9.246527 -289.913044) (xy 9.184793 -289.963709)
			(xy 9.11839 -290.008078) (xy 9.047957 -290.045726) (xy 8.974174 -290.076288) (xy 8.897751 -290.099471)
			(xy 8.819423 -290.115052) (xy 8.739945 -290.12288) (xy 8.660082 -290.12288) (xy 8.580604 -290.115053)
			(xy 8.502276 -290.099473) (xy 8.425852 -290.07629) (xy 8.352069 -290.045728) (xy 8.281636 -290.008082)
			(xy 8.215233 -289.963713) (xy 8.153498 -289.913049) (xy 8.097026 -289.856578) (xy 8.046362 -289.794843)
			(xy 8.001992 -289.72844) (xy 7.964345 -289.658008) (xy 7.933782 -289.584225) (xy 7.910599 -289.507801)
			(xy 7.895018 -289.429473) (xy 7.88719 -289.349995) (xy 7.8867 -289.310064) (xy 7.887171 -289.270934)
			(xy 7.894683 -289.193037) (xy 7.909644 -289.116221) (xy 7.931915 -289.041198) (xy 7.961291 -288.968662)
			(xy 7.9975 -288.899283) (xy 8.040206 -288.833703) (xy 8.064246 -288.802826) (xy 8.074406 -288.790126)
			(xy 8.076438 -288.758122) (xy 8.008874 -288.649156) (xy 7.97941 -288.63671) (xy 7.963662 -288.640012)
			(xy 7.911593 -288.650606) (xy 7.80618 -288.664035) (xy 7.70001 -288.668522) (xy 7.59384 -288.664035)
			(xy 7.488427 -288.650606) (xy 7.436358 -288.640012) (xy 7.42061 -288.63671) (xy 7.391146 -288.649156)
			(xy 7.323582 -288.758122) (xy 7.325614 -288.790126) (xy 7.335774 -288.802826) (xy 7.359807 -288.833709)
			(xy 7.40251 -288.899289) (xy 7.438717 -288.968668) (xy 7.468093 -289.041203) (xy 7.490367 -289.116225)
			(xy 7.505333 -289.193039) (xy 7.512853 -289.270935) (xy 7.51332 -289.310064) (xy 7.512824 -289.349995)
			(xy 7.504996 -289.429472) (xy 7.489415 -289.5078) (xy 7.466232 -289.584223) (xy 7.43567 -289.658005)
			(xy 7.398023 -289.728437) (xy 7.353654 -289.79484) (xy 7.302989 -289.856574) (xy 7.246518 -289.913044)
			(xy 7.184784 -289.963708) (xy 7.118381 -290.008077) (xy 7.047949 -290.045723) (xy 6.974166 -290.076285)
			(xy 6.897743 -290.099467) (xy 6.819415 -290.115047) (xy 6.739938 -290.122874) (xy 6.660076 -290.122874)
			(xy 6.580598 -290.115046) (xy 6.502271 -290.099465) (xy 6.425848 -290.076282) (xy 6.352065 -290.04572)
			(xy 6.281633 -290.008073) (xy 6.215231 -289.963704) (xy 6.153497 -289.91304) (xy 6.097026 -289.856569)
			(xy 6.046362 -289.794834) (xy 6.001994 -289.728432) (xy 5.964347 -289.657999) (xy 5.933786 -289.584216)
			(xy 5.910603 -289.507793) (xy 5.895023 -289.429466) (xy 5.887196 -289.349988) (xy 1.27 -289.349988)
			(xy 1.27 -299.310044) (xy 5.378133 -299.310044) (xy 5.382265 -299.205611) (xy 5.394637 -299.10183)
			(xy 5.415171 -298.999352) (xy 5.443738 -298.898817) (xy 5.48016 -298.800854) (xy 5.524209 -298.706075)
			(xy 5.57561 -298.615073) (xy 5.634041 -298.528417) (xy 5.699137 -298.446649) (xy 5.77049 -298.370281)
			(xy 5.847655 -298.29979) (xy 5.930148 -298.235616) (xy 6.017455 -298.178162) (xy 6.109028 -298.127787)
			(xy 6.156452 -298.10583) (xy 6.16839 -298.100242) (xy 6.184138 -298.079414) (xy 6.199124 -297.967908)
			(xy 6.189726 -297.943524) (xy 6.179566 -297.935142) (xy 6.149432 -297.909425) (xy 6.093774 -297.853042)
			(xy 6.043861 -297.791516) (xy 6.000166 -297.725428) (xy 5.963102 -297.655406) (xy 5.933021 -297.582112)
			(xy 5.910208 -297.506242) (xy 5.894878 -297.428512) (xy 5.887177 -297.349661) (xy 5.886704 -297.310048)
			(xy 5.887212 -297.270116) (xy 5.895036 -297.190638) (xy 5.910612 -297.112308) (xy 5.933792 -297.035883)
			(xy 5.964351 -296.962098) (xy 6.001996 -296.891664) (xy 6.046363 -296.825259) (xy 6.097026 -296.763523)
			(xy 6.153496 -296.70705) (xy 6.21523 -296.656384) (xy 6.281633 -296.612014) (xy 6.352066 -296.574366)
			(xy 6.425849 -296.543804) (xy 6.502274 -296.520621) (xy 6.580602 -296.505041) (xy 6.660081 -296.497214)
			(xy 6.700012 -296.49674) (xy 6.739625 -296.497212) (xy 6.818476 -296.504915) (xy 6.896205 -296.520246)
			(xy 6.972075 -296.54306) (xy 7.045368 -296.573141) (xy 7.11539 -296.610205) (xy 7.181478 -296.6539)
			(xy 7.243005 -296.703812) (xy 7.299389 -296.759468) (xy 7.325106 -296.789602) (xy 7.333488 -296.799762)
			(xy 7.357872 -296.80916) (xy 7.469378 -296.794174) (xy 7.490206 -296.778426) (xy 7.495794 -296.766488)
			(xy 7.518123 -296.718352) (xy 7.569398 -296.625441) (xy 7.627962 -296.536944) (xy 7.693437 -296.45343)
			(xy 7.765401 -296.375438) (xy 7.84339 -296.303471) (xy 7.926901 -296.237993) (xy 8.015396 -296.179426)
			(xy 8.108304 -296.128147) (xy 8.156448 -296.105834) (xy 8.168386 -296.100246) (xy 8.184134 -296.079418)
			(xy 8.19912 -295.967912) (xy 8.189722 -295.943528) (xy 8.179562 -295.935146) (xy 8.149429 -295.909428)
			(xy 8.093771 -295.853045) (xy 8.043858 -295.791519) (xy 8.000163 -295.725431) (xy 7.963099 -295.655409)
			(xy 7.933018 -295.582116) (xy 7.910205 -295.506245) (xy 7.894875 -295.428516) (xy 7.887174 -295.349665)
			(xy 7.8867 -295.310052) (xy 7.887234 -295.268164) (xy 7.895842 -295.184832) (xy 7.912972 -295.102827)
			(xy 7.938442 -295.023017) (xy 7.971984 -294.946249) (xy 8.01324 -294.873336) (xy 8.037068 -294.838882)
			(xy 8.04545 -294.827198) (xy 8.047482 -294.799004) (xy 7.999476 -294.70604) (xy 7.994821 -294.697986)
			(xy 7.980928 -294.685638) (xy 7.963557 -294.679022) (xy 7.954264 -294.678608) (xy 7.874 -294.678608)
			(xy 7.864029 -294.679056) (xy 7.845593 -294.686649) (xy 7.838186 -294.69334) (xy 7.485126 -295.0464)
			(xy 7.478268 -295.07307) (xy 7.482078 -295.086532) (xy 7.492027 -295.122944) (xy 7.505932 -295.197141)
			(xy 7.512903 -295.272307) (xy 7.51332 -295.310052) (xy 7.51283 -295.349983) (xy 7.505002 -295.429461)
			(xy 7.489422 -295.507789) (xy 7.466239 -295.584212) (xy 7.435677 -295.657996) (xy 7.39803 -295.728428)
			(xy 7.353661 -295.794831) (xy 7.302997 -295.856566) (xy 7.246526 -295.913037) (xy 7.184791 -295.963701)
			(xy 7.118388 -296.00807) (xy 7.047956 -296.045717) (xy 6.974172 -296.076279) (xy 6.897749 -296.099462)
			(xy 6.819421 -296.115042) (xy 6.739943 -296.12287) (xy 6.660081 -296.12287) (xy 6.580603 -296.115042)
			(xy 6.502275 -296.099462) (xy 6.425852 -296.076279) (xy 6.352068 -296.045717) (xy 6.281636 -296.00807)
			(xy 6.215233 -295.963701) (xy 6.153498 -295.913037) (xy 6.097027 -295.856566) (xy 6.046363 -295.794831)
			(xy 6.001994 -295.728428) (xy 5.964347 -295.657996) (xy 5.933785 -295.584212) (xy 5.910602 -295.507789)
			(xy 5.895022 -295.429461) (xy 5.887194 -295.349983) (xy 5.886704 -295.310052) (xy 5.887163 -295.270439)
			(xy 5.894869 -295.191588) (xy 5.910202 -295.113859) (xy 5.933019 -295.037989) (xy 5.963102 -294.964696)
			(xy 6.000167 -294.894674) (xy 6.043863 -294.828587) (xy 6.093775 -294.76706) (xy 6.149432 -294.710676)
			(xy 6.179566 -294.684958) (xy 6.189726 -294.676576) (xy 6.199124 -294.652192) (xy 6.184138 -294.540686)
			(xy 6.16839 -294.519858) (xy 6.156452 -294.51427) (xy 6.109028 -294.492313) (xy 6.017455 -294.441938)
			(xy 5.930148 -294.384484) (xy 5.847655 -294.32031) (xy 5.77049 -294.249819) (xy 5.699137 -294.173451)
			(xy 5.634041 -294.091683) (xy 5.57561 -294.005027) (xy 5.524209 -293.914025) (xy 5.48016 -293.819246)
			(xy 5.443738 -293.721283) (xy 5.415171 -293.620748) (xy 5.394637 -293.51827) (xy 5.382265 -293.414489)
			(xy 5.378133 -293.310056) (xy 5.382265 -293.205623) (xy 5.394637 -293.101842) (xy 5.415171 -292.999364)
			(xy 5.443738 -292.898829) (xy 5.48016 -292.800866) (xy 5.524209 -292.706087) (xy 5.57561 -292.615085)
			(xy 5.634041 -292.528429) (xy 5.699137 -292.446661) (xy 5.77049 -292.370293) (xy 5.847655 -292.299802)
			(xy 5.930148 -292.235628) (xy 6.017455 -292.178174) (xy 6.109028 -292.127799) (xy 6.156452 -292.105842)
			(xy 6.16839 -292.100254) (xy 6.184138 -292.079426) (xy 6.199124 -291.96792) (xy 6.189726 -291.943536)
			(xy 6.179566 -291.935154) (xy 6.149433 -291.909436) (xy 6.093775 -291.853053) (xy 6.043862 -291.791527)
			(xy 6.000167 -291.72544) (xy 5.963103 -291.655417) (xy 5.933022 -291.582124) (xy 5.910208 -291.506253)
			(xy 5.894878 -291.428524) (xy 5.887177 -291.349673) (xy 5.886704 -291.31006) (xy 5.887194 -291.270129)
			(xy 5.895022 -291.190651) (xy 5.910602 -291.112323) (xy 5.933785 -291.0359) (xy 5.964347 -290.962116)
			(xy 6.001994 -290.891684) (xy 6.046363 -290.825281) (xy 6.097027 -290.763546) (xy 6.153498 -290.707075)
			(xy 6.215233 -290.656411) (xy 6.281636 -290.612042) (xy 6.352068 -290.574395) (xy 6.425852 -290.543833)
			(xy 6.502275 -290.52065) (xy 6.580603 -290.50507) (xy 6.660081 -290.497242) (xy 6.739943 -290.497242)
			(xy 6.819421 -290.50507) (xy 6.897749 -290.52065) (xy 6.974172 -290.543833) (xy 7.047956 -290.574395)
			(xy 7.118388 -290.612042) (xy 7.184791 -290.656411) (xy 7.246526 -290.707075) (xy 7.302997 -290.763546)
			(xy 7.353661 -290.825281) (xy 7.39803 -290.891684) (xy 7.435677 -290.962116) (xy 7.466239 -291.0359)
			(xy 7.489422 -291.112323) (xy 7.505002 -291.190651) (xy 7.51283 -291.270129) (xy 7.51332 -291.31006)
			(xy 7.512861 -291.349673) (xy 7.505154 -291.428524) (xy 7.48982 -291.506252) (xy 7.467003 -291.582122)
			(xy 7.43692 -291.655415) (xy 7.399855 -291.725437) (xy 7.35616 -291.791524) (xy 7.306248 -291.853051)
			(xy 7.250591 -291.909436) (xy 7.220458 -291.935154) (xy 7.210298 -291.943536) (xy 7.2009 -291.96792)
			(xy 7.215886 -292.079426) (xy 7.231634 -292.100254) (xy 7.243572 -292.105842) (xy 7.291716 -292.128155)
			(xy 7.384626 -292.179433) (xy 7.473122 -292.237999) (xy 7.556635 -292.303476) (xy 7.634626 -292.375442)
			(xy 7.706592 -292.453433) (xy 7.772069 -292.536946) (xy 7.830636 -292.625442) (xy 7.881914 -292.718352)
			(xy 7.904226 -292.766496) (xy 7.909814 -292.778434) (xy 7.930642 -292.794182) (xy 8.042148 -292.809168)
			(xy 8.066532 -292.79977) (xy 8.074914 -292.78961) (xy 8.100624 -292.75947) (xy 8.157009 -292.703814)
			(xy 8.218537 -292.653902) (xy 8.284625 -292.610208) (xy 8.354648 -292.573145) (xy 8.427942 -292.543065)
			(xy 8.503814 -292.520252) (xy 8.581543 -292.504922) (xy 8.660395 -292.497222) (xy 8.700008 -292.496748)
			(xy 8.73994 -292.497218) (xy 8.81942 -292.505046) (xy 8.897749 -292.520627) (xy 8.974175 -292.54381)
			(xy 9.04796 -292.574373) (xy 9.118394 -292.612021) (xy 9.184798 -292.656391) (xy 9.246534 -292.707056)
			(xy 9.303006 -292.763529) (xy 9.353672 -292.825265) (xy 9.398042 -292.89167) (xy 9.435689 -292.962104)
			(xy 9.466251 -293.035889) (xy 9.489434 -293.112314) (xy 9.505014 -293.190644) (xy 9.512842 -293.270124)
			(xy 9.513316 -293.310056) (xy 9.512764 -293.351893) (xy 9.504144 -293.435122) (xy 9.48703 -293.517028)
			(xy 9.461605 -293.596747) (xy 9.428135 -293.673436) (xy 9.386974 -293.746287) (xy 9.363202 -293.780718)
			(xy 9.35482 -293.792402) (xy 9.353042 -293.820596) (xy 9.401048 -293.91356) (xy 9.40566 -293.921655)
			(xy 9.419537 -293.934059) (xy 9.43695 -293.940636) (xy 9.44626 -293.940992) (xy 9.525 -293.940992)
			(xy 9.553974 -293.941542) (xy 9.611201 -293.950656) (xy 9.666297 -293.968611) (xy 9.717905 -293.994965)
			(xy 9.764754 -294.029069) (xy 9.785604 -294.049196) (xy 10.547604 -294.811196) (xy 10.567751 -294.832026)
			(xy 10.601855 -294.878879) (xy 10.628205 -294.930493) (xy 10.646151 -294.985594) (xy 10.655253 -295.042825)
			(xy 10.655808 -295.0718) (xy 10.655808 -295.557702) (xy 10.657078 -295.563798) (xy 10.662403 -295.586476)
			(xy 10.66813 -295.632708) (xy 10.668508 -295.656) (xy 10.668022 -295.683251) (xy 10.660266 -295.737199)
			(xy 10.644911 -295.789494) (xy 10.622269 -295.839071) (xy 10.592803 -295.884921) (xy 10.557112 -295.926112)
			(xy 10.515921 -295.961803) (xy 10.470071 -295.991269) (xy 10.420494 -296.013911) (xy 10.368199 -296.029266)
			(xy 10.314251 -296.037022) (xy 10.259749 -296.037022) (xy 10.205801 -296.029266) (xy 10.153506 -296.013911)
			(xy 10.103929 -295.991269) (xy 10.058079 -295.961803) (xy 10.016888 -295.926112) (xy 9.981197 -295.884921)
			(xy 9.951731 -295.839071) (xy 9.929089 -295.789494) (xy 9.913734 -295.737199) (xy 9.905978 -295.683251)
			(xy 9.905492 -295.656) (xy 9.905875 -295.632708) (xy 9.911602 -295.586477) (xy 9.916922 -295.563798)
			(xy 9.918192 -295.557702) (xy 9.918192 -295.245536) (xy 9.917794 -295.235554) (xy 9.910203 -295.217092)
			(xy 9.90346 -295.209722) (xy 9.387078 -294.69334) (xy 9.37965 -294.686682) (xy 9.361226 -294.679094)
			(xy 9.351264 -294.678608) (xy 9.339834 -294.678608) (xy 9.329814 -294.679048) (xy 9.311296 -294.686708)
			(xy 9.297123 -294.700874) (xy 9.289453 -294.719388) (xy 9.289034 -294.729408) (xy 9.289034 -294.73906)
			(xy 9.295638 -294.756332) (xy 9.302242 -294.763444) (xy 9.330618 -294.795525) (xy 9.3812 -294.864648)
			(xy 9.424237 -294.938703) (xy 9.459253 -295.016871) (xy 9.485861 -295.098286) (xy 9.503764 -295.182047)
			(xy 9.512766 -295.267226) (xy 9.513316 -295.310052) (xy 9.512853 -295.349665) (xy 9.505147 -295.428516)
			(xy 9.489813 -295.506244) (xy 9.466997 -295.582114) (xy 9.436914 -295.655407) (xy 9.39985 -295.725428)
			(xy 9.356155 -295.791516) (xy 9.306243 -295.853043) (xy 9.250587 -295.909428) (xy 9.220454 -295.935146)
			(xy 9.210294 -295.943528) (xy 9.200896 -295.967912) (xy 9.215882 -296.079418) (xy 9.23163 -296.100246)
			(xy 9.243568 -296.105834) (xy 9.29099 -296.127794) (xy 9.382563 -296.17817) (xy 9.46987 -296.235624)
			(xy 9.552363 -296.299797) (xy 9.629528 -296.370288) (xy 9.700881 -296.446656) (xy 9.765976 -296.528424)
			(xy 9.824407 -296.615079) (xy 9.875808 -296.706081) (xy 9.919857 -296.80086) (xy 9.956279 -296.898823)
			(xy 9.984846 -296.999358) (xy 10.00538 -297.101836) (xy 10.017752 -297.205616) (xy 10.021884 -297.310049)
			(xy 10.017752 -297.414482) (xy 10.00538 -297.518262) (xy 9.984847 -297.62074) (xy 9.956279 -297.721275)
			(xy 9.919857 -297.819239) (xy 9.875808 -297.914017) (xy 9.824408 -298.005019) (xy 9.765977 -298.091675)
			(xy 9.700882 -298.173443) (xy 9.629529 -298.249811) (xy 9.552364 -298.320302) (xy 9.469871 -298.384475)
			(xy 9.382565 -298.441929) (xy 9.290992 -298.492305) (xy 9.243568 -298.514262) (xy 9.23163 -298.51985)
			(xy 9.215882 -298.540678) (xy 9.200896 -298.652184) (xy 9.210294 -298.676568) (xy 9.220454 -298.68495)
			(xy 9.250589 -298.710666) (xy 9.306247 -298.767049) (xy 9.35616 -298.828576) (xy 9.399855 -298.894663)
			(xy 9.436919 -298.964685) (xy 9.466999 -299.037979) (xy 9.489813 -299.11385) (xy 9.505142 -299.191579)
			(xy 9.512843 -299.270431) (xy 9.513316 -299.310044) (xy 9.51286 -299.349976) (xy 9.505028 -299.429454)
			(xy 9.489444 -299.507782) (xy 9.466258 -299.584206) (xy 9.435692 -299.657989) (xy 9.398043 -299.728421)
			(xy 9.353671 -299.794824) (xy 9.303004 -299.856558) (xy 9.246531 -299.913029) (xy 9.184795 -299.963692)
			(xy 9.11839 -300.008061) (xy 9.047957 -300.045708) (xy 8.974172 -300.07627) (xy 8.897747 -300.099453)
			(xy 8.819419 -300.115033) (xy 8.73994 -300.122862) (xy 8.700008 -300.123352) (xy 8.660395 -300.122868)
			(xy 8.581545 -300.115168) (xy 8.503816 -300.099838) (xy 8.427946 -300.077026) (xy 8.354653 -300.046946)
			(xy 8.28463 -300.009884) (xy 8.218543 -299.96619) (xy 8.157015 -299.916279) (xy 8.100631 -299.860623)
			(xy 8.074914 -299.83049) (xy 8.066532 -299.82033) (xy 8.042148 -299.810932) (xy 7.930642 -299.825918)
			(xy 7.909814 -299.841666) (xy 7.904226 -299.853604) (xy 7.881927 -299.901754) (xy 7.830646 -299.994663)
			(xy 7.772077 -300.083159) (xy 7.706598 -300.166671) (xy 7.634631 -300.24466) (xy 7.556638 -300.316626)
			(xy 7.473124 -300.382102) (xy 7.384627 -300.440668) (xy 7.291716 -300.491946) (xy 7.243572 -300.514258)
			(xy 7.231634 -300.519846) (xy 7.215886 -300.540674) (xy 7.2009 -300.65218) (xy 7.210298 -300.676564)
			(xy 7.220458 -300.684946) (xy 7.250592 -300.710663) (xy 7.30625 -300.767046) (xy 7.356163 -300.828573)
			(xy 7.399858 -300.89466) (xy 7.436921 -300.964682) (xy 7.467002 -301.037976) (xy 7.489816 -301.113846)
			(xy 7.505146 -301.191576) (xy 7.512847 -301.270427) (xy 7.51332 -301.31004) (xy 7.886194 -301.31004)
			(xy 7.890238 -301.22901) (xy 7.90233 -301.148786) (xy 7.922349 -301.070164) (xy 7.950098 -300.993926)
			(xy 7.985299 -300.92083) (xy 8.027603 -300.851602) (xy 8.07659 -300.78693) (xy 8.131773 -300.727458)
			(xy 8.192603 -300.673775) (xy 8.258476 -300.626415) (xy 8.328737 -300.58585) (xy 8.402688 -300.552482)
			(xy 8.479594 -300.526643) (xy 8.558691 -300.50859) (xy 8.639192 -300.498502) (xy 8.720297 -300.496479)
			(xy 8.801201 -300.502542) (xy 8.881099 -300.51663) (xy 8.959197 -300.538603) (xy 9.034719 -300.568244)
			(xy 9.106915 -300.605256) (xy 9.175067 -300.649273) (xy 9.238497 -300.699858) (xy 9.296576 -300.756506)
			(xy 9.348726 -300.818656) (xy 9.394428 -300.885689) (xy 9.433229 -300.956939) (xy 9.464743 -301.031699)
			(xy 9.488657 -301.109225) (xy 9.504732 -301.188747) (xy 9.51281 -301.269475) (xy 9.513316 -301.31004)
			(xy 9.51281 -301.350605) (xy 9.504732 -301.431333) (xy 9.488657 -301.510855) (xy 9.464743 -301.588381)
			(xy 9.433229 -301.663141) (xy 9.394428 -301.734391) (xy 9.348726 -301.801424) (xy 9.296576 -301.863574)
			(xy 9.238497 -301.920222) (xy 9.175067 -301.970807) (xy 9.106915 -302.014824) (xy 9.034719 -302.051836)
			(xy 8.959197 -302.081477) (xy 8.881099 -302.10345) (xy 8.801201 -302.117538) (xy 8.720297 -302.123601)
			(xy 8.639192 -302.121578) (xy 8.558691 -302.11149) (xy 8.479594 -302.093437) (xy 8.402688 -302.067598)
			(xy 8.328737 -302.03423) (xy 8.258476 -301.993665) (xy 8.192603 -301.946305) (xy 8.131773 -301.892622)
			(xy 8.07659 -301.83315) (xy 8.027603 -301.768478) (xy 7.985299 -301.69925) (xy 7.950098 -301.626154)
			(xy 7.922349 -301.549916) (xy 7.90233 -301.471294) (xy 7.890238 -301.39107) (xy 7.886194 -301.31004)
			(xy 7.51332 -301.31004) (xy 7.51283 -301.349971) (xy 7.505002 -301.429449) (xy 7.489422 -301.507777)
			(xy 7.466239 -301.5842) (xy 7.435677 -301.657984) (xy 7.39803 -301.728416) (xy 7.353661 -301.794819)
			(xy 7.302997 -301.856554) (xy 7.246526 -301.913025) (xy 7.184791 -301.963689) (xy 7.118388 -302.008058)
			(xy 7.047956 -302.045705) (xy 6.974172 -302.076267) (xy 6.897749 -302.09945) (xy 6.819421 -302.11503)
			(xy 6.739943 -302.122858) (xy 6.660081 -302.122858) (xy 6.580603 -302.11503) (xy 6.502275 -302.09945)
			(xy 6.425852 -302.076267) (xy 6.352068 -302.045705) (xy 6.281636 -302.008058) (xy 6.215233 -301.963689)
			(xy 6.153498 -301.913025) (xy 6.097027 -301.856554) (xy 6.046363 -301.794819) (xy 6.001994 -301.728416)
			(xy 5.964347 -301.657984) (xy 5.933785 -301.5842) (xy 5.910602 -301.507777) (xy 5.895022 -301.429449)
			(xy 5.887194 -301.349971) (xy 5.886704 -301.31004) (xy 5.887154 -301.270427) (xy 5.894861 -301.191575)
			(xy 5.910196 -301.113846) (xy 5.933014 -301.037976) (xy 5.963098 -300.964683) (xy 6.000164 -300.894662)
			(xy 6.043861 -300.828574) (xy 6.093774 -300.767047) (xy 6.149432 -300.710663) (xy 6.179566 -300.684946)
			(xy 6.189726 -300.676564) (xy 6.199124 -300.65218) (xy 6.184138 -300.540674) (xy 6.16839 -300.519846)
			(xy 6.156452 -300.514258) (xy 6.109028 -300.492301) (xy 6.017455 -300.441926) (xy 5.930148 -300.384472)
			(xy 5.847655 -300.320298) (xy 5.77049 -300.249807) (xy 5.699137 -300.173439) (xy 5.634041 -300.091671)
			(xy 5.57561 -300.005015) (xy 5.524209 -299.914013) (xy 5.48016 -299.819234) (xy 5.443738 -299.721271)
			(xy 5.415171 -299.620736) (xy 5.394637 -299.518258) (xy 5.382265 -299.414477) (xy 5.378133 -299.310044)
			(xy 1.27 -299.310044) (xy 1.27 -303.310036) (xy 5.886198 -303.310036) (xy 5.890242 -303.229006) (xy 5.902334 -303.148782)
			(xy 5.922353 -303.07016) (xy 5.950102 -302.993922) (xy 5.985303 -302.920826) (xy 6.027607 -302.851598)
			(xy 6.076594 -302.786926) (xy 6.131777 -302.727454) (xy 6.192607 -302.673771) (xy 6.25848 -302.626411)
			(xy 6.328741 -302.585846) (xy 6.402692 -302.552478) (xy 6.479598 -302.526639) (xy 6.558695 -302.508586)
			(xy 6.639196 -302.498498) (xy 6.720301 -302.496475) (xy 6.801205 -302.502538) (xy 6.881103 -302.516626)
			(xy 6.959201 -302.538599) (xy 7.034723 -302.56824) (xy 7.106919 -302.605252) (xy 7.175071 -302.649269)
			(xy 7.238501 -302.699854) (xy 7.29658 -302.756502) (xy 7.34873 -302.818652) (xy 7.394432 -302.885685)
			(xy 7.433233 -302.956935) (xy 7.464747 -303.031695) (xy 7.488661 -303.109221) (xy 7.504736 -303.188743)
			(xy 7.512814 -303.269471) (xy 7.51332 -303.310036) (xy 7.886194 -303.310036) (xy 7.890238 -303.229006)
			(xy 7.90233 -303.148782) (xy 7.922349 -303.07016) (xy 7.950098 -302.993922) (xy 7.985299 -302.920826)
			(xy 8.027603 -302.851598) (xy 8.07659 -302.786926) (xy 8.131773 -302.727454) (xy 8.192603 -302.673771)
			(xy 8.258476 -302.626411) (xy 8.328737 -302.585846) (xy 8.402688 -302.552478) (xy 8.479594 -302.526639)
			(xy 8.558691 -302.508586) (xy 8.639192 -302.498498) (xy 8.720297 -302.496475) (xy 8.801201 -302.502538)
			(xy 8.881099 -302.516626) (xy 8.959197 -302.538599) (xy 9.034719 -302.56824) (xy 9.106915 -302.605252)
			(xy 9.175067 -302.649269) (xy 9.238497 -302.699854) (xy 9.296576 -302.756502) (xy 9.348726 -302.818652)
			(xy 9.394428 -302.885685) (xy 9.433229 -302.956935) (xy 9.464743 -303.031695) (xy 9.488657 -303.109221)
			(xy 9.504732 -303.188743) (xy 9.51281 -303.269471) (xy 9.512891 -303.276) (xy 16.088104 -303.276)
			(xy 16.092175 -303.220378) (xy 16.104301 -303.165941) (xy 16.124224 -303.11385) (xy 16.15152 -303.065215)
			(xy 16.185606 -303.021072) (xy 16.225755 -302.982363) (xy 16.271113 -302.949912) (xy 16.320713 -302.924411)
			(xy 16.373497 -302.906404) (xy 16.42834 -302.896274) (xy 16.484074 -302.894237) (xy 16.539511 -302.900337)
			(xy 16.593468 -302.914443) (xy 16.644797 -302.936255) (xy 16.692403 -302.965309) (xy 16.735271 -303.000984)
			(xy 16.772488 -303.042521) (xy 16.803261 -303.089034) (xy 16.826933 -303.139531) (xy 16.843001 -303.192938)
			(xy 16.851121 -303.248114) (xy 16.85163 -303.276) (xy 16.851121 -303.303886) (xy 16.843001 -303.359062)
			(xy 16.826933 -303.412469) (xy 16.803261 -303.462966) (xy 16.772488 -303.509479) (xy 16.735271 -303.551016)
			(xy 16.692403 -303.586691) (xy 16.644797 -303.615745) (xy 16.593468 -303.637557) (xy 16.539511 -303.651663)
			(xy 16.484074 -303.657763) (xy 16.42834 -303.655726) (xy 16.373497 -303.645596) (xy 16.320713 -303.627589)
			(xy 16.271113 -303.602088) (xy 16.225755 -303.569637) (xy 16.185606 -303.530928) (xy 16.15152 -303.486785)
			(xy 16.124224 -303.43815) (xy 16.104301 -303.386059) (xy 16.092175 -303.331622) (xy 16.088104 -303.276)
			(xy 9.512891 -303.276) (xy 9.513316 -303.310036) (xy 9.51281 -303.350601) (xy 9.504732 -303.431329)
			(xy 9.488657 -303.510851) (xy 9.464743 -303.588377) (xy 9.433229 -303.663137) (xy 9.394428 -303.734387)
			(xy 9.348726 -303.80142) (xy 9.296576 -303.86357) (xy 9.238497 -303.920218) (xy 9.175067 -303.970803)
			(xy 9.106915 -304.01482) (xy 9.034719 -304.051832) (xy 8.959197 -304.081473) (xy 8.881099 -304.103446)
			(xy 8.801201 -304.117534) (xy 8.720297 -304.123597) (xy 8.639192 -304.121574) (xy 8.558691 -304.111486)
			(xy 8.479594 -304.093433) (xy 8.402688 -304.067594) (xy 8.328737 -304.034226) (xy 8.258476 -303.993661)
			(xy 8.192603 -303.946301) (xy 8.131773 -303.892618) (xy 8.07659 -303.833146) (xy 8.027603 -303.768474)
			(xy 7.985299 -303.699246) (xy 7.950098 -303.62615) (xy 7.922349 -303.549912) (xy 7.90233 -303.47129)
			(xy 7.890238 -303.391066) (xy 7.886194 -303.310036) (xy 7.51332 -303.310036) (xy 7.512814 -303.350601)
			(xy 7.504736 -303.431329) (xy 7.488661 -303.510851) (xy 7.464747 -303.588377) (xy 7.433233 -303.663137)
			(xy 7.394432 -303.734387) (xy 7.34873 -303.80142) (xy 7.29658 -303.86357) (xy 7.238501 -303.920218)
			(xy 7.175071 -303.970803) (xy 7.106919 -304.01482) (xy 7.034723 -304.051832) (xy 6.959201 -304.081473)
			(xy 6.881103 -304.103446) (xy 6.801205 -304.117534) (xy 6.720301 -304.123597) (xy 6.639196 -304.121574)
			(xy 6.558695 -304.111486) (xy 6.479598 -304.093433) (xy 6.402692 -304.067594) (xy 6.328741 -304.034226)
			(xy 6.25848 -303.993661) (xy 6.192607 -303.946301) (xy 6.131777 -303.892618) (xy 6.076594 -303.833146)
			(xy 6.027607 -303.768474) (xy 5.985303 -303.699246) (xy 5.950102 -303.62615) (xy 5.922353 -303.549912)
			(xy 5.902334 -303.47129) (xy 5.890242 -303.391066) (xy 5.886198 -303.310036) (xy 1.27 -303.310036)
			(xy 1.27 -304.81905) (xy 18.288252 -304.81905) (xy 18.292323 -304.763428) (xy 18.304449 -304.708991)
			(xy 18.324372 -304.6569) (xy 18.351668 -304.608265) (xy 18.385754 -304.564122) (xy 18.425903 -304.525413)
			(xy 18.471261 -304.492962) (xy 18.520861 -304.467461) (xy 18.573645 -304.449454) (xy 18.628488 -304.439324)
			(xy 18.684222 -304.437287) (xy 18.739659 -304.443387) (xy 18.793616 -304.457493) (xy 18.844945 -304.479305)
			(xy 18.892551 -304.508359) (xy 18.935419 -304.544034) (xy 18.972636 -304.585571) (xy 19.003409 -304.632084)
			(xy 19.027081 -304.682581) (xy 19.043149 -304.735988) (xy 19.051269 -304.791164) (xy 19.051778 -304.81905)
			(xy 19.051269 -304.846936) (xy 19.043149 -304.902112) (xy 19.027081 -304.955519) (xy 19.003409 -305.006016)
			(xy 18.972636 -305.052529) (xy 18.935419 -305.094066) (xy 18.892551 -305.129741) (xy 18.844945 -305.158795)
			(xy 18.793616 -305.180607) (xy 18.739659 -305.194713) (xy 18.684222 -305.200813) (xy 18.628488 -305.198776)
			(xy 18.573645 -305.188646) (xy 18.520861 -305.170639) (xy 18.471261 -305.145138) (xy 18.425903 -305.112687)
			(xy 18.385754 -305.073978) (xy 18.351668 -305.029835) (xy 18.324372 -304.9812) (xy 18.304449 -304.929109)
			(xy 18.292323 -304.874672) (xy 18.288252 -304.81905) (xy 1.27 -304.81905) (xy 1.27 -305.631342) (xy 13.841982 -305.631342)
			(xy 13.846053 -305.57572) (xy 13.858179 -305.521283) (xy 13.878102 -305.469192) (xy 13.905398 -305.420557)
			(xy 13.939484 -305.376414) (xy 13.979633 -305.337705) (xy 14.024991 -305.305254) (xy 14.074591 -305.279753)
			(xy 14.127375 -305.261746) (xy 14.182218 -305.251616) (xy 14.237952 -305.249579) (xy 14.293389 -305.255679)
			(xy 14.347346 -305.269785) (xy 14.398675 -305.291597) (xy 14.446281 -305.320651) (xy 14.489149 -305.356326)
			(xy 14.526366 -305.397863) (xy 14.557139 -305.444376) (xy 14.580811 -305.494873) (xy 14.596879 -305.54828)
			(xy 14.604999 -305.603456) (xy 14.605508 -305.631342) (xy 14.604999 -305.659228) (xy 14.596879 -305.714404)
			(xy 14.580811 -305.767811) (xy 14.557139 -305.818308) (xy 14.526366 -305.864821) (xy 14.489149 -305.906358)
			(xy 14.446281 -305.942033) (xy 14.398675 -305.971087) (xy 14.347346 -305.992899) (xy 14.293389 -306.007005)
			(xy 14.237952 -306.013105) (xy 14.182218 -306.011068) (xy 14.127375 -306.000938) (xy 14.074591 -305.982931)
			(xy 14.024991 -305.95743) (xy 13.979633 -305.924979) (xy 13.939484 -305.88627) (xy 13.905398 -305.842127)
			(xy 13.878102 -305.793492) (xy 13.858179 -305.741401) (xy 13.846053 -305.686964) (xy 13.841982 -305.631342)
			(xy 1.27 -305.631342) (xy 1.27 -308.61) (xy 2.411982 -308.61) (xy 2.416053 -308.554378) (xy 2.428179 -308.499941)
			(xy 2.448102 -308.44785) (xy 2.475398 -308.399215) (xy 2.509484 -308.355072) (xy 2.549633 -308.316363)
			(xy 2.594991 -308.283912) (xy 2.644591 -308.258411) (xy 2.697375 -308.240404) (xy 2.752218 -308.230274)
			(xy 2.807952 -308.228237) (xy 2.863389 -308.234337) (xy 2.917346 -308.248443) (xy 2.968675 -308.270255)
			(xy 3.016281 -308.299309) (xy 3.059149 -308.334984) (xy 3.096366 -308.376521) (xy 3.127139 -308.423034)
			(xy 3.150811 -308.473531) (xy 3.166879 -308.526938) (xy 3.174999 -308.582114) (xy 3.175508 -308.61)
			(xy 48.512982 -308.61) (xy 48.517053 -308.554378) (xy 48.529179 -308.499941) (xy 48.549102 -308.44785)
			(xy 48.576398 -308.399215) (xy 48.610484 -308.355072) (xy 48.650633 -308.316363) (xy 48.695991 -308.283912)
			(xy 48.745591 -308.258411) (xy 48.798375 -308.240404) (xy 48.853218 -308.230274) (xy 48.908952 -308.228237)
			(xy 48.964389 -308.234337) (xy 49.018346 -308.248443) (xy 49.069675 -308.270255) (xy 49.117281 -308.299309)
			(xy 49.160149 -308.334984) (xy 49.197366 -308.376521) (xy 49.228139 -308.423034) (xy 49.251811 -308.473531)
			(xy 49.267879 -308.526938) (xy 49.275999 -308.582114) (xy 49.276508 -308.61) (xy 49.275999 -308.637886)
			(xy 49.267879 -308.693062) (xy 49.251811 -308.746469) (xy 49.228139 -308.796966) (xy 49.197366 -308.843479)
			(xy 49.160149 -308.885016) (xy 49.117281 -308.920691) (xy 49.069675 -308.949745) (xy 49.018346 -308.971557)
			(xy 48.964389 -308.985663) (xy 48.908952 -308.991763) (xy 48.853218 -308.989726) (xy 48.798375 -308.979596)
			(xy 48.745591 -308.961589) (xy 48.695991 -308.936088) (xy 48.650633 -308.903637) (xy 48.610484 -308.864928)
			(xy 48.576398 -308.820785) (xy 48.549102 -308.77215) (xy 48.529179 -308.720059) (xy 48.517053 -308.665622)
			(xy 48.512982 -308.61) (xy 3.175508 -308.61) (xy 3.174999 -308.637886) (xy 3.166879 -308.693062)
			(xy 3.150811 -308.746469) (xy 3.127139 -308.796966) (xy 3.096366 -308.843479) (xy 3.059149 -308.885016)
			(xy 3.016281 -308.920691) (xy 2.968675 -308.949745) (xy 2.917346 -308.971557) (xy 2.863389 -308.985663)
			(xy 2.807952 -308.991763) (xy 2.752218 -308.989726) (xy 2.697375 -308.979596) (xy 2.644591 -308.961589)
			(xy 2.594991 -308.936088) (xy 2.549633 -308.903637) (xy 2.509484 -308.864928) (xy 2.475398 -308.820785)
			(xy 2.448102 -308.77215) (xy 2.428179 -308.720059) (xy 2.416053 -308.665622) (xy 2.411982 -308.61)
			(xy 1.27 -308.61) (xy 1.27 -310.515) (xy 1.650492 -310.515) (xy 1.65096 -310.48763) (xy 1.658778 -310.433451)
			(xy 1.674266 -310.380948) (xy 1.697108 -310.331201) (xy 1.726831 -310.285234) (xy 1.744472 -310.264302)
			(xy 1.750568 -310.25719) (xy 1.756918 -310.240172) (xy 1.756918 -310.154828) (xy 1.750568 -310.13781)
			(xy 1.744472 -310.130698) (xy 1.726838 -310.109762) (xy 1.697125 -310.06379) (xy 1.674288 -310.014044)
			(xy 1.658796 -309.961544) (xy 1.650967 -309.907369) (xy 1.650492 -309.88) (xy 1.650978 -309.852749)
			(xy 1.658734 -309.798801) (xy 1.674089 -309.746506) (xy 1.696731 -309.696929) (xy 1.726197 -309.651079)
			(xy 1.761888 -309.609888) (xy 1.803079 -309.574197) (xy 1.848929 -309.544731) (xy 1.898506 -309.522089)
			(xy 1.950801 -309.506734) (xy 2.004749 -309.498978) (xy 2.059251 -309.498978) (xy 2.113199 -309.506734)
			(xy 2.165494 -309.522089) (xy 2.215071 -309.544731) (xy 2.260921 -309.574197) (xy 2.302112 -309.609888)
			(xy 2.337803 -309.651079) (xy 2.367269 -309.696929) (xy 2.389911 -309.746506) (xy 2.405266 -309.798801)
			(xy 2.413022 -309.852749) (xy 2.413508 -309.88) (xy 2.41304 -309.90737) (xy 2.405222 -309.961549)
			(xy 2.389734 -310.014052) (xy 2.366892 -310.063799) (xy 2.337169 -310.109766) (xy 2.319528 -310.130698)
			(xy 2.313432 -310.13781) (xy 2.307082 -310.154828) (xy 2.307082 -310.240172) (xy 2.313432 -310.25719)
			(xy 2.319528 -310.264302) (xy 2.337162 -310.285238) (xy 2.366875 -310.33121) (xy 2.389712 -310.380956)
			(xy 2.405204 -310.433456) (xy 2.413033 -310.487631) (xy 2.413508 -310.515) (xy 49.275492 -310.515)
			(xy 49.27596 -310.48763) (xy 49.283778 -310.433451) (xy 49.299266 -310.380948) (xy 49.322108 -310.331201)
			(xy 49.351831 -310.285234) (xy 49.369472 -310.264302) (xy 49.375568 -310.25719) (xy 49.381918 -310.240172)
			(xy 49.381918 -310.154828) (xy 49.375568 -310.13781) (xy 49.369472 -310.130698) (xy 49.351814 -310.109781)
			(xy 49.322106 -310.063804) (xy 49.299274 -310.014052) (xy 49.283787 -309.961548) (xy 49.275964 -309.90737)
			(xy 49.275492 -309.88) (xy 49.275978 -309.852749) (xy 49.283734 -309.798801) (xy 49.299089 -309.746506)
			(xy 49.321731 -309.696929) (xy 49.351197 -309.651079) (xy 49.386888 -309.609888) (xy 49.428079 -309.574197)
			(xy 49.473929 -309.544731) (xy 49.523506 -309.522089) (xy 49.575801 -309.506734) (xy 49.629749 -309.498978)
			(xy 49.684251 -309.498978) (xy 49.738199 -309.506734) (xy 49.790494 -309.522089) (xy 49.840071 -309.544731)
			(xy 49.885921 -309.574197) (xy 49.927112 -309.609888) (xy 49.962803 -309.651079) (xy 49.992269 -309.696929)
			(xy 50.014911 -309.746506) (xy 50.030266 -309.798801) (xy 50.038022 -309.852749) (xy 50.038508 -309.88)
			(xy 50.03804 -309.90737) (xy 50.030222 -309.961549) (xy 50.014734 -310.014052) (xy 49.991892 -310.063799)
			(xy 49.962169 -310.109766) (xy 49.944528 -310.130698) (xy 49.938432 -310.13781) (xy 49.932082 -310.154828)
			(xy 49.932082 -310.240172) (xy 49.938432 -310.25719) (xy 49.944528 -310.264302) (xy 49.962186 -310.285219)
			(xy 49.991894 -310.331196) (xy 50.014726 -310.380948) (xy 50.030213 -310.433452) (xy 50.038036 -310.48763)
			(xy 50.038508 -310.515) (xy 50.038022 -310.542251) (xy 50.030266 -310.596199) (xy 50.014911 -310.648494)
			(xy 49.992269 -310.698071) (xy 49.962803 -310.743921) (xy 49.927112 -310.785112) (xy 49.885921 -310.820803)
			(xy 49.840071 -310.850269) (xy 49.790494 -310.872911) (xy 49.738199 -310.888266) (xy 49.684251 -310.896022)
			(xy 49.629749 -310.896022) (xy 49.575801 -310.888266) (xy 49.523506 -310.872911) (xy 49.473929 -310.850269)
			(xy 49.428079 -310.820803) (xy 49.386888 -310.785112) (xy 49.351197 -310.743921) (xy 49.321731 -310.698071)
			(xy 49.299089 -310.648494) (xy 49.283734 -310.596199) (xy 49.275978 -310.542251) (xy 49.275492 -310.515)
			(xy 2.413508 -310.515) (xy 2.413022 -310.542251) (xy 2.405266 -310.596199) (xy 2.389911 -310.648494)
			(xy 2.367269 -310.698071) (xy 2.337803 -310.743921) (xy 2.302112 -310.785112) (xy 2.260921 -310.820803)
			(xy 2.215071 -310.850269) (xy 2.165494 -310.872911) (xy 2.113199 -310.888266) (xy 2.059251 -310.896022)
			(xy 2.004749 -310.896022) (xy 1.950801 -310.888266) (xy 1.898506 -310.872911) (xy 1.848929 -310.850269)
			(xy 1.803079 -310.820803) (xy 1.761888 -310.785112) (xy 1.726197 -310.743921) (xy 1.696731 -310.698071)
			(xy 1.674089 -310.648494) (xy 1.658734 -310.596199) (xy 1.650978 -310.542251) (xy 1.650492 -310.515)
			(xy 1.27 -310.515) (xy 1.27 -311.8739) (xy 2.704082 -311.8739) (xy 2.708153 -311.818278) (xy 2.720279 -311.763841)
			(xy 2.740202 -311.71175) (xy 2.767498 -311.663115) (xy 2.801584 -311.618972) (xy 2.841733 -311.580263)
			(xy 2.887091 -311.547812) (xy 2.936691 -311.522311) (xy 2.989475 -311.504304) (xy 3.044318 -311.494174)
			(xy 3.100052 -311.492137) (xy 3.155489 -311.498237) (xy 3.209446 -311.512343) (xy 3.260775 -311.534155)
			(xy 3.308381 -311.563209) (xy 3.351249 -311.598884) (xy 3.388466 -311.640421) (xy 3.419239 -311.686934)
			(xy 3.442911 -311.737431) (xy 3.458979 -311.790838) (xy 3.467099 -311.846014) (xy 3.467608 -311.8739)
			(xy 3.467099 -311.901786) (xy 3.458979 -311.956962) (xy 3.442911 -312.010369) (xy 3.419239 -312.060866)
			(xy 3.388466 -312.107379) (xy 3.351249 -312.148916) (xy 3.308381 -312.184591) (xy 3.260775 -312.213645)
			(xy 3.209446 -312.235457) (xy 3.155489 -312.249563) (xy 3.100052 -312.255663) (xy 3.044318 -312.253626)
			(xy 2.989475 -312.243496) (xy 2.936691 -312.225489) (xy 2.887091 -312.199988) (xy 2.841733 -312.167537)
			(xy 2.801584 -312.128828) (xy 2.767498 -312.084685) (xy 2.740202 -312.03605) (xy 2.720279 -311.983959)
			(xy 2.708153 -311.929522) (xy 2.704082 -311.8739) (xy 1.27 -311.8739) (xy 1.27 -312.436948) (xy 41.147996 -312.436948)
			(xy 41.147996 -312.352252) (xy 41.156047 -312.267938) (xy 41.172076 -312.184772) (xy 41.195937 -312.103505)
			(xy 41.227416 -312.024875) (xy 41.266227 -311.949594) (xy 41.312017 -311.878342) (xy 41.364373 -311.811766)
			(xy 41.422821 -311.750468) (xy 41.486831 -311.695003) (xy 41.555823 -311.645874) (xy 41.629173 -311.603525)
			(xy 41.706216 -311.568341) (xy 41.786255 -311.540639) (xy 41.868564 -311.520671) (xy 41.952399 -311.508618)
			(xy 42.037 -311.504588) (xy 42.121601 -311.508618) (xy 42.205436 -311.520671) (xy 42.287745 -311.540639)
			(xy 42.367784 -311.568341) (xy 42.444827 -311.603525) (xy 42.518177 -311.645874) (xy 42.587169 -311.695003)
			(xy 42.651179 -311.750468) (xy 42.709627 -311.811766) (xy 42.761983 -311.878342) (xy 42.807773 -311.949594)
			(xy 42.846584 -312.024875) (xy 42.878063 -312.103505) (xy 42.885226 -312.1279) (xy 45.998382 -312.1279)
			(xy 46.002453 -312.072278) (xy 46.014579 -312.017841) (xy 46.034502 -311.96575) (xy 46.061798 -311.917115)
			(xy 46.095884 -311.872972) (xy 46.136033 -311.834263) (xy 46.181391 -311.801812) (xy 46.230991 -311.776311)
			(xy 46.283775 -311.758304) (xy 46.338618 -311.748174) (xy 46.394352 -311.746137) (xy 46.449789 -311.752237)
			(xy 46.503746 -311.766343) (xy 46.555075 -311.788155) (xy 46.602681 -311.817209) (xy 46.645549 -311.852884)
			(xy 46.682766 -311.894421) (xy 46.713539 -311.940934) (xy 46.737211 -311.991431) (xy 46.753279 -312.044838)
			(xy 46.761399 -312.100014) (xy 46.761908 -312.1279) (xy 46.761399 -312.155786) (xy 46.753279 -312.210962)
			(xy 46.737211 -312.264369) (xy 46.713539 -312.314866) (xy 46.682766 -312.361379) (xy 46.645549 -312.402916)
			(xy 46.602681 -312.438591) (xy 46.555075 -312.467645) (xy 46.503746 -312.489457) (xy 46.449789 -312.503563)
			(xy 46.394352 -312.509663) (xy 46.338618 -312.507626) (xy 46.283775 -312.497496) (xy 46.230991 -312.479489)
			(xy 46.181391 -312.453988) (xy 46.136033 -312.421537) (xy 46.095884 -312.382828) (xy 46.061798 -312.338685)
			(xy 46.034502 -312.29005) (xy 46.014579 -312.237959) (xy 46.002453 -312.183522) (xy 45.998382 -312.1279)
			(xy 42.885226 -312.1279) (xy 42.901924 -312.184772) (xy 42.917953 -312.267938) (xy 42.926004 -312.352252)
			(xy 42.926508 -312.3946) (xy 42.926004 -312.436948) (xy 42.917953 -312.521262) (xy 42.901924 -312.604428)
			(xy 42.878063 -312.685695) (xy 42.846584 -312.764325) (xy 42.807773 -312.839606) (xy 42.761983 -312.910858)
			(xy 42.709627 -312.977434) (xy 42.651179 -313.038732) (xy 42.587169 -313.094197) (xy 42.518177 -313.143326)
			(xy 42.444827 -313.185675) (xy 42.367784 -313.220859) (xy 42.287745 -313.248561) (xy 42.205436 -313.268529)
			(xy 42.121601 -313.280582) (xy 42.037 -313.284613) (xy 41.952399 -313.280582) (xy 41.868564 -313.268529)
			(xy 41.786255 -313.248561) (xy 41.706216 -313.220859) (xy 41.629173 -313.185675) (xy 41.555823 -313.143326)
			(xy 41.486831 -313.094197) (xy 41.422821 -313.038732) (xy 41.364373 -312.977434) (xy 41.312017 -312.910858)
			(xy 41.266227 -312.839606) (xy 41.227416 -312.764325) (xy 41.195937 -312.685695) (xy 41.172076 -312.604428)
			(xy 41.156047 -312.521262) (xy 41.147996 -312.436948) (xy 1.27 -312.436948) (xy 1.27 -313.4741) (xy 2.219196 -313.4741)
			(xy 2.223267 -313.418478) (xy 2.235393 -313.364041) (xy 2.255316 -313.31195) (xy 2.282612 -313.263315)
			(xy 2.316698 -313.219172) (xy 2.356847 -313.180463) (xy 2.402205 -313.148012) (xy 2.451805 -313.122511)
			(xy 2.504589 -313.104504) (xy 2.559432 -313.094374) (xy 2.615166 -313.092337) (xy 2.670603 -313.098437)
			(xy 2.72456 -313.112543) (xy 2.775889 -313.134355) (xy 2.823495 -313.163409) (xy 2.866363 -313.199084)
			(xy 2.90358 -313.240621) (xy 2.934353 -313.287134) (xy 2.958025 -313.337631) (xy 2.974093 -313.391038)
			(xy 2.982213 -313.446214) (xy 2.982722 -313.4741) (xy 2.982213 -313.501986) (xy 2.974093 -313.557162)
			(xy 2.958025 -313.610569) (xy 2.934353 -313.661066) (xy 2.90358 -313.707579) (xy 2.885193 -313.7281)
			(xy 46.034196 -313.7281) (xy 46.038267 -313.672478) (xy 46.050393 -313.618041) (xy 46.070316 -313.56595)
			(xy 46.097612 -313.517315) (xy 46.131698 -313.473172) (xy 46.171847 -313.434463) (xy 46.217205 -313.402012)
			(xy 46.266805 -313.376511) (xy 46.319589 -313.358504) (xy 46.374432 -313.348374) (xy 46.430166 -313.346337)
			(xy 46.485603 -313.352437) (xy 46.53956 -313.366543) (xy 46.590889 -313.388355) (xy 46.638495 -313.417409)
			(xy 46.681363 -313.453084) (xy 46.71858 -313.494621) (xy 46.749353 -313.541134) (xy 46.773025 -313.591631)
			(xy 46.789093 -313.645038) (xy 46.797213 -313.700214) (xy 46.797722 -313.7281) (xy 46.797213 -313.755986)
			(xy 46.789093 -313.811162) (xy 46.773025 -313.864569) (xy 46.749353 -313.915066) (xy 46.71858 -313.961579)
			(xy 46.681363 -314.003116) (xy 46.638495 -314.038791) (xy 46.590889 -314.067845) (xy 46.53956 -314.089657)
			(xy 46.485603 -314.103763) (xy 46.430166 -314.109863) (xy 46.374432 -314.107826) (xy 46.319589 -314.097696)
			(xy 46.266805 -314.079689) (xy 46.217205 -314.054188) (xy 46.171847 -314.021737) (xy 46.131698 -313.983028)
			(xy 46.097612 -313.938885) (xy 46.070316 -313.89025) (xy 46.050393 -313.838159) (xy 46.038267 -313.783722)
			(xy 46.034196 -313.7281) (xy 2.885193 -313.7281) (xy 2.866363 -313.749116) (xy 2.823495 -313.784791)
			(xy 2.775889 -313.813845) (xy 2.72456 -313.835657) (xy 2.670603 -313.849763) (xy 2.615166 -313.855863)
			(xy 2.559432 -313.853826) (xy 2.504589 -313.843696) (xy 2.451805 -313.825689) (xy 2.402205 -313.800188)
			(xy 2.356847 -313.767737) (xy 2.316698 -313.729028) (xy 2.282612 -313.684885) (xy 2.255316 -313.63625)
			(xy 2.235393 -313.584159) (xy 2.223267 -313.529722) (xy 2.219196 -313.4741) (xy 1.27 -313.4741) (xy 1.27 -314.198)
			(xy 5.586982 -314.198) (xy 5.591053 -314.142378) (xy 5.603179 -314.087941) (xy 5.623102 -314.03585)
			(xy 5.650398 -313.987215) (xy 5.684484 -313.943072) (xy 5.724633 -313.904363) (xy 5.769991 -313.871912)
			(xy 5.819591 -313.846411) (xy 5.872375 -313.828404) (xy 5.927218 -313.818274) (xy 5.982952 -313.816237)
			(xy 6.038389 -313.822337) (xy 6.092346 -313.836443) (xy 6.143675 -313.858255) (xy 6.191281 -313.887309)
			(xy 6.234149 -313.922984) (xy 6.271366 -313.964521) (xy 6.302139 -314.011034) (xy 6.325811 -314.061531)
			(xy 6.341879 -314.114938) (xy 6.349999 -314.170114) (xy 6.350508 -314.198) (xy 6.349999 -314.225886)
			(xy 6.341879 -314.281062) (xy 6.325811 -314.334469) (xy 6.302139 -314.384966) (xy 6.271366 -314.431479)
			(xy 6.234149 -314.473016) (xy 6.191281 -314.508691) (xy 6.143675 -314.537745) (xy 6.092346 -314.559557)
			(xy 6.038389 -314.573663) (xy 5.982952 -314.579763) (xy 5.927218 -314.577726) (xy 5.872375 -314.567596)
			(xy 5.819591 -314.549589) (xy 5.769991 -314.524088) (xy 5.724633 -314.491637) (xy 5.684484 -314.452928)
			(xy 5.650398 -314.408785) (xy 5.623102 -314.36015) (xy 5.603179 -314.308059) (xy 5.591053 -314.253622)
			(xy 5.586982 -314.198) (xy 1.27 -314.198) (xy 1.27 -314.833) (xy 2.411982 -314.833) (xy 2.416053 -314.777378)
			(xy 2.428179 -314.722941) (xy 2.448102 -314.67085) (xy 2.475398 -314.622215) (xy 2.509484 -314.578072)
			(xy 2.549633 -314.539363) (xy 2.594991 -314.506912) (xy 2.644591 -314.481411) (xy 2.697375 -314.463404)
			(xy 2.752218 -314.453274) (xy 2.807952 -314.451237) (xy 2.863389 -314.457337) (xy 2.917346 -314.471443)
			(xy 2.968675 -314.493255) (xy 3.016281 -314.522309) (xy 3.059149 -314.557984) (xy 3.096366 -314.599521)
			(xy 3.127139 -314.646034) (xy 3.150811 -314.696531) (xy 3.166879 -314.749938) (xy 3.174999 -314.805114)
			(xy 3.175508 -314.833) (xy 4.570982 -314.833) (xy 4.575053 -314.777378) (xy 4.587179 -314.722941)
			(xy 4.607102 -314.67085) (xy 4.634398 -314.622215) (xy 4.668484 -314.578072) (xy 4.708633 -314.539363)
			(xy 4.753991 -314.506912) (xy 4.803591 -314.481411) (xy 4.856375 -314.463404) (xy 4.911218 -314.453274)
			(xy 4.966952 -314.451237) (xy 5.022389 -314.457337) (xy 5.076346 -314.471443) (xy 5.127675 -314.493255)
			(xy 5.175281 -314.522309) (xy 5.218149 -314.557984) (xy 5.255366 -314.599521) (xy 5.286139 -314.646034)
			(xy 5.309811 -314.696531) (xy 5.325879 -314.749938) (xy 5.333999 -314.805114) (xy 5.334508 -314.833)
			(xy 5.333999 -314.860886) (xy 5.325879 -314.916062) (xy 5.309811 -314.969469) (xy 5.286139 -315.019966)
			(xy 5.255366 -315.066479) (xy 5.236979 -315.087) (xy 46.226982 -315.087) (xy 46.231053 -315.031378)
			(xy 46.243179 -314.976941) (xy 46.263102 -314.92485) (xy 46.290398 -314.876215) (xy 46.324484 -314.832072)
			(xy 46.364633 -314.793363) (xy 46.409991 -314.760912) (xy 46.459591 -314.735411) (xy 46.512375 -314.717404)
			(xy 46.567218 -314.707274) (xy 46.622952 -314.705237) (xy 46.678389 -314.711337) (xy 46.732346 -314.725443)
			(xy 46.783675 -314.747255) (xy 46.831281 -314.776309) (xy 46.874149 -314.811984) (xy 46.911366 -314.853521)
			(xy 46.942139 -314.900034) (xy 46.965811 -314.950531) (xy 46.981879 -315.003938) (xy 46.989999 -315.059114)
			(xy 46.990508 -315.087) (xy 48.385982 -315.087) (xy 48.390053 -315.031378) (xy 48.402179 -314.976941)
			(xy 48.422102 -314.92485) (xy 48.449398 -314.876215) (xy 48.483484 -314.832072) (xy 48.523633 -314.793363)
			(xy 48.568991 -314.760912) (xy 48.618591 -314.735411) (xy 48.671375 -314.717404) (xy 48.726218 -314.707274)
			(xy 48.781952 -314.705237) (xy 48.837389 -314.711337) (xy 48.891346 -314.725443) (xy 48.942675 -314.747255)
			(xy 48.990281 -314.776309) (xy 49.033149 -314.811984) (xy 49.070366 -314.853521) (xy 49.101139 -314.900034)
			(xy 49.124811 -314.950531) (xy 49.140879 -315.003938) (xy 49.148999 -315.059114) (xy 49.149508 -315.087)
			(xy 49.148999 -315.114886) (xy 49.140879 -315.170062) (xy 49.124811 -315.223469) (xy 49.101139 -315.273966)
			(xy 49.070366 -315.320479) (xy 49.033149 -315.362016) (xy 48.990281 -315.397691) (xy 48.942675 -315.426745)
			(xy 48.891346 -315.448557) (xy 48.837389 -315.462663) (xy 48.781952 -315.468763) (xy 48.726218 -315.466726)
			(xy 48.671375 -315.456596) (xy 48.618591 -315.438589) (xy 48.568991 -315.413088) (xy 48.523633 -315.380637)
			(xy 48.483484 -315.341928) (xy 48.449398 -315.297785) (xy 48.422102 -315.24915) (xy 48.402179 -315.197059)
			(xy 48.390053 -315.142622) (xy 48.385982 -315.087) (xy 46.990508 -315.087) (xy 46.989999 -315.114886)
			(xy 46.981879 -315.170062) (xy 46.965811 -315.223469) (xy 46.942139 -315.273966) (xy 46.911366 -315.320479)
			(xy 46.874149 -315.362016) (xy 46.831281 -315.397691) (xy 46.783675 -315.426745) (xy 46.732346 -315.448557)
			(xy 46.678389 -315.462663) (xy 46.622952 -315.468763) (xy 46.567218 -315.466726) (xy 46.512375 -315.456596)
			(xy 46.459591 -315.438589) (xy 46.409991 -315.413088) (xy 46.364633 -315.380637) (xy 46.324484 -315.341928)
			(xy 46.290398 -315.297785) (xy 46.263102 -315.24915) (xy 46.243179 -315.197059) (xy 46.231053 -315.142622)
			(xy 46.226982 -315.087) (xy 5.236979 -315.087) (xy 5.218149 -315.108016) (xy 5.175281 -315.143691)
			(xy 5.127675 -315.172745) (xy 5.076346 -315.194557) (xy 5.022389 -315.208663) (xy 4.966952 -315.214763)
			(xy 4.911218 -315.212726) (xy 4.856375 -315.202596) (xy 4.803591 -315.184589) (xy 4.753991 -315.159088)
			(xy 4.708633 -315.126637) (xy 4.668484 -315.087928) (xy 4.634398 -315.043785) (xy 4.607102 -314.99515)
			(xy 4.587179 -314.943059) (xy 4.575053 -314.888622) (xy 4.570982 -314.833) (xy 3.175508 -314.833)
			(xy 3.174999 -314.860886) (xy 3.166879 -314.916062) (xy 3.150811 -314.969469) (xy 3.127139 -315.019966)
			(xy 3.096366 -315.066479) (xy 3.059149 -315.108016) (xy 3.016281 -315.143691) (xy 2.968675 -315.172745)
			(xy 2.917346 -315.194557) (xy 2.863389 -315.208663) (xy 2.807952 -315.214763) (xy 2.752218 -315.212726)
			(xy 2.697375 -315.202596) (xy 2.644591 -315.184589) (xy 2.594991 -315.159088) (xy 2.549633 -315.126637)
			(xy 2.509484 -315.087928) (xy 2.475398 -315.043785) (xy 2.448102 -314.99515) (xy 2.428179 -314.943059)
			(xy 2.416053 -314.888622) (xy 2.411982 -314.833) (xy 1.27 -314.833) (xy 1.27 -327.01219) (xy 20.643082 -327.01219)
			(xy 20.643082 -326.807686) (xy 20.651111 -326.603338) (xy 20.667156 -326.399464) (xy 20.691193 -326.196376)
			(xy 20.723185 -325.994389) (xy 20.763082 -325.793814) (xy 20.810822 -325.594959) (xy 20.866333 -325.398132)
			(xy 20.929529 -325.203637) (xy 21.000311 -325.011772) (xy 21.078572 -324.822834) (xy 21.16419 -324.637114)
			(xy 21.257033 -324.454899) (xy 21.356959 -324.276469) (xy 21.463812 -324.1021) (xy 21.577429 -323.932061)
			(xy 21.697634 -323.766613) (xy 21.824242 -323.606011) (xy 21.957057 -323.450505) (xy 22.095875 -323.300332)
			(xy 22.240482 -323.155725) (xy 22.390655 -323.016907) (xy 22.546161 -322.884092) (xy 22.706763 -322.757484)
			(xy 22.872211 -322.637279) (xy 23.04225 -322.523662) (xy 23.216619 -322.416809) (xy 23.395049 -322.316883)
			(xy 23.577264 -322.22404) (xy 23.762984 -322.138422) (xy 23.951922 -322.060161) (xy 24.143787 -321.989379)
			(xy 24.338282 -321.926183) (xy 24.535109 -321.870672) (xy 24.733964 -321.822932) (xy 24.934539 -321.783035)
			(xy 25.136526 -321.751043) (xy 25.339614 -321.727006) (xy 25.543488 -321.710961) (xy 25.747836 -321.702932)
			(xy 25.95234 -321.702932) (xy 26.156688 -321.710961) (xy 26.360562 -321.727006) (xy 26.56365 -321.751043)
			(xy 26.765637 -321.783035) (xy 26.966212 -321.822932) (xy 27.165067 -321.870672) (xy 27.361894 -321.926183)
			(xy 27.556389 -321.989379) (xy 27.748254 -322.060161) (xy 27.937192 -322.138422) (xy 28.122912 -322.22404)
			(xy 28.305127 -322.316883) (xy 28.483557 -322.416809) (xy 28.657926 -322.523662) (xy 28.827965 -322.637279)
			(xy 28.993413 -322.757484) (xy 29.154015 -322.884092) (xy 29.309521 -323.016907) (xy 29.459694 -323.155725)
			(xy 29.604301 -323.300332) (xy 29.743119 -323.450505) (xy 29.875934 -323.606011) (xy 30.002542 -323.766613)
			(xy 30.122747 -323.932061) (xy 30.236364 -324.1021) (xy 30.343217 -324.276469) (xy 30.443143 -324.454899)
			(xy 30.535986 -324.637114) (xy 30.621604 -324.822834) (xy 30.699865 -325.011772) (xy 30.770647 -325.203637)
			(xy 30.833843 -325.398132) (xy 30.889354 -325.594959) (xy 30.937094 -325.793814) (xy 30.976991 -325.994389)
			(xy 31.008983 -326.196376) (xy 31.03302 -326.399464) (xy 31.049065 -326.603338) (xy 31.057094 -326.807686)
			(xy 31.057596 -326.909938) (xy 31.057094 -327.01219) (xy 31.049065 -327.216538) (xy 31.03302 -327.420412)
			(xy 31.008983 -327.6235) (xy 30.976991 -327.825487) (xy 30.937094 -328.026062) (xy 30.889354 -328.224917)
			(xy 30.833843 -328.421744) (xy 30.770647 -328.616239) (xy 30.699865 -328.808104) (xy 30.621604 -328.997042)
			(xy 30.535986 -329.182762) (xy 30.443143 -329.364977) (xy 30.343217 -329.543407) (xy 30.236364 -329.717776)
			(xy 30.122747 -329.887815) (xy 30.002542 -330.053263) (xy 29.875934 -330.213865) (xy 29.743119 -330.369371)
			(xy 29.604301 -330.519544) (xy 29.459694 -330.664151) (xy 29.309521 -330.802969) (xy 29.154015 -330.935784)
			(xy 28.993413 -331.062392) (xy 28.827965 -331.182597) (xy 28.657926 -331.296214) (xy 28.483557 -331.403067)
			(xy 28.305127 -331.502993) (xy 28.122912 -331.595836) (xy 27.937192 -331.681454) (xy 27.748254 -331.759715)
			(xy 27.556389 -331.830497) (xy 27.361894 -331.893693) (xy 27.165067 -331.949204) (xy 26.966212 -331.996944)
			(xy 26.765637 -332.036841) (xy 26.56365 -332.068833) (xy 26.360562 -332.09287) (xy 26.156688 -332.108915)
			(xy 25.95234 -332.116944) (xy 25.747836 -332.116944) (xy 25.543488 -332.108915) (xy 25.339614 -332.09287)
			(xy 25.136526 -332.068833) (xy 24.934539 -332.036841) (xy 24.733964 -331.996944) (xy 24.535109 -331.949204)
			(xy 24.338282 -331.893693) (xy 24.143787 -331.830497) (xy 23.951922 -331.759715) (xy 23.762984 -331.681454)
			(xy 23.577264 -331.595836) (xy 23.395049 -331.502993) (xy 23.216619 -331.403067) (xy 23.04225 -331.296214)
			(xy 22.872211 -331.182597) (xy 22.706763 -331.062392) (xy 22.546161 -330.935784) (xy 22.390655 -330.802969)
			(xy 22.240482 -330.664151) (xy 22.095875 -330.519544) (xy 21.957057 -330.369371) (xy 21.824242 -330.213865)
			(xy 21.697634 -330.053263) (xy 21.577429 -329.887815) (xy 21.463812 -329.717776) (xy 21.356959 -329.543407)
			(xy 21.257033 -329.364977) (xy 21.16419 -329.182762) (xy 21.078572 -328.997042) (xy 21.000311 -328.808104)
			(xy 20.929529 -328.616239) (xy 20.866333 -328.421744) (xy 20.810822 -328.224917) (xy 20.763082 -328.026062)
			(xy 20.723185 -327.825487) (xy 20.691193 -327.6235) (xy 20.667156 -327.420412) (xy 20.651111 -327.216538)
			(xy 20.643082 -327.01219) (xy 1.27 -327.01219) (xy 1.27 -332.04257) (xy 2.984235 -332.04257) (xy 2.984235 -331.91343)
			(xy 2.992185 -331.784535) (xy 3.008055 -331.656375) (xy 3.031784 -331.529434) (xy 3.063283 -331.404195)
			(xy 3.102432 -331.281132) (xy 3.149083 -331.160713) (xy 3.203058 -331.043394) (xy 3.264153 -330.92962)
			(xy 3.332136 -330.819823) (xy 3.40675 -330.71442) (xy 3.487711 -330.61381) (xy 3.574711 -330.518375)
			(xy 3.667422 -330.428476) (xy 3.765492 -330.344455) (xy 3.868547 -330.266631) (xy 3.976198 -330.195299)
			(xy 4.088037 -330.130729) (xy 4.203638 -330.073167) (xy 4.322563 -330.02283) (xy 4.444362 -329.97991)
			(xy 4.568572 -329.944569) (xy 4.694721 -329.916942) (xy 4.822333 -329.897133) (xy 4.950922 -329.885217)
			(xy 5.08 -329.881241) (xy 5.209078 -329.885217) (xy 5.337667 -329.897133) (xy 5.465279 -329.916942)
			(xy 5.591428 -329.944569) (xy 5.715638 -329.97991) (xy 5.837437 -330.02283) (xy 5.956362 -330.073167)
			(xy 6.071963 -330.130729) (xy 6.183802 -330.195299) (xy 6.291453 -330.266631) (xy 6.394508 -330.344455)
			(xy 6.492578 -330.428476) (xy 6.585289 -330.518375) (xy 6.672289 -330.61381) (xy 6.75325 -330.71442)
			(xy 6.827864 -330.819823) (xy 6.895847 -330.92962) (xy 6.956942 -331.043394) (xy 7.010917 -331.160713)
			(xy 7.057568 -331.281132) (xy 7.096717 -331.404195) (xy 7.128216 -331.529434) (xy 7.151945 -331.656375)
			(xy 7.167815 -331.784535) (xy 7.175765 -331.91343) (xy 7.176262 -331.978) (xy 7.175765 -332.04257)
			(xy 7.167815 -332.171465) (xy 7.151945 -332.299625) (xy 7.128216 -332.426566) (xy 7.096717 -332.551805)
			(xy 7.057568 -332.674868) (xy 7.010917 -332.795287) (xy 6.956942 -332.912606) (xy 6.895847 -333.02638)
			(xy 6.827864 -333.136177) (xy 6.75325 -333.24158) (xy 6.672289 -333.34219) (xy 6.585289 -333.437625)
			(xy 6.492578 -333.527524) (xy 6.394508 -333.611545) (xy 6.291453 -333.689369) (xy 6.183802 -333.760701)
			(xy 6.071963 -333.825271) (xy 5.956362 -333.882833) (xy 5.837437 -333.93317) (xy 5.715638 -333.97609)
			(xy 5.591428 -334.011431) (xy 5.465279 -334.039058) (xy 5.337667 -334.058867) (xy 5.209078 -334.070783)
			(xy 5.08 -334.07476) (xy 4.950922 -334.070783) (xy 4.822333 -334.058867) (xy 4.694721 -334.039058)
			(xy 4.568572 -334.011431) (xy 4.444362 -333.97609) (xy 4.322563 -333.93317) (xy 4.203638 -333.882833)
			(xy 4.088037 -333.825271) (xy 3.976198 -333.760701) (xy 3.868547 -333.689369) (xy 3.765492 -333.611545)
			(xy 3.667422 -333.527524) (xy 3.574711 -333.437625) (xy 3.487711 -333.34219) (xy 3.40675 -333.24158)
			(xy 3.332136 -333.136177) (xy 3.264153 -333.02638) (xy 3.203058 -332.912606) (xy 3.149083 -332.795287)
			(xy 3.102432 -332.674868) (xy 3.063283 -332.551805) (xy 3.031784 -332.426566) (xy 3.008055 -332.299625)
			(xy 2.992185 -332.171465) (xy 2.984235 -332.04257) (xy 1.27 -332.04257) (xy 1.27 -333.000096) (xy 1.270501 -333.074036)
			(xy 1.278507 -333.221699) (xy 1.294496 -333.368713) (xy 1.31842 -333.514645) (xy 1.35021 -333.659067)
			(xy 1.389772 -333.801557) (xy 1.43699 -333.941696) (xy 1.491726 -334.079073) (xy 1.55382 -334.213286)
			(xy 1.623088 -334.34394) (xy 1.699328 -334.470652) (xy 1.782316 -334.593051) (xy 1.87181 -334.710777)
			(xy 1.967545 -334.823485) (xy 2.069242 -334.930846) (xy 2.176603 -335.032543) (xy 2.289311 -335.128278)
			(xy 2.407037 -335.217772) (xy 2.529436 -335.30076) (xy 2.656148 -335.377) (xy 2.786802 -335.446268)
			(xy 2.921015 -335.508362) (xy 3.058392 -335.563098) (xy 3.198531 -335.610316) (xy 3.341021 -335.649878)
			(xy 3.485443 -335.681668) (xy 3.631375 -335.705592) (xy 3.778389 -335.721581) (xy 3.926052 -335.729587)
			(xy 3.999992 -335.730088)
		)
		(stroke
			(width 0)
			(type solid)
		)
		(fill yes)
		(layer "In2.Cu")
		(net "P3V3_AUX")
	)
	(gr_poly
		(pts
			(arc
				(start 47.69993 -336.492088)
				(mid 50.169141 -335.469307)
				(end 51.191922 -333.000096)
			)
			(arc
				(start 51.191922 -3.999992)
				(mid 50.169141 -1.530781)
				(end 47.69993 -0.508)
			)
			(xy 36.950396 -0.508) (xy 35.74796 -1.710436)
			(arc
				(start 35.74796 -10.7442)
				(mid 35.762241 -10.871735)
				(end 35.76701 -10.999978)
			)
			(arc
				(start 35.76701 -10.999978)
				(mid 35.261199 -12.221113)
				(end 34.040064 -12.726924)
			)
			(xy 34.036 -12.726924)
			(arc
				(start 34.036 -13.21562)
				(mid 35.605325 -12.568112)
				(end 36.255706 -10.999978)
			)
			(xy 36.255706 -1.920748) (xy 37.160708 -1.015746)
			(arc
				(start 47.69993 -1.015746)
				(mid 49.810111 -1.889811)
				(end 50.684176 -3.999992)
			)
			(arc
				(start 50.684176 -333.000096)
				(mid 49.810111 -335.110277)
				(end 47.69993 -335.984342)
			)
			(arc
				(start 3.999992 -335.984342)
				(mid 1.889811 -335.110277)
				(end 1.015746 -333.000096)
			)
			(arc
				(start 1.015746 -3.999992)
				(mid 1.889811 -1.889811)
				(end 3.999992 -1.015746)
			)
			(xy 14.539214 -1.015746) (xy 15.444216 -1.920748)
			(arc
				(start 15.444216 -10.999978)
				(mid 16.09074 -12.564247)
				(end 17.653 -13.21562)
			)
			(xy 17.653 -12.7762)
			(arc
				(start 17.603724 -12.726924)
				(mid 16.41855 -12.201662)
				(end 15.93215 -10.999978)
			)
			(arc
				(start 15.93215 -10.999978)
				(mid 15.937108 -10.869173)
				(end 15.951962 -10.73912)
			)
			(xy 15.951962 -1.710436) (xy 14.749526 -0.508)
			(arc
				(start 3.999992 -0.508)
				(mid 1.530781 -1.530781)
				(end 0.508 -3.999992)
			)
			(arc
				(start 0.508 -333.000096)
				(mid 1.530781 -335.469307)
				(end 3.999992 -336.492088)
			)
		)
		(stroke
			(width 0)
			(type solid)
		)
		(fill yes)
		(layer "In3.Cu")
		(net "GND")
	)
	(gr_poly
		(pts
			(xy 4.068318 -335.348072) (xy 4.104132 -335.348834) (xy 8.985504 -335.348834) (xy 9.021318 -335.348072)
			(xy 9.057132 -335.348834) (xy 14.192504 -335.348834) (xy 14.228318 -335.348072) (xy 14.264132 -335.348834)
			(xy 19.272504 -335.348834) (xy 19.308318 -335.348072) (xy 19.344132 -335.348834) (xy 24.352504 -335.348834)
			(xy 24.388318 -335.348072) (xy 24.424132 -335.348834) (xy 29.432504 -335.348834) (xy 29.468318 -335.348072)
			(xy 29.504132 -335.348834) (xy 34.512504 -335.348834) (xy 34.548318 -335.348072) (xy 34.584132 -335.348834)
			(xy 39.592504 -335.348834) (xy 39.628318 -335.348072) (xy 39.664132 -335.348834) (xy 44.672504 -335.348834)
			(xy 44.708318 -335.348072) (xy 44.744132 -335.348834) (xy 44.745148 -335.348834) (xy 47.69993 -335.348834)
			(xy 47.770113 -335.348319) (xy 47.910228 -335.339951) (xy 48.049593 -335.323229) (xy 48.187711 -335.298211)
			(xy 48.324087 -335.264988) (xy 48.458236 -335.223679) (xy 48.589677 -335.17443) (xy 48.717943 -335.117418)
			(xy 48.842573 -335.052847) (xy 48.903128 -335.017364) (xy 48.90516 -335.016094) (xy 48.954944 -334.98536)
			(xy 48.956976 -334.98409) (xy 49.01541 -334.946458) (xy 49.128222 -334.865245) (xy 49.236033 -334.777503)
			(xy 49.338467 -334.683538) (xy 49.435164 -334.583679) (xy 49.525786 -334.478277) (xy 49.610016 -334.3677)
			(xy 49.687559 -334.252335) (xy 49.758144 -334.132586) (xy 49.821522 -334.008872) (xy 49.877474 -333.881627)
			(xy 49.925802 -333.751295) (xy 49.966338 -333.618333) (xy 49.998939 -333.483206) (xy 50.023492 -333.346388)
			(xy 50.03991 -333.208358) (xy 50.048137 -333.069598) (xy 50.048668 -333.000096) (xy 50.048668 -332.559406)
			(xy 50.046636 -332.500986) (xy 50.048668 -332.442566) (xy 50.048668 -327.479406) (xy 50.046636 -327.420986)
			(xy 50.048668 -327.362566) (xy 50.048668 -322.399406) (xy 50.046636 -322.340986) (xy 50.048668 -322.282566)
			(xy 50.048668 -317.319406) (xy 50.046636 -317.260986) (xy 50.048668 -317.202566) (xy 50.048668 -312.239406)
			(xy 50.046636 -312.180986) (xy 50.048668 -312.122566) (xy 50.048668 -311.462674) (xy 50.048032 -311.450733)
			(xy 50.037313 -311.429392) (xy 50.028094 -311.42178) (xy 49.952656 -311.366154) (xy 49.929034 -311.36209)
			(xy 49.91735 -311.365646) (xy 49.875074 -311.378011) (xy 49.788703 -311.395313) (xy 49.701044 -311.403987)
			(xy 49.657 -311.404508) (xy 49.615898 -311.404033) (xy 49.534043 -311.396448) (xy 49.453238 -311.381343)
			(xy 49.374171 -311.358847) (xy 49.297517 -311.329151) (xy 49.22393 -311.292509) (xy 49.154038 -311.249234)
			(xy 49.088437 -311.199694) (xy 49.027687 -311.144313) (xy 48.972306 -311.083563) (xy 48.922766 -311.017962)
			(xy 48.879491 -310.94807) (xy 48.842849 -310.874483) (xy 48.813153 -310.797829) (xy 48.790657 -310.718762)
			(xy 48.775552 -310.637957) (xy 48.767967 -310.556102) (xy 48.767492 -310.515) (xy 48.767903 -310.476711)
			(xy 48.774512 -310.400417) (xy 48.787663 -310.324976) (xy 48.80726 -310.250947) (xy 48.819816 -310.214772)
			(xy 48.822457 -310.206334) (xy 48.822457 -310.188666) (xy 48.819816 -310.180228) (xy 48.807274 -310.14405)
			(xy 48.7877 -310.070018) (xy 48.774556 -309.994578) (xy 48.767938 -309.918288) (xy 48.767492 -309.88)
			(xy 48.768055 -309.835022) (xy 48.777139 -309.745526) (xy 48.795225 -309.657406) (xy 48.808132 -309.614316)
			(xy 48.811434 -309.603648) (xy 48.808894 -309.582566) (xy 48.758348 -309.498238) (xy 48.740822 -309.486046)
			(xy 48.7299 -309.484014) (xy 48.689654 -309.475932) (xy 48.610735 -309.453329) (xy 48.534234 -309.42355)
			(xy 48.460802 -309.386849) (xy 48.391063 -309.343539) (xy 48.325612 -309.293988) (xy 48.265005 -309.238617)
			(xy 48.209757 -309.177897) (xy 48.160339 -309.112345) (xy 48.11717 -309.042519) (xy 48.080619 -308.969013)
			(xy 48.050996 -308.892451) (xy 48.028552 -308.813486) (xy 48.01348 -308.732789) (xy 48.005907 -308.651046)
			(xy 48.005492 -308.61) (xy 48.005996 -308.567652) (xy 48.014047 -308.483338) (xy 48.030076 -308.400172)
			(xy 48.053937 -308.318905) (xy 48.085416 -308.240275) (xy 48.124227 -308.164994) (xy 48.170017 -308.093742)
			(xy 48.222373 -308.027166) (xy 48.280821 -307.965868) (xy 48.344831 -307.910403) (xy 48.413823 -307.861274)
			(xy 48.487173 -307.818925) (xy 48.564216 -307.783741) (xy 48.644255 -307.756039) (xy 48.726564 -307.736071)
			(xy 48.810399 -307.724018) (xy 48.895 -307.719988) (xy 48.979601 -307.724018) (xy 49.063436 -307.736071)
			(xy 49.145745 -307.756039) (xy 49.225784 -307.783741) (xy 49.302827 -307.818925) (xy 49.376177 -307.861274)
			(xy 49.445169 -307.910403) (xy 49.509179 -307.965868) (xy 49.567627 -308.027166) (xy 49.619983 -308.093742)
			(xy 49.665773 -308.164994) (xy 49.704584 -308.240275) (xy 49.736063 -308.318905) (xy 49.759924 -308.400172)
			(xy 49.775953 -308.483338) (xy 49.784004 -308.567652) (xy 49.784508 -308.61) (xy 49.783945 -308.654978)
			(xy 49.774861 -308.744474) (xy 49.756775 -308.832594) (xy 49.743868 -308.875684) (xy 49.740566 -308.886352)
			(xy 49.743106 -308.907434) (xy 49.793652 -308.991762) (xy 49.811178 -309.003954) (xy 49.8221 -309.005986)
			(xy 49.84618 -309.010679) (xy 49.893831 -309.022372) (xy 49.91735 -309.029354) (xy 49.929034 -309.03291)
			(xy 49.952656 -309.028846) (xy 50.028094 -308.97322) (xy 50.037324 -308.965611) (xy 50.048063 -308.944272)
			(xy 50.048668 -308.932326) (xy 50.048668 -307.159406) (xy 50.046636 -307.100986) (xy 50.048668 -307.042566)
			(xy 50.048668 -302.079406) (xy 50.046636 -302.020986) (xy 50.048668 -301.962566) (xy 50.048668 -296.999406)
			(xy 50.046636 -296.940986) (xy 50.048668 -296.882566) (xy 50.048668 -291.919406) (xy 50.046636 -291.860986)
			(xy 50.048668 -291.802566) (xy 50.048668 -286.839406) (xy 50.046636 -286.780986) (xy 50.048668 -286.722566)
			(xy 50.048668 -281.759406) (xy 50.046636 -281.700986) (xy 50.048668 -281.642566) (xy 50.048668 -276.679406)
			(xy 50.046636 -276.620986) (xy 50.048668 -276.562566) (xy 50.048668 -271.599406) (xy 50.046636 -271.540986)
			(xy 50.048668 -271.482566) (xy 50.048668 -266.519406) (xy 50.046636 -266.460986) (xy 50.048668 -266.402566)
			(xy 50.048668 -261.439406) (xy 50.046636 -261.380986) (xy 50.048668 -261.322566) (xy 50.048668 -256.359406)
			(xy 50.046636 -256.300986) (xy 50.048668 -256.242566) (xy 50.048668 -251.279406) (xy 50.046636 -251.220986)
			(xy 50.048668 -251.162566) (xy 50.048668 -246.199406) (xy 50.046636 -246.140986) (xy 50.048668 -246.082566)
			(xy 50.048668 -240.611406) (xy 50.046636 -240.552986) (xy 50.048668 -240.494566) (xy 50.048668 -236.039406)
			(xy 50.046636 -235.980986) (xy 50.048668 -235.922566) (xy 50.048668 -230.959406) (xy 50.046636 -230.900986)
			(xy 50.048668 -230.842566) (xy 50.048668 -229.070662) (xy 50.048198 -229.060759) (xy 50.040705 -229.042424)
			(xy 50.026842 -229.028278) (xy 50.017934 -229.023926) (xy 49.918112 -228.981) (xy 49.888648 -228.98608)
			(xy 49.877472 -228.996748) (xy 49.846538 -229.025264) (xy 49.780165 -229.076973) (xy 49.709206 -229.122184)
			(xy 49.634296 -229.160494) (xy 49.556103 -229.19156) (xy 49.475327 -229.215105) (xy 49.392688 -229.230918)
			(xy 49.308925 -229.238858) (xy 49.266856 -229.239318) (xy 49.225755 -229.238841) (xy 49.143903 -229.231253)
			(xy 49.0631 -229.216145) (xy 48.984037 -229.193646) (xy 48.907386 -229.163948) (xy 48.833802 -229.127305)
			(xy 48.763913 -229.084029) (xy 48.698315 -229.034489) (xy 48.637568 -228.979108) (xy 48.582189 -228.918359)
			(xy 48.532652 -228.852759) (xy 48.489379 -228.782868) (xy 48.452738 -228.709283) (xy 48.423043 -228.632631)
			(xy 48.400547 -228.553566) (xy 48.385442 -228.472763) (xy 48.377857 -228.390911) (xy 48.377348 -228.34981)
			(xy 48.377932 -228.303414) (xy 48.387565 -228.211124) (xy 48.406758 -228.120338) (xy 48.435303 -228.032046)
			(xy 48.453548 -227.989384) (xy 48.457369 -227.979444) (xy 48.457372 -227.958174) (xy 48.453548 -227.948236)
			(xy 48.435309 -227.905572) (xy 48.406768 -227.817278) (xy 48.387569 -227.726495) (xy 48.377923 -227.634206)
			(xy 48.377348 -227.58781) (xy 48.377932 -227.541414) (xy 48.387565 -227.449124) (xy 48.406758 -227.358338)
			(xy 48.435303 -227.270046) (xy 48.453548 -227.227384) (xy 48.457369 -227.217444) (xy 48.457372 -227.196174)
			(xy 48.453548 -227.186236) (xy 48.435309 -227.143572) (xy 48.406768 -227.055278) (xy 48.387569 -226.964495)
			(xy 48.377923 -226.872206) (xy 48.377348 -226.82581) (xy 48.377932 -226.779414) (xy 48.387565 -226.687124)
			(xy 48.406758 -226.596338) (xy 48.435303 -226.508046) (xy 48.453548 -226.465384) (xy 48.457369 -226.455444)
			(xy 48.457372 -226.434174) (xy 48.453548 -226.424236) (xy 48.435309 -226.381572) (xy 48.406768 -226.293278)
			(xy 48.387569 -226.202495) (xy 48.377923 -226.110206) (xy 48.377348 -226.06381) (xy 48.377932 -226.017414)
			(xy 48.387565 -225.925124) (xy 48.406758 -225.834338) (xy 48.435303 -225.746046) (xy 48.453548 -225.703384)
			(xy 48.457369 -225.693444) (xy 48.457372 -225.672174) (xy 48.453548 -225.662236) (xy 48.435309 -225.619572)
			(xy 48.406768 -225.531278) (xy 48.387569 -225.440495) (xy 48.377923 -225.348206) (xy 48.377348 -225.30181)
			(xy 48.377822 -225.260706) (xy 48.385406 -225.17885) (xy 48.40051 -225.098042) (xy 48.423006 -225.018973)
			(xy 48.452701 -224.942317) (xy 48.489342 -224.868727) (xy 48.532617 -224.798832) (xy 48.582156 -224.733228)
			(xy 48.637537 -224.672475) (xy 48.698287 -224.617091) (xy 48.763888 -224.567548) (xy 48.83378 -224.524269)
			(xy 48.907367 -224.487623) (xy 48.984022 -224.457923) (xy 49.06309 -224.435423) (xy 49.143896 -224.420314)
			(xy 49.225752 -224.412725) (xy 49.266856 -224.412302) (xy 49.308923 -224.412794) (xy 49.392682 -224.420741)
			(xy 49.475316 -224.436557) (xy 49.556089 -224.460102) (xy 49.634279 -224.491166) (xy 49.709188 -224.529471)
			(xy 49.780147 -224.574676) (xy 49.846522 -224.626376) (xy 49.877472 -224.654872) (xy 49.888648 -224.66554)
			(xy 49.918112 -224.67062) (xy 50.017934 -224.627694) (xy 50.02686 -224.623362) (xy 50.040754 -224.609225)
			(xy 50.048234 -224.59087) (xy 50.048668 -224.580958) (xy 50.048668 -220.799406) (xy 50.046636 -220.740986)
			(xy 50.048668 -220.682566) (xy 50.048668 -215.719406) (xy 50.046636 -215.660986) (xy 50.048668 -215.602566)
			(xy 50.048668 -210.639406) (xy 50.046636 -210.580986) (xy 50.048668 -210.522566) (xy 50.048668 -205.559406)
			(xy 50.046636 -205.500986) (xy 50.048668 -205.442566) (xy 50.048668 -200.479406) (xy 50.046636 -200.420986)
			(xy 50.048668 -200.362566) (xy 50.048668 -195.399406) (xy 50.046636 -195.340986) (xy 50.048668 -195.282566)
			(xy 50.048668 -192.03416) (xy 50.048398 -192.025629) (xy 50.042873 -192.00949) (xy 50.032322 -191.996086)
			(xy 50.0253 -191.991234) (xy 49.941988 -191.938148) (xy 49.916334 -191.93637) (xy 49.904396 -191.941958)
			(xy 49.871122 -191.956436) (xy 49.861949 -191.960672) (xy 49.847672 -191.974949) (xy 49.843436 -191.984122)
			(xy 49.826236 -192.024156) (xy 49.785108 -192.100977) (xy 49.736664 -192.173407) (xy 49.681369 -192.240753)
			(xy 49.619753 -192.302369) (xy 49.552407 -192.357664) (xy 49.479977 -192.406108) (xy 49.403156 -192.447236)
			(xy 49.363122 -192.464436) (xy 49.353949 -192.468672) (xy 49.339672 -192.482949) (xy 49.335436 -192.492122)
			(xy 49.318236 -192.532156) (xy 49.277108 -192.608977) (xy 49.228664 -192.681407) (xy 49.173369 -192.748753)
			(xy 49.111753 -192.810369) (xy 49.044407 -192.865664) (xy 48.971977 -192.914108) (xy 48.895156 -192.955236)
			(xy 48.855122 -192.972436) (xy 48.845949 -192.976672) (xy 48.831672 -192.990949) (xy 48.827436 -193.000122)
			(xy 48.810205 -193.040216) (xy 48.768998 -193.117147) (xy 48.720455 -193.189672) (xy 48.665044 -193.257096)
			(xy 48.603295 -193.318769) (xy 48.535805 -193.374099) (xy 48.46322 -193.422554) (xy 48.386239 -193.463668)
			(xy 48.305602 -193.497045) (xy 48.222084 -193.522366) (xy 48.136488 -193.539386) (xy 48.049636 -193.547942)
			(xy 48.006 -193.548508) (xy 47.964898 -193.548033) (xy 47.883043 -193.540448) (xy 47.802238 -193.525343)
			(xy 47.723171 -193.502847) (xy 47.646517 -193.473151) (xy 47.57293 -193.436509) (xy 47.503038 -193.393234)
			(xy 47.437437 -193.343694) (xy 47.376687 -193.288313) (xy 47.321306 -193.227563) (xy 47.271766 -193.161962)
			(xy 47.228491 -193.09207) (xy 47.191849 -193.018483) (xy 47.162153 -192.941829) (xy 47.139657 -192.862762)
			(xy 47.124552 -192.781957) (xy 47.116967 -192.700102) (xy 47.116492 -192.659) (xy 47.117021 -192.615361)
			(xy 47.125562 -192.528501) (xy 47.14257 -192.442896) (xy 47.167884 -192.359368) (xy 47.201258 -192.278723)
			(xy 47.242372 -192.201734) (xy 47.29083 -192.129144) (xy 47.346167 -192.06165) (xy 47.407849 -191.999902)
			(xy 47.475284 -191.944494) (xy 47.547823 -191.895958) (xy 47.624767 -191.854762) (xy 47.664878 -191.837564)
			(xy 47.674051 -191.833328) (xy 47.688328 -191.819051) (xy 47.692564 -191.809878) (xy 47.709764 -191.769844)
			(xy 47.750892 -191.693023) (xy 47.799336 -191.620593) (xy 47.854631 -191.553247) (xy 47.916247 -191.491631)
			(xy 47.983593 -191.436336) (xy 48.056023 -191.387892) (xy 48.132844 -191.346764) (xy 48.172878 -191.329564)
			(xy 48.182051 -191.325328) (xy 48.196328 -191.311051) (xy 48.200564 -191.301878) (xy 48.217764 -191.261844)
			(xy 48.258892 -191.185023) (xy 48.307336 -191.112593) (xy 48.362631 -191.045247) (xy 48.424247 -190.983631)
			(xy 48.491593 -190.928336) (xy 48.564023 -190.879892) (xy 48.640844 -190.838764) (xy 48.680878 -190.821564)
			(xy 48.690051 -190.817328) (xy 48.704328 -190.803051) (xy 48.708564 -190.793878) (xy 48.725795 -190.753784)
			(xy 48.767002 -190.676853) (xy 48.815545 -190.604328) (xy 48.870956 -190.536904) (xy 48.932705 -190.475231)
			(xy 49.000195 -190.419901) (xy 49.07278 -190.371446) (xy 49.149761 -190.330332) (xy 49.230398 -190.296955)
			(xy 49.313916 -190.271634) (xy 49.399512 -190.254614) (xy 49.486364 -190.246058) (xy 49.53 -190.245492)
			(xy 49.568479 -190.245891) (xy 49.645151 -190.25252) (xy 49.720963 -190.265745) (xy 49.795351 -190.285467)
			(xy 49.867758 -190.31154) (xy 49.902872 -190.32728) (xy 49.914556 -190.332868) (xy 49.939956 -190.33109)
			(xy 50.033936 -190.272924) (xy 50.046636 -190.250572) (xy 50.04689 -190.237872) (xy 50.048668 -190.202566)
			(xy 50.048668 -185.239406) (xy 50.046636 -185.180986) (xy 50.048668 -185.122566) (xy 50.048668 -180.159406)
			(xy 50.046636 -180.100986) (xy 50.048668 -180.042566) (xy 50.048668 -179.902866) (xy 50.048195 -179.892149)
			(xy 50.039433 -179.872588) (xy 50.023422 -179.858339) (xy 50.013362 -179.854606) (xy 49.905666 -179.819808)
			(xy 49.874424 -179.829968) (xy 49.864518 -179.843684) (xy 49.83951 -179.877578) (xy 49.784053 -179.940985)
			(xy 49.72285 -179.998865) (xy 49.65645 -180.0507) (xy 49.585448 -180.096027) (xy 49.510479 -180.13444)
			(xy 49.432215 -180.165594) (xy 49.351356 -180.189211) (xy 49.268627 -180.205078) (xy 49.184768 -180.213055)
			(xy 49.14265 -180.213508) (xy 49.100302 -180.213004) (xy 49.015988 -180.204953) (xy 48.932822 -180.188924)
			(xy 48.851555 -180.165063) (xy 48.772925 -180.133584) (xy 48.697644 -180.094773) (xy 48.626392 -180.048983)
			(xy 48.559816 -179.996627) (xy 48.498518 -179.938179) (xy 48.443053 -179.874169) (xy 48.393924 -179.805177)
			(xy 48.351575 -179.731827) (xy 48.316391 -179.654784) (xy 48.288689 -179.574745) (xy 48.268721 -179.492436)
			(xy 48.256668 -179.408601) (xy 48.252638 -179.324) (xy 48.256668 -179.239399) (xy 48.268721 -179.155564)
			(xy 48.288689 -179.073255) (xy 48.316391 -178.993216) (xy 48.351575 -178.916173) (xy 48.393924 -178.842823)
			(xy 48.443053 -178.773831) (xy 48.498518 -178.709821) (xy 48.559816 -178.651373) (xy 48.626392 -178.599017)
			(xy 48.697644 -178.553227) (xy 48.772925 -178.514416) (xy 48.851555 -178.482937) (xy 48.932822 -178.459076)
			(xy 49.015988 -178.443047) (xy 49.100302 -178.434996) (xy 49.14265 -178.434492) (xy 49.184768 -178.434983)
			(xy 49.268628 -178.442944) (xy 49.351359 -178.458799) (xy 49.432221 -178.482406) (xy 49.510487 -178.513554)
			(xy 49.585457 -178.551964) (xy 49.65646 -178.59729) (xy 49.722858 -178.649128) (xy 49.784056 -178.707012)
			(xy 49.839507 -178.770424) (xy 49.864518 -178.804316) (xy 49.874424 -178.818032) (xy 49.905666 -178.828192)
			(xy 50.013362 -178.793394) (xy 50.023365 -178.789583) (xy 50.039292 -178.775321) (xy 50.048059 -178.755821)
			(xy 50.048668 -178.745134) (xy 50.048668 -175.079406) (xy 50.046636 -175.020986) (xy 50.048668 -174.962566)
			(xy 50.048668 -169.999406) (xy 50.046636 -169.940986) (xy 50.048668 -169.882566) (xy 50.048668 -164.919406)
			(xy 50.046636 -164.860986) (xy 50.048668 -164.802566) (xy 50.048668 -159.839406) (xy 50.046636 -159.780986)
			(xy 50.048668 -159.722566) (xy 50.048668 -154.759406) (xy 50.046636 -154.700986) (xy 50.048668 -154.642566)
			(xy 50.048668 -149.679406) (xy 50.046636 -149.620986) (xy 50.048668 -149.562566) (xy 50.048668 -144.599406)
			(xy 50.046636 -144.540986) (xy 50.048668 -144.482566) (xy 50.048668 -140.429234) (xy 50.048213 -140.419395)
			(xy 50.040786 -140.401175) (xy 50.02702 -140.387115) (xy 50.018188 -140.382752) (xy 49.919128 -140.339318)
			(xy 49.88941 -140.344398) (xy 49.878234 -140.354558) (xy 49.847485 -140.382219) (xy 49.781686 -140.432343)
			(xy 49.711517 -140.476138) (xy 49.637583 -140.513227) (xy 49.560524 -140.543288) (xy 49.481006 -140.566062)
			(xy 49.399716 -140.581352) (xy 49.317358 -140.589026) (xy 49.276 -140.589508) (xy 49.23274 -140.588988)
			(xy 49.14663 -140.58058) (xy 49.061743 -140.563852) (xy 48.97888 -140.538964) (xy 48.898825 -140.506149)
			(xy 48.822333 -140.465718) (xy 48.750127 -140.418053) (xy 48.682889 -140.363604) (xy 48.621253 -140.302885)
			(xy 48.565804 -140.23647) (xy 48.517063 -140.164985) (xy 48.475491 -140.089107) (xy 48.441481 -140.009552)
			(xy 48.427894 -139.968478) (xy 48.424882 -139.960077) (xy 48.41401 -139.945937) (xy 48.398953 -139.936375)
			(xy 48.390302 -139.934188) (xy 48.348304 -139.924515) (xy 48.266263 -139.898101) (xy 48.187161 -139.863874)
			(xy 48.111742 -139.822155) (xy 48.040712 -139.773337) (xy 47.974737 -139.717876) (xy 47.914437 -139.656294)
			(xy 47.860377 -139.589166) (xy 47.813064 -139.517125) (xy 47.772942 -139.440844) (xy 47.740388 -139.36104)
			(xy 47.715706 -139.278461) (xy 47.699128 -139.193881) (xy 47.690809 -139.108095) (xy 47.690278 -139.065)
			(xy 47.690768 -139.023535) (xy 47.698512 -138.940966) (xy 47.713904 -138.859476) (xy 47.73681 -138.779772)
			(xy 47.767033 -138.702544) (xy 47.804309 -138.628463) (xy 47.825914 -138.593068) (xy 47.83201 -138.583162)
			(xy 47.83455 -138.560302) (xy 47.800768 -138.463528) (xy 47.784512 -138.447272) (xy 47.77359 -138.443208)
			(xy 47.734009 -138.428731) (xy 47.657528 -138.393315) (xy 47.58474 -138.35082) (xy 47.516301 -138.301628)
			(xy 47.452824 -138.24618) (xy 47.394878 -138.184975) (xy 47.342984 -138.118561) (xy 47.297608 -138.047534)
			(xy 47.259156 -137.972532) (xy 47.227974 -137.894228) (xy 47.204342 -137.813325) (xy 47.188472 -137.730549)
			(xy 47.180506 -137.646642) (xy 47.179992 -137.6045) (xy 47.180505 -137.5613) (xy 47.188883 -137.475306)
			(xy 47.205561 -137.39053) (xy 47.230381 -137.307771) (xy 47.263109 -137.227809) (xy 47.303437 -137.151397)
			(xy 47.350985 -137.079256) (xy 47.405304 -137.012066) (xy 47.465883 -136.95046) (xy 47.53215 -136.895018)
			(xy 47.603482 -136.846264) (xy 47.679204 -136.804657) (xy 47.758605 -136.770589) (xy 47.840935 -136.744381)
			(xy 47.883064 -136.734804) (xy 47.89424 -136.732264) (xy 47.912274 -136.718294) (xy 47.958502 -136.627362)
			(xy 47.95901 -136.604248) (xy 47.954184 -136.593834) (xy 47.935512 -136.55075) (xy 47.9063 -136.461506)
			(xy 47.886655 -136.369681) (xy 47.876796 -136.276296) (xy 47.876206 -136.229344) (xy 47.876662 -136.188884)
			(xy 47.884007 -136.108298) (xy 47.898639 -136.028713) (xy 47.920438 -135.950785) (xy 47.949224 -135.875158)
			(xy 47.984758 -135.802458) (xy 48.026748 -135.733285) (xy 48.074845 -135.668211) (xy 48.128654 -135.607774)
			(xy 48.187728 -135.552473) (xy 48.251581 -135.502765) (xy 48.2854 -135.480552) (xy 48.297338 -135.472932)
			(xy 48.309784 -135.448294) (xy 48.301148 -135.3312) (xy 48.285654 -135.308594) (xy 48.2727 -135.302752)
			(xy 48.234301 -135.284748) (xy 48.16079 -135.242443) (xy 48.091641 -135.193332) (xy 48.027481 -135.137861)
			(xy 47.968894 -135.076534) (xy 47.916411 -135.009908) (xy 47.87051 -134.938587) (xy 47.831607 -134.863221)
			(xy 47.800056 -134.784493) (xy 47.776143 -134.703119) (xy 47.760086 -134.619839) (xy 47.75203 -134.535407)
			(xy 47.751492 -134.493) (xy 47.75204 -134.448744) (xy 47.760832 -134.360669) (xy 47.778329 -134.273904)
			(xy 47.804359 -134.189305) (xy 47.838663 -134.107711) (xy 47.880903 -134.029928) (xy 47.93066 -133.956725)
			(xy 47.987443 -133.888827) (xy 48.0187 -133.857492) (xy 48.026066 -133.85038) (xy 48.033686 -133.832092)
			(xy 48.034956 -133.740144) (xy 48.02759 -133.721602) (xy 48.020478 -133.714236) (xy 47.991143 -133.683162)
			(xy 47.937913 -133.616304) (xy 47.891341 -133.544648) (xy 47.851858 -133.468855) (xy 47.819828 -133.389625)
			(xy 47.795545 -133.307687) (xy 47.779235 -133.223797) (xy 47.771047 -133.13873) (xy 47.770542 -133.096)
			(xy 47.771052 -133.053125) (xy 47.779301 -132.967774) (xy 47.795732 -132.883614) (xy 47.820193 -132.801428)
			(xy 47.852456 -132.721979) (xy 47.871888 -132.683758) (xy 47.87773 -132.672582) (xy 47.877476 -132.647436)
			(xy 47.82566 -132.550916) (xy 47.804832 -132.536946) (xy 47.792132 -132.535676) (xy 47.748864 -132.5307)
			(xy 47.663503 -132.513374) (xy 47.580246 -132.487787) (xy 47.499888 -132.454184) (xy 47.423199 -132.412887)
			(xy 47.350915 -132.364291) (xy 47.283728 -132.308861) (xy 47.222281 -132.24713) (xy 47.167162 -132.179687)
			(xy 47.1189 -132.10718) (xy 47.077957 -132.030302) (xy 47.044725 -131.94979) (xy 47.019522 -131.866415)
			(xy 47.002591 -131.780976) (xy 46.994092 -131.694291) (xy 46.993556 -131.65074) (xy 46.994026 -131.609471)
			(xy 47.001677 -131.527288) (xy 47.016907 -131.446168) (xy 47.039586 -131.366807) (xy 47.069517 -131.289887)
			(xy 47.106445 -131.216071) (xy 47.150051 -131.145992) (xy 47.199961 -131.080254) (xy 47.255746 -131.019421)
			(xy 47.316925 -130.964017) (xy 47.382973 -130.914518) (xy 47.453322 -130.87135) (xy 47.490126 -130.852672)
			(xy 47.501302 -130.847338) (xy 47.516034 -130.827272) (xy 47.532544 -130.720592) (xy 47.52467 -130.69697)
			(xy 47.51578 -130.688334) (xy 47.483974 -130.65693) (xy 47.426144 -130.588771) (xy 47.375444 -130.515154)
			(xy 47.332386 -130.436822) (xy 47.297404 -130.354565) (xy 47.270851 -130.269213) (xy 47.252996 -130.181628)
			(xy 47.244018 -130.092693) (xy 47.243492 -130.048) (xy 47.243996 -130.005652) (xy 47.252047 -129.921338)
			(xy 47.268076 -129.838172) (xy 47.291937 -129.756905) (xy 47.323416 -129.678275) (xy 47.362227 -129.602994)
			(xy 47.408017 -129.531742) (xy 47.460373 -129.465166) (xy 47.518821 -129.403868) (xy 47.582831 -129.348403)
			(xy 47.651823 -129.299274) (xy 47.725173 -129.256925) (xy 47.802216 -129.221741) (xy 47.882255 -129.194039)
			(xy 47.964564 -129.174071) (xy 48.048399 -129.162018) (xy 48.133 -129.157988) (xy 48.217601 -129.162018)
			(xy 48.301436 -129.174071) (xy 48.383745 -129.194039) (xy 48.463784 -129.221741) (xy 48.540827 -129.256925)
			(xy 48.614177 -129.299274) (xy 48.683169 -129.348403) (xy 48.747179 -129.403868) (xy 48.805627 -129.465166)
			(xy 48.857983 -129.531742) (xy 48.903773 -129.602994) (xy 48.942584 -129.678275) (xy 48.974063 -129.756905)
			(xy 48.997924 -129.838172) (xy 49.013953 -129.921338) (xy 49.022004 -130.005652) (xy 49.022508 -130.048)
			(xy 49.022021 -130.089987) (xy 49.014105 -130.173586) (xy 48.998344 -130.256068) (xy 48.974877 -130.336696)
			(xy 48.943914 -130.414753) (xy 48.905732 -130.489543) (xy 48.860668 -130.560401) (xy 48.809126 -130.626696)
			(xy 48.7807 -130.6576) (xy 48.771302 -130.66776) (xy 48.765206 -130.694684) (xy 48.800512 -130.805682)
			(xy 48.821086 -130.824224) (xy 48.834802 -130.826764) (xy 48.877478 -130.835857) (xy 48.96095 -130.861293)
			(xy 49.041531 -130.894781) (xy 49.118444 -130.935999) (xy 49.190951 -130.984552) (xy 49.258355 -131.039971)
			(xy 49.320008 -131.101725) (xy 49.375317 -131.16922) (xy 49.42375 -131.241806) (xy 49.464843 -131.318787)
			(xy 49.498199 -131.399422) (xy 49.523498 -131.482936) (xy 49.540497 -131.568526) (xy 49.549033 -131.655369)
			(xy 49.549558 -131.699) (xy 49.54903 -131.742491) (xy 49.540536 -131.829056) (xy 49.523628 -131.914379)
			(xy 49.498468 -131.997642) (xy 49.465297 -132.07805) (xy 49.424432 -132.154834) (xy 49.376264 -132.22726)
			(xy 49.321253 -132.294636) (xy 49.290986 -132.325872) (xy 49.283874 -132.333238) (xy 49.276254 -132.351526)
			(xy 49.276254 -132.443474) (xy 49.283874 -132.461762) (xy 49.290986 -132.469128) (xy 49.321272 -132.500345)
			(xy 49.376275 -132.567729) (xy 49.424437 -132.64016) (xy 49.465298 -132.716948) (xy 49.498467 -132.797357)
			(xy 49.523628 -132.880621) (xy 49.54054 -132.965943) (xy 49.549042 -133.052509) (xy 49.549558 -133.096)
			(xy 49.54901 -133.140256) (xy 49.540218 -133.22833) (xy 49.52272 -133.315095) (xy 49.496689 -133.399692)
			(xy 49.462383 -133.481286) (xy 49.420142 -133.559067) (xy 49.370382 -133.632268) (xy 49.313598 -133.700164)
			(xy 49.28235 -133.731508) (xy 49.274984 -133.73862) (xy 49.267364 -133.756908) (xy 49.266094 -133.848856)
			(xy 49.27346 -133.867398) (xy 49.280572 -133.874764) (xy 49.309905 -133.905839) (xy 49.363133 -133.972698)
			(xy 49.409702 -134.044354) (xy 49.449182 -134.120147) (xy 49.481211 -134.199378) (xy 49.505492 -134.281315)
			(xy 49.521802 -134.365204) (xy 49.529989 -134.45027) (xy 49.530508 -134.493) (xy 49.53005 -134.533459)
			(xy 49.522702 -134.614043) (xy 49.508066 -134.693626) (xy 49.486265 -134.771552) (xy 49.457477 -134.847176)
			(xy 49.421941 -134.919873) (xy 49.37995 -134.989043) (xy 49.331851 -135.054115) (xy 49.278043 -135.114549)
			(xy 49.218968 -135.169848) (xy 49.155116 -135.219554) (xy 49.121314 -135.241792) (xy 49.109376 -135.249412)
			(xy 49.09693 -135.27405) (xy 49.105566 -135.391144) (xy 49.12106 -135.41375) (xy 49.134014 -135.419592)
			(xy 49.172417 -135.437593) (xy 49.245937 -135.479892) (xy 49.315096 -135.528999) (xy 49.379266 -135.584467)
			(xy 49.437862 -135.645792) (xy 49.490355 -135.712418) (xy 49.536265 -135.783739) (xy 49.575177 -135.859106)
			(xy 49.606736 -135.937836) (xy 49.630657 -136.019213) (xy 49.646721 -136.102498) (xy 49.654782 -136.186934)
			(xy 49.655222 -136.229344) (xy 49.654712 -136.272546) (xy 49.646338 -136.358544) (xy 49.629665 -136.443324)
			(xy 49.604848 -136.526088) (xy 49.572123 -136.606055) (xy 49.531797 -136.682472) (xy 49.484251 -136.754618)
			(xy 49.429933 -136.821814) (xy 49.369354 -136.883425) (xy 49.303086 -136.938871) (xy 49.231754 -136.98763)
			(xy 49.15603 -137.029242) (xy 49.076627 -137.063314) (xy 48.994294 -137.089526) (xy 48.95215 -137.09904)
			(xy 48.940974 -137.10158) (xy 48.92294 -137.11555) (xy 48.876712 -137.206482) (xy 48.876204 -137.229596)
			(xy 48.88103 -137.24001) (xy 48.8997 -137.283094) (xy 48.928907 -137.372339) (xy 48.948547 -137.464164)
			(xy 48.958401 -137.557548) (xy 48.959008 -137.6045) (xy 48.958517 -137.645965) (xy 48.950774 -137.728534)
			(xy 48.935382 -137.810023) (xy 48.912475 -137.889728) (xy 48.882252 -137.966955) (xy 48.844975 -138.041036)
			(xy 48.823372 -138.076432) (xy 48.817276 -138.086338) (xy 48.814736 -138.109198) (xy 48.848518 -138.205972)
			(xy 48.864774 -138.222228) (xy 48.875696 -138.226292) (xy 48.914353 -138.240402) (xy 48.989116 -138.274804)
			(xy 49.06038 -138.315969) (xy 49.127534 -138.363544) (xy 49.190003 -138.417122) (xy 49.247253 -138.476245)
			(xy 49.298794 -138.540405) (xy 49.344185 -138.609055) (xy 49.383037 -138.681605) (xy 49.415016 -138.757436)
			(xy 49.427892 -138.796522) (xy 49.430908 -138.804917) (xy 49.441787 -138.819039) (xy 49.456848 -138.828577)
			(xy 49.465484 -138.830812) (xy 49.50372 -138.839602) (xy 49.578602 -138.863028) (xy 49.651131 -138.892955)
			(xy 49.720744 -138.929152) (xy 49.7869 -138.971338) (xy 49.849084 -139.019184) (xy 49.878234 -139.045442)
			(xy 49.88941 -139.055602) (xy 49.919128 -139.060682) (xy 50.018188 -139.017248) (xy 50.027009 -139.012883)
			(xy 50.040731 -138.998799) (xy 50.048167 -138.980596) (xy 50.048668 -138.970766) (xy 50.048668 -134.439406)
			(xy 50.046636 -134.380986) (xy 50.048668 -134.322566) (xy 50.048668 -129.359406) (xy 50.046636 -129.300986)
			(xy 50.048668 -129.242566) (xy 50.048668 -127.312674) (xy 50.048032 -127.300733) (xy 50.037313 -127.279392)
			(xy 50.028094 -127.27178) (xy 49.952656 -127.216154) (xy 49.929034 -127.21209) (xy 49.91735 -127.215646)
			(xy 49.875074 -127.228011) (xy 49.788703 -127.245313) (xy 49.701044 -127.253987) (xy 49.657 -127.254508)
			(xy 49.615898 -127.254033) (xy 49.534043 -127.246448) (xy 49.453238 -127.231343) (xy 49.374171 -127.208847)
			(xy 49.297517 -127.179151) (xy 49.22393 -127.142509) (xy 49.154038 -127.099234) (xy 49.088437 -127.049694)
			(xy 49.027687 -126.994313) (xy 48.972306 -126.933563) (xy 48.922766 -126.867962) (xy 48.879491 -126.79807)
			(xy 48.842849 -126.724483) (xy 48.813153 -126.647829) (xy 48.790657 -126.568762) (xy 48.775552 -126.487957)
			(xy 48.767967 -126.406102) (xy 48.767492 -126.365) (xy 48.767903 -126.326711) (xy 48.774512 -126.250417)
			(xy 48.787663 -126.174976) (xy 48.80726 -126.100947) (xy 48.819816 -126.064772) (xy 48.822457 -126.056334)
			(xy 48.822457 -126.038666) (xy 48.819816 -126.030228) (xy 48.807274 -125.99405) (xy 48.7877 -125.920018)
			(xy 48.774556 -125.844578) (xy 48.767938 -125.768288) (xy 48.767492 -125.73) (xy 48.767952 -125.689428)
			(xy 48.775363 -125.608624) (xy 48.790105 -125.528831) (xy 48.812056 -125.450713) (xy 48.841033 -125.37492)
			(xy 48.876796 -125.302082) (xy 48.89754 -125.267212) (xy 48.902939 -125.257326) (xy 48.90543 -125.234968)
			(xy 48.898123 -125.213691) (xy 48.890682 -125.205236) (xy 48.86133 -125.174169) (xy 48.808065 -125.107322)
			(xy 48.761459 -125.035673) (xy 48.721942 -124.959883) (xy 48.689877 -124.880652) (xy 48.665561 -124.79871)
			(xy 48.649218 -124.714814) (xy 48.640999 -124.629737) (xy 48.640492 -124.587) (xy 48.640967 -124.545898)
			(xy 48.648552 -124.464043) (xy 48.663657 -124.383238) (xy 48.686153 -124.304171) (xy 48.715849 -124.227517)
			(xy 48.752491 -124.15393) (xy 48.795766 -124.084038) (xy 48.845306 -124.018437) (xy 48.900687 -123.957687)
			(xy 48.961437 -123.902306) (xy 49.027038 -123.852766) (xy 49.09693 -123.809491) (xy 49.170517 -123.772849)
			(xy 49.247171 -123.743153) (xy 49.326238 -123.720657) (xy 49.407043 -123.705552) (xy 49.488898 -123.697967)
			(xy 49.53 -123.697492) (xy 49.568649 -123.697896) (xy 49.645656 -123.704582) (xy 49.721791 -123.717932)
			(xy 49.79648 -123.737842) (xy 49.869157 -123.764163) (xy 49.904396 -123.780042) (xy 49.916334 -123.78563)
			(xy 49.941988 -123.783852) (xy 50.0253 -123.730766) (xy 50.032282 -123.725877) (xy 50.042785 -123.712465)
			(xy 50.04833 -123.696358) (xy 50.048668 -123.68784) (xy 50.048668 -119.199406) (xy 50.046636 -119.140986)
			(xy 50.048668 -119.082566) (xy 50.048668 -114.119406) (xy 50.046636 -114.060986) (xy 50.048668 -114.002566)
			(xy 50.048668 -109.039406) (xy 50.046636 -108.980986) (xy 50.048668 -108.922566) (xy 50.048668 -103.959406)
			(xy 50.046636 -103.900986) (xy 50.048668 -103.842566) (xy 50.048668 -98.879406) (xy 50.046636 -98.820986)
			(xy 50.048668 -98.762566) (xy 50.048668 -93.799406) (xy 50.046636 -93.740986) (xy 50.048668 -93.682566)
			(xy 50.048668 -88.719406) (xy 50.046636 -88.660986) (xy 50.048668 -88.602566) (xy 50.048668 -83.639406)
			(xy 50.046636 -83.580986) (xy 50.048668 -83.522566) (xy 50.048668 -78.559406) (xy 50.046636 -78.500986)
			(xy 50.048668 -78.442566) (xy 50.048668 -73.479406) (xy 50.046636 -73.420986) (xy 50.048668 -73.362566)
			(xy 50.048668 -68.399406) (xy 50.046636 -68.340986) (xy 50.048668 -68.282566) (xy 50.048668 -63.319406)
			(xy 50.046636 -63.260986) (xy 50.048668 -63.202566) (xy 50.048668 -58.239406) (xy 50.046636 -58.180986)
			(xy 50.048668 -58.122566) (xy 50.048668 -53.159406) (xy 50.046636 -53.100986) (xy 50.048668 -53.042566)
			(xy 50.048668 -48.079406) (xy 50.046636 -48.020986) (xy 50.048668 -47.962566) (xy 50.048668 -42.999406)
			(xy 50.046636 -42.940986) (xy 50.048668 -42.882566) (xy 50.048668 -40.658796) (xy 50.048196 -40.648526)
			(xy 50.040143 -40.629632) (xy 50.025327 -40.615406) (xy 50.015902 -40.611298) (xy 49.912016 -40.571928)
			(xy 49.881536 -40.579548) (xy 49.870868 -40.591486) (xy 49.842793 -40.62252) (xy 49.781715 -40.679738)
			(xy 49.715531 -40.730964) (xy 49.644826 -40.775744) (xy 49.570226 -40.813682) (xy 49.492391 -40.844441)
			(xy 49.412011 -40.86775) (xy 49.329795 -40.883403) (xy 49.246472 -40.891261) (xy 49.204626 -40.891714)
			(xy 49.166336 -40.891304) (xy 49.090042 -40.884698) (xy 49.0146 -40.871548) (xy 48.94057 -40.851954)
			(xy 48.904398 -40.83939) (xy 48.89596 -40.836748) (xy 48.878292 -40.836748) (xy 48.869854 -40.83939)
			(xy 48.833676 -40.851933) (xy 48.759644 -40.871509) (xy 48.684204 -40.884655) (xy 48.607914 -40.891275)
			(xy 48.569626 -40.891714) (xy 48.527276 -40.891227) (xy 48.442958 -40.883178) (xy 48.359788 -40.867151)
			(xy 48.278518 -40.84329) (xy 48.199884 -40.811811) (xy 48.124598 -40.773001) (xy 48.053342 -40.727209)
			(xy 47.986762 -40.674852) (xy 47.925461 -40.616403) (xy 47.869993 -40.552391) (xy 47.820861 -40.483397)
			(xy 47.77851 -40.410044) (xy 47.743323 -40.332998) (xy 47.71562 -40.252956) (xy 47.695651 -40.170643)
			(xy 47.683596 -40.086805) (xy 47.679566 -40.0022) (xy 47.683596 -39.917595) (xy 47.695651 -39.833757)
			(xy 47.71562 -39.751444) (xy 47.743323 -39.671402) (xy 47.77851 -39.594356) (xy 47.820861 -39.521003)
			(xy 47.869993 -39.452009) (xy 47.925461 -39.387997) (xy 47.986762 -39.329548) (xy 48.053342 -39.277191)
			(xy 48.124598 -39.231399) (xy 48.199884 -39.192589) (xy 48.278518 -39.16111) (xy 48.359788 -39.137249)
			(xy 48.442958 -39.121222) (xy 48.527276 -39.113173) (xy 48.569626 -39.112698) (xy 48.607916 -39.113106)
			(xy 48.684211 -39.119708) (xy 48.759654 -39.132854) (xy 48.833686 -39.152445) (xy 48.869854 -39.165022)
			(xy 48.878292 -39.167664) (xy 48.89596 -39.167664) (xy 48.904398 -39.165022) (xy 48.940575 -39.152477)
			(xy 49.014607 -39.132897) (xy 49.090047 -39.119747) (xy 49.166338 -39.113122) (xy 49.204626 -39.112698)
			(xy 49.246471 -39.113179) (xy 49.32979 -39.121043) (xy 49.412002 -39.1367) (xy 49.49238 -39.16001)
			(xy 49.570212 -39.190767) (xy 49.644811 -39.2287) (xy 49.715517 -39.273473) (xy 49.781704 -39.32469)
			(xy 49.842788 -39.381898) (xy 49.870868 -39.412926) (xy 49.881536 -39.424864) (xy 49.912016 -39.432484)
			(xy 50.015902 -39.393114) (xy 50.025345 -39.389033) (xy 50.040173 -39.374799) (xy 50.048236 -39.355893)
			(xy 50.048668 -39.345616) (xy 50.048668 -37.919406) (xy 50.046636 -37.860986) (xy 50.048668 -37.802566)
			(xy 50.048668 -32.839406) (xy 50.046636 -32.780986) (xy 50.048668 -32.722566) (xy 50.048668 -27.759406)
			(xy 50.046636 -27.700986) (xy 50.048668 -27.642566) (xy 50.048668 -22.679406) (xy 50.046636 -22.620986)
			(xy 50.048668 -22.562566) (xy 50.048668 -17.599406) (xy 50.046636 -17.540986) (xy 50.048668 -17.482566)
			(xy 50.048668 -12.519406) (xy 50.046636 -12.460986) (xy 50.048668 -12.402566) (xy 50.048668 -7.439406)
			(xy 50.046636 -7.380986) (xy 50.048668 -7.322566) (xy 50.048668 -3.999992) (xy 50.048188 -3.932571)
			(xy 50.040452 -3.797952) (xy 50.025007 -3.663998) (xy 50.001902 -3.531151) (xy 49.971214 -3.399848)
			(xy 49.933045 -3.270522) (xy 49.887519 -3.143599) (xy 49.834787 -3.019496) (xy 49.805336 -2.958846)
			(xy 49.803812 -2.956052) (xy 49.794632 -2.9398) (xy 49.777481 -2.906642) (xy 49.769522 -2.889758)
			(xy 49.768252 -2.886964) (xy 49.734494 -2.825321) (xy 49.660604 -2.705751) (xy 49.579694 -2.590814)
			(xy 49.492055 -2.480922) (xy 49.398 -2.376468) (xy 49.297867 -2.277826) (xy 49.192013 -2.18535) (xy 49.080818 -2.09937)
			(xy 48.96468 -2.020194) (xy 48.844014 -1.948106) (xy 48.719253 -1.883364) (xy 48.590844 -1.8262)
			(xy 48.459245 -1.776817) (xy 48.324928 -1.735394) (xy 48.188374 -1.702078) (xy 48.050072 -1.676989)
			(xy 47.910518 -1.660216) (xy 47.77021 -1.65182) (xy 47.69993 -1.651254) (xy 47.22876 -1.651254) (xy 47.192946 -1.652016)
			(xy 47.157132 -1.651254) (xy 42.14876 -1.651254) (xy 42.112946 -1.652016) (xy 42.077132 -1.651254)
			(xy 37.445188 -1.651254) (xy 37.43512 -1.651681) (xy 37.416524 -1.659404) (xy 37.40912 -1.66624)
			(xy 36.9062 -2.16916) (xy 36.899363 -2.176562) (xy 36.89165 -2.19516) (xy 36.891214 -2.205228) (xy 36.891214 -4.50957)
			(xy 43.243235 -4.50957) (xy 43.243235 -4.38043) (xy 43.251185 -4.251535) (xy 43.267055 -4.123375)
			(xy 43.290784 -3.996434) (xy 43.322283 -3.871195) (xy 43.361432 -3.748132) (xy 43.408083 -3.627713)
			(xy 43.462058 -3.510394) (xy 43.523153 -3.39662) (xy 43.591136 -3.286823) (xy 43.66575 -3.18142)
			(xy 43.746711 -3.08081) (xy 43.833711 -2.985375) (xy 43.926422 -2.895476) (xy 44.024492 -2.811455)
			(xy 44.127547 -2.733631) (xy 44.235198 -2.662299) (xy 44.347037 -2.597729) (xy 44.462638 -2.540167)
			(xy 44.581563 -2.48983) (xy 44.703362 -2.44691) (xy 44.827572 -2.411569) (xy 44.953721 -2.383942)
			(xy 45.081333 -2.364133) (xy 45.209922 -2.352217) (xy 45.339 -2.348241) (xy 45.468078 -2.352217)
			(xy 45.596667 -2.364133) (xy 45.724279 -2.383942) (xy 45.850428 -2.411569) (xy 45.974638 -2.44691)
			(xy 46.096437 -2.48983) (xy 46.215362 -2.540167) (xy 46.330963 -2.597729) (xy 46.442802 -2.662299)
			(xy 46.550453 -2.733631) (xy 46.653508 -2.811455) (xy 46.751578 -2.895476) (xy 46.844289 -2.985375)
			(xy 46.931289 -3.08081) (xy 47.01225 -3.18142) (xy 47.086864 -3.286823) (xy 47.154847 -3.39662) (xy 47.215942 -3.510394)
			(xy 47.269917 -3.627713) (xy 47.316568 -3.748132) (xy 47.355717 -3.871195) (xy 47.387216 -3.996434)
			(xy 47.410945 -4.123375) (xy 47.426815 -4.251535) (xy 47.434765 -4.38043) (xy 47.435262 -4.445) (xy 47.434765 -4.50957)
			(xy 47.426815 -4.638465) (xy 47.410945 -4.766625) (xy 47.387216 -4.893566) (xy 47.355717 -5.018805)
			(xy 47.316568 -5.141868) (xy 47.269917 -5.262287) (xy 47.215942 -5.379606) (xy 47.154847 -5.49338)
			(xy 47.086864 -5.603177) (xy 47.01225 -5.70858) (xy 46.931289 -5.80919) (xy 46.844289 -5.904625)
			(xy 46.751578 -5.994524) (xy 46.653508 -6.078545) (xy 46.550453 -6.156369) (xy 46.442802 -6.227701)
			(xy 46.330963 -6.292271) (xy 46.215362 -6.349833) (xy 46.096437 -6.40017) (xy 45.974638 -6.44309)
			(xy 45.850428 -6.478431) (xy 45.724279 -6.506058) (xy 45.596667 -6.525867) (xy 45.468078 -6.537783)
			(xy 45.339 -6.54176) (xy 45.209922 -6.537783) (xy 45.081333 -6.525867) (xy 44.953721 -6.506058) (xy 44.827572 -6.478431)
			(xy 44.703362 -6.44309) (xy 44.581563 -6.40017) (xy 44.462638 -6.349833) (xy 44.347037 -6.292271)
			(xy 44.235198 -6.227701) (xy 44.127547 -6.156369) (xy 44.024492 -6.078545) (xy 43.926422 -5.994524)
			(xy 43.833711 -5.904625) (xy 43.746711 -5.80919) (xy 43.66575 -5.70858) (xy 43.591136 -5.603177)
			(xy 43.523153 -5.49338) (xy 43.462058 -5.379606) (xy 43.408083 -5.262287) (xy 43.361432 -5.141868)
			(xy 43.322283 -5.018805) (xy 43.290784 -4.893566) (xy 43.267055 -4.766625) (xy 43.251185 -4.638465)
			(xy 43.243235 -4.50957) (xy 36.891214 -4.50957) (xy 36.891214 -6.776212) (xy 36.892259 -6.791685)
			(xy 36.893402 -6.82268) (xy 36.8935 -6.838188) (xy 36.893402 -6.853696) (xy 36.892259 -6.884691)
			(xy 36.891214 -6.900164) (xy 36.891214 -10.999978) (xy 36.890732 -11.074441) (xy 36.882962 -11.223165)
			(xy 36.867437 -11.37128) (xy 36.844202 -11.518383) (xy 36.813318 -11.664072) (xy 36.77487 -11.80795)
			(xy 36.728964 -11.949625) (xy 36.675724 -12.08871) (xy 36.615295 -12.224826) (xy 36.547843 -12.357601)
			(xy 36.473551 -12.486674) (xy 36.392622 -12.611692) (xy 36.305276 -12.732315) (xy 36.211752 -12.848214)
			(xy 36.112305 -12.959071) (xy 36.007207 -13.064586) (xy 35.896743 -13.164471) (xy 35.781215 -13.258452)
			(xy 35.660938 -13.346273) (xy 35.536241 -13.427696) (xy 35.407463 -13.502498) (xy 35.274955 -13.570474)
			(xy 35.139079 -13.63144) (xy 35.000205 -13.68523) (xy 34.858713 -13.731696) (xy 34.714988 -13.770712)
			(xy 34.569422 -13.802171) (xy 34.495994 -13.814552) (xy 34.492692 -13.81506) (xy 34.450752 -13.824164)
			(xy 34.36564 -13.835228) (xy 34.322766 -13.837158) (xy 34.319464 -13.837412) (xy 34.249793 -13.843848)
			(xy 34.11003 -13.850707) (xy 34.040064 -13.851128) (xy 30.25521 -13.851128) (xy 30.245138 -13.850707)
			(xy 30.226529 -13.842999) (xy 30.219142 -13.836142) (xy 29.787596 -13.404596) (xy 29.780751 -13.397197)
			(xy 29.773018 -13.378599) (xy 29.77261 -13.368528) (xy 29.77261 -8.70585) (xy 29.772178 -8.695784)
			(xy 29.764452 -8.677191) (xy 29.757624 -8.669782) (xy 29.662628 -8.574786) (xy 29.65523 -8.567942)
			(xy 29.63663 -8.56022) (xy 29.62656 -8.5598) (xy 28.265882 -8.5598) (xy 28.255813 -8.560227) (xy 28.237214 -8.567946)
			(xy 28.229814 -8.574786) (xy 28.107386 -8.697214) (xy 28.100532 -8.704609) (xy 28.09279 -8.723208)
			(xy 28.0924 -8.733282) (xy 28.0924 -11.535918) (xy 28.091973 -11.545987) (xy 28.084254 -11.564586)
			(xy 28.077414 -11.571986) (xy 26.583386 -13.066014) (xy 26.575991 -13.072868) (xy 26.557392 -13.08061)
			(xy 26.547318 -13.081) (xy 24.659082 -13.081) (xy 24.649013 -13.081427) (xy 24.630414 -13.089146)
			(xy 24.623014 -13.095986) (xy 23.882858 -13.836142) (xy 23.87546 -13.842988) (xy 23.856861 -13.850716)
			(xy 23.84679 -13.851128) (xy 21.946108 -13.851128) (xy 21.936063 -13.851552) (xy 21.917509 -13.859259)
			(xy 21.903334 -13.873496) (xy 21.899118 -13.882624) (xy 21.882761 -13.921432) (xy 21.843728 -13.996064)
			(xy 21.797814 -14.066671) (xy 21.74543 -14.132621) (xy 21.687046 -14.193323) (xy 21.623183 -14.248232)
			(xy 21.554416 -14.296858) (xy 21.481359 -14.338764) (xy 21.404667 -14.373575) (xy 21.325027 -14.400979)
			(xy 21.243153 -14.420731) (xy 21.159778 -14.432653) (xy 21.07565 -14.436639) (xy 20.991522 -14.432653)
			(xy 20.908147 -14.420731) (xy 20.826273 -14.400979) (xy 20.746633 -14.373575) (xy 20.669941 -14.338764)
			(xy 20.596884 -14.296858) (xy 20.528117 -14.248232) (xy 20.464254 -14.193323) (xy 20.40587 -14.132621)
			(xy 20.353486 -14.066671) (xy 20.307572 -13.996064) (xy 20.268539 -13.921432) (xy 20.252182 -13.882624)
			(xy 20.247975 -13.87349) (xy 20.233797 -13.85925) (xy 20.215239 -13.851541) (xy 20.205192 -13.851128)
			(xy 17.686528 -13.851128) (xy 17.60159 -13.851303) (xy 17.431932 -13.842787) (xy 17.347438 -13.83411)
			(xy 17.345152 -13.833856) (xy 17.314325 -13.831658) (xy 17.253056 -13.823524) (xy 17.222724 -13.8176)
			(xy 17.220438 -13.817092) (xy 17.146634 -13.805091) (xy 17.000288 -13.77433) (xy 16.855756 -13.73594)
			(xy 16.713436 -13.690026) (xy 16.573718 -13.636713) (xy 16.436987 -13.57615) (xy 16.303619 -13.508502)
			(xy 16.173981 -13.433955) (xy 16.048429 -13.352715) (xy 15.927309 -13.265004) (xy 15.810953 -13.171065)
			(xy 15.699682 -13.071154) (xy 15.593801 -12.965549) (xy 15.493603 -12.854537) (xy 15.399361 -12.738426)
			(xy 15.311337 -12.617533) (xy 15.229771 -12.492193) (xy 15.154888 -12.362749) (xy 15.086894 -12.229557)
			(xy 15.025975 -12.092983) (xy 14.9723 -11.953404) (xy 14.926017 -11.811204) (xy 14.887251 -11.666772)
			(xy 14.856111 -11.520507) (xy 14.832681 -11.37281) (xy 14.817026 -11.224088) (xy 14.809189 -11.07475)
			(xy 14.808708 -10.999978) (xy 14.808708 -6.614668) (xy 14.8082 -6.585458) (xy 14.808708 -6.556248)
			(xy 14.808708 -2.204974) (xy 14.808281 -2.194906) (xy 14.80056 -2.176307) (xy 14.793722 -2.168906)
			(xy 14.291056 -1.66624) (xy 14.283657 -1.659396) (xy 14.265058 -1.651672) (xy 14.254988 -1.651254)
			(xy 14.006068 -1.651254) (xy 13.951458 -1.653032) (xy 13.896848 -1.651254) (xy 8.926068 -1.651254)
			(xy 8.871458 -1.653032) (xy 8.816848 -1.651254) (xy 4.10083 -1.651254) (xy 4.099052 -1.651508) (xy 4.081933 -1.652726)
			(xy 4.047634 -1.653996) (xy 4.030472 -1.654048) (xy 4.014329 -1.653989) (xy 3.982063 -1.652846) (xy 3.965956 -1.651762)
			(xy 3.961384 -1.651508) (xy 3.893788 -1.653103) (xy 3.758931 -1.663099) (xy 3.624873 -1.680838) (xy 3.492058 -1.706262)
			(xy 3.360925 -1.739285) (xy 3.23191 -1.779799) (xy 3.10544 -1.827669) (xy 2.981934 -1.882737) (xy 2.861801 -1.94482)
			(xy 2.745439 -2.013713) (xy 2.633235 -2.089187) (xy 2.525559 -2.170993) (xy 2.422768 -2.258858) (xy 2.325203 -2.352492)
			(xy 2.233188 -2.451585) (xy 2.147027 -2.555809) (xy 2.067005 -2.664817) (xy 1.993389 -2.778249) (xy 1.926421 -2.895729)
			(xy 1.866324 -3.016868) (xy 1.813297 -3.141264) (xy 1.767515 -3.268505) (xy 1.729131 -3.398169) (xy 1.698271 -3.529828)
			(xy 1.675038 -3.663044) (xy 1.659508 -3.797376) (xy 1.651734 -3.932379) (xy 1.651254 -3.999992) (xy 1.651254 -4.50957)
			(xy 9.080235 -4.50957) (xy 9.080235 -4.38043) (xy 9.088185 -4.251535) (xy 9.104055 -4.123375) (xy 9.127784 -3.996434)
			(xy 9.159283 -3.871195) (xy 9.198432 -3.748132) (xy 9.245083 -3.627713) (xy 9.299058 -3.510394) (xy 9.360153 -3.39662)
			(xy 9.428136 -3.286823) (xy 9.50275 -3.18142) (xy 9.583711 -3.08081) (xy 9.670711 -2.985375) (xy 9.763422 -2.895476)
			(xy 9.861492 -2.811455) (xy 9.964547 -2.733631) (xy 10.072198 -2.662299) (xy 10.184037 -2.597729)
			(xy 10.299638 -2.540167) (xy 10.418563 -2.48983) (xy 10.540362 -2.44691) (xy 10.664572 -2.411569)
			(xy 10.790721 -2.383942) (xy 10.918333 -2.364133) (xy 11.046922 -2.352217) (xy 11.176 -2.348241)
			(xy 11.305078 -2.352217) (xy 11.433667 -2.364133) (xy 11.561279 -2.383942) (xy 11.687428 -2.411569)
			(xy 11.811638 -2.44691) (xy 11.933437 -2.48983) (xy 12.052362 -2.540167) (xy 12.167963 -2.597729)
			(xy 12.279802 -2.662299) (xy 12.387453 -2.733631) (xy 12.490508 -2.811455) (xy 12.588578 -2.895476)
			(xy 12.681289 -2.985375) (xy 12.768289 -3.08081) (xy 12.84925 -3.18142) (xy 12.923864 -3.286823)
			(xy 12.991847 -3.39662) (xy 13.052942 -3.510394) (xy 13.106917 -3.627713) (xy 13.153568 -3.748132)
			(xy 13.192717 -3.871195) (xy 13.224216 -3.996434) (xy 13.247945 -4.123375) (xy 13.263815 -4.251535)
			(xy 13.271765 -4.38043) (xy 13.272262 -4.445) (xy 13.271765 -4.50957) (xy 13.263815 -4.638465) (xy 13.247945 -4.766625)
			(xy 13.224216 -4.893566) (xy 13.192717 -5.018805) (xy 13.153568 -5.141868) (xy 13.106917 -5.262287)
			(xy 13.052942 -5.379606) (xy 12.991847 -5.49338) (xy 12.923864 -5.603177) (xy 12.84925 -5.70858)
			(xy 12.768289 -5.80919) (xy 12.681289 -5.904625) (xy 12.588578 -5.994524) (xy 12.490508 -6.078545)
			(xy 12.387453 -6.156369) (xy 12.279802 -6.227701) (xy 12.167963 -6.292271) (xy 12.052362 -6.349833)
			(xy 11.933437 -6.40017) (xy 11.811638 -6.44309) (xy 11.687428 -6.478431) (xy 11.561279 -6.506058)
			(xy 11.433667 -6.525867) (xy 11.305078 -6.537783) (xy 11.176 -6.54176) (xy 11.046922 -6.537783) (xy 10.918333 -6.525867)
			(xy 10.790721 -6.506058) (xy 10.664572 -6.478431) (xy 10.540362 -6.44309) (xy 10.418563 -6.40017)
			(xy 10.299638 -6.349833) (xy 10.184037 -6.292271) (xy 10.072198 -6.227701) (xy 9.964547 -6.156369)
			(xy 9.861492 -6.078545) (xy 9.763422 -5.994524) (xy 9.670711 -5.904625) (xy 9.583711 -5.80919) (xy 9.50275 -5.70858)
			(xy 9.428136 -5.603177) (xy 9.360153 -5.49338) (xy 9.299058 -5.379606) (xy 9.245083 -5.262287) (xy 9.198432 -5.141868)
			(xy 9.159283 -5.018805) (xy 9.127784 -4.893566) (xy 9.104055 -4.766625) (xy 9.088185 -4.638465) (xy 9.080235 -4.50957)
			(xy 1.651254 -4.50957) (xy 1.651254 -7.740904) (xy 1.652778 -7.79145) (xy 1.651254 -7.841996) (xy 1.651254 -10.196576)
			(xy 1.651788 -10.207598) (xy 1.660995 -10.227627) (xy 1.669034 -10.235184) (xy 1.73609 -10.292588)
			(xy 1.757426 -10.298684) (xy 1.768348 -10.29716) (xy 1.802292 -10.292181) (xy 1.870695 -10.286839)
			(xy 1.905 -10.286492) (xy 1.947348 -10.286996) (xy 2.031662 -10.295047) (xy 2.114828 -10.311076)
			(xy 2.196095 -10.334937) (xy 2.274725 -10.366416) (xy 2.350006 -10.405227) (xy 2.421258 -10.451017)
			(xy 2.487834 -10.503373) (xy 2.549132 -10.561821) (xy 2.604597 -10.625831) (xy 2.653726 -10.694823)
			(xy 2.696075 -10.768173) (xy 2.731259 -10.845216) (xy 2.758961 -10.925255) (xy 2.778929 -11.007564)
			(xy 2.790982 -11.091399) (xy 2.795013 -11.176) (xy 2.790982 -11.260601) (xy 2.778929 -11.344436)
			(xy 2.758961 -11.426745) (xy 2.731259 -11.506784) (xy 2.696075 -11.583827) (xy 2.653726 -11.657177)
			(xy 2.604597 -11.726169) (xy 2.549132 -11.790179) (xy 2.487834 -11.848627) (xy 2.421258 -11.900983)
			(xy 2.350006 -11.946773) (xy 2.274725 -11.985584) (xy 2.196095 -12.017063) (xy 2.114828 -12.040924)
			(xy 2.031662 -12.056953) (xy 1.947348 -12.065004) (xy 1.905 -12.065508) (xy 1.870695 -12.065152)
			(xy 1.802292 -12.059815) (xy 1.768348 -12.05484) (xy 1.757426 -12.053316) (xy 1.73609 -12.059412)
			(xy 1.669034 -12.116816) (xy 1.661008 -12.124387) (xy 1.651788 -12.144404) (xy 1.651254 -12.155424)
			(xy 1.651254 -12.820904) (xy 1.652778 -12.87145) (xy 1.651254 -12.921996) (xy 1.651254 -17.900904)
			(xy 1.652778 -17.95145) (xy 1.651254 -18.001996) (xy 1.651254 -22.980904) (xy 1.652778 -23.03145)
			(xy 1.651254 -23.081996) (xy 1.651254 -26.409904) (xy 5.378704 -26.409904) (xy 5.379211 -26.358413)
			(xy 5.387226 -26.255743) (xy 5.403209 -26.154009) (xy 5.427061 -26.053827) (xy 5.458638 -25.955806)
			(xy 5.497749 -25.86054) (xy 5.544156 -25.768607) (xy 5.597577 -25.680565) (xy 5.65769 -25.596948)
			(xy 5.724128 -25.518264) (xy 5.759958 -25.48128) (xy 5.767324 -25.474168) (xy 5.77469 -25.45588)
			(xy 5.77469 -25.363932) (xy 5.767324 -25.345644) (xy 5.759958 -25.338532) (xy 5.724125 -25.301551)
			(xy 5.657685 -25.222867) (xy 5.597571 -25.13925) (xy 5.544148 -25.051208) (xy 5.49774 -24.959275)
			(xy 5.458628 -24.864009) (xy 5.42705 -24.765987) (xy 5.403197 -24.665805) (xy 5.387214 -24.56407)
			(xy 5.379198 -24.4614) (xy 5.379199 -24.358417) (xy 5.387214 -24.255747) (xy 5.403197 -24.154012)
			(xy 5.42705 -24.05383) (xy 5.458629 -23.955809) (xy 5.497741 -23.860542) (xy 5.54415 -23.768609)
			(xy 5.597573 -23.680567) (xy 5.657687 -23.596951) (xy 5.724127 -23.518267) (xy 5.759958 -23.481284)
			(xy 5.767324 -23.474172) (xy 5.77469 -23.455884) (xy 5.77469 -23.363936) (xy 5.767324 -23.345648)
			(xy 5.759958 -23.338536) (xy 5.724129 -23.301551) (xy 5.657689 -23.222867) (xy 5.597575 -23.139251)
			(xy 5.544152 -23.051209) (xy 5.497743 -22.959277) (xy 5.458631 -22.864011) (xy 5.427053 -22.765989)
			(xy 5.4032 -22.665807) (xy 5.387217 -22.564073) (xy 5.379201 -22.461403) (xy 5.379201 -22.35842)
			(xy 5.387217 -22.25575) (xy 5.4032 -22.154016) (xy 5.427052 -22.053834) (xy 5.45863 -21.955812) (xy 5.497742 -21.860546)
			(xy 5.544151 -21.768613) (xy 5.597574 -21.680571) (xy 5.657688 -21.596955) (xy 5.724128 -21.518271)
			(xy 5.759958 -21.481288) (xy 5.767324 -21.474176) (xy 5.77469 -21.455888) (xy 5.77469 -21.36394)
			(xy 5.767324 -21.345652) (xy 5.759958 -21.33854) (xy 5.724127 -21.301557) (xy 5.657687 -21.222873)
			(xy 5.597573 -21.139257) (xy 5.54415 -21.051215) (xy 5.497741 -20.959282) (xy 5.458629 -20.864016)
			(xy 5.427051 -20.765994) (xy 5.403198 -20.665812) (xy 5.387215 -20.564077) (xy 5.379199 -20.461407)
			(xy 5.379199 -20.358425) (xy 5.387215 -20.255755) (xy 5.403198 -20.15402) (xy 5.427051 -20.053838)
			(xy 5.458629 -19.955816) (xy 5.497741 -19.86055) (xy 5.54415 -19.768617) (xy 5.597573 -19.680575)
			(xy 5.657687 -19.596959) (xy 5.724127 -19.518275) (xy 5.759958 -19.481292) (xy 5.767324 -19.47418)
			(xy 5.77469 -19.455892) (xy 5.77469 -19.363944) (xy 5.767324 -19.345656) (xy 5.759958 -19.338544)
			(xy 5.724127 -19.301561) (xy 5.657687 -19.222877) (xy 5.597573 -19.139261) (xy 5.54415 -19.051219)
			(xy 5.497742 -18.959286) (xy 5.45863 -18.86402) (xy 5.427051 -18.765998) (xy 5.403198 -18.665816)
			(xy 5.387216 -18.564081) (xy 5.3792 -18.461411) (xy 5.3792 -18.358429) (xy 5.387216 -18.255759) (xy 5.403198 -18.154024)
			(xy 5.427051 -18.053842) (xy 5.45863 -17.95582) (xy 5.497742 -17.860554) (xy 5.54415 -17.768621)
			(xy 5.597573 -17.680579) (xy 5.657687 -17.596963) (xy 5.724127 -17.518279) (xy 5.759958 -17.481296)
			(xy 5.767324 -17.474184) (xy 5.77469 -17.455896) (xy 5.77469 -17.363948) (xy 5.767324 -17.34566)
			(xy 5.759958 -17.338548) (xy 5.724126 -17.301566) (xy 5.657686 -17.222882) (xy 5.597571 -17.139266)
			(xy 5.544147 -17.051224) (xy 5.497738 -16.959291) (xy 5.458626 -16.864025) (xy 5.427048 -16.766003)
			(xy 5.403195 -16.665821) (xy 5.387212 -16.564086) (xy 5.379197 -16.461415) (xy 5.378704 -16.409924)
			(xy 5.379225 -16.358433) (xy 5.387238 -16.255764) (xy 5.403219 -16.15403) (xy 5.427069 -16.053849)
			(xy 5.458645 -15.955827) (xy 5.497754 -15.860561) (xy 5.54416 -15.768628) (xy 5.597581 -15.680586)
			(xy 5.657692 -15.596969) (xy 5.724129 -15.518284) (xy 5.759958 -15.4813) (xy 5.767324 -15.474188)
			(xy 5.77469 -15.4559) (xy 5.77469 -15.363952) (xy 5.767324 -15.345664) (xy 5.759958 -15.338552) (xy 5.724128 -15.301568)
			(xy 5.657687 -15.222885) (xy 5.597573 -15.139269) (xy 5.544149 -15.051227) (xy 5.49774 -14.959294)
			(xy 5.458627 -14.864028) (xy 5.427049 -14.766007) (xy 5.403196 -14.665824) (xy 5.387213 -14.56409)
			(xy 5.379197 -14.461419) (xy 5.378704 -14.409928) (xy 5.379227 -14.358437) (xy 5.387241 -14.255768)
			(xy 5.403221 -14.154034) (xy 5.427071 -14.053853) (xy 5.458646 -13.955832) (xy 5.497755 -13.860565)
			(xy 5.544161 -13.768632) (xy 5.597581 -13.68059) (xy 5.657692 -13.596973) (xy 5.724129 -13.518288)
			(xy 5.759958 -13.481304) (xy 5.767324 -13.474192) (xy 5.77469 -13.455904) (xy 5.77469 -13.363956)
			(xy 5.767324 -13.345668) (xy 5.759958 -13.338556) (xy 5.72413 -13.30157) (xy 5.657689 -13.222887)
			(xy 5.597574 -13.139271) (xy 5.54415 -13.05123) (xy 5.497741 -12.959297) (xy 5.458628 -12.864031)
			(xy 5.42705 -12.76601) (xy 5.403196 -12.665828) (xy 5.387213 -12.564093) (xy 5.379197 -12.461423)
			(xy 5.378704 -12.409932) (xy 5.379179 -12.359113) (xy 5.386987 -12.257774) (xy 5.402557 -12.157336)
			(xy 5.425799 -12.05839) (xy 5.456576 -11.961523) (xy 5.494704 -11.867307) (xy 5.539958 -11.776299)
			(xy 5.592072 -11.689038) (xy 5.650737 -11.606039) (xy 5.715605 -11.527793) (xy 5.786294 -11.454762)
			(xy 5.862386 -11.387379) (xy 5.94343 -11.326042) (xy 6.028948 -11.271113) (xy 6.118433 -11.222918)
			(xy 6.211357 -11.181741) (xy 6.30717 -11.147826) (xy 6.405306 -11.121373) (xy 6.455156 -11.111484)
			(xy 6.466586 -11.109452) (xy 6.484874 -11.096244) (xy 6.533642 -11.007344) (xy 6.535166 -10.984738)
			(xy 6.530848 -10.97407) (xy 6.512841 -10.927389) (xy 6.483432 -10.831746) (xy 6.461716 -10.734069)
			(xy 6.447829 -10.634975) (xy 6.441858 -10.535091) (xy 6.443843 -10.435048) (xy 6.453771 -10.33548)
			(xy 6.471577 -10.237015) (xy 6.497151 -10.140276) (xy 6.53033 -10.045874) (xy 6.570905 -9.954408)
			(xy 6.618619 -9.866454) (xy 6.67317 -9.782569) (xy 6.734213 -9.703284) (xy 6.801363 -9.629099) (xy 6.874194 -9.560484)
			(xy 6.952248 -9.497873) (xy 7.035028 -9.441661) (xy 7.122014 -9.392204) (xy 7.212654 -9.349815) (xy 7.306375 -9.314761)
			(xy 7.402585 -9.287264) (xy 7.500676 -9.267498) (xy 7.600027 -9.255589) (xy 7.70001 -9.251611) (xy 7.799993 -9.255589)
			(xy 7.899344 -9.267498) (xy 7.997435 -9.287264) (xy 8.093645 -9.314761) (xy 8.187366 -9.349815) (xy 8.278006 -9.392204)
			(xy 8.364992 -9.441661) (xy 8.447772 -9.497873) (xy 8.525826 -9.560484) (xy 8.598657 -9.629099) (xy 8.665807 -9.703284)
			(xy 8.72685 -9.782569) (xy 8.781401 -9.866454) (xy 8.829115 -9.954408) (xy 8.86969 -10.045874) (xy 8.902869 -10.140276)
			(xy 8.928443 -10.237015) (xy 8.946249 -10.33548) (xy 8.956177 -10.435048) (xy 8.958162 -10.535091)
			(xy 8.952191 -10.634975) (xy 8.938304 -10.734069) (xy 8.916588 -10.831746) (xy 8.887179 -10.927389)
			(xy 8.869172 -10.97407) (xy 8.864854 -10.984738) (xy 8.866378 -11.007344) (xy 8.915146 -11.096244)
			(xy 8.933434 -11.109452) (xy 8.944864 -11.111484) (xy 8.994714 -11.121371) (xy 9.092848 -11.147828)
			(xy 9.188659 -11.181746) (xy 9.281581 -11.222925) (xy 9.371064 -11.271122) (xy 9.456579 -11.326052)
			(xy 9.537622 -11.38739) (xy 9.613712 -11.454774) (xy 9.684399 -11.527804) (xy 9.749267 -11.60605)
			(xy 9.807931 -11.689048) (xy 9.860045 -11.776308) (xy 9.9053 -11.867315) (xy 9.943429 -11.961529)
			(xy 9.974207 -12.058395) (xy 9.997451 -12.157339) (xy 10.013025 -12.257776) (xy 10.020835 -12.359113)
			(xy 10.021316 -12.409932) (xy 10.020827 -12.461423) (xy 10.012809 -12.564093) (xy 9.996824 -12.665828)
			(xy 9.97297 -12.76601) (xy 9.941391 -12.864031) (xy 9.902278 -12.959297) (xy 9.855869 -13.05123)
			(xy 9.802446 -13.139272) (xy 9.742332 -13.222888) (xy 9.675892 -13.301572) (xy 9.640062 -13.338556)
			(xy 9.632696 -13.345668) (xy 9.62533 -13.363956) (xy 9.62533 -13.455904) (xy 9.632696 -13.474192)
			(xy 9.640062 -13.481304) (xy 9.67589 -13.51829) (xy 9.742331 -13.596973) (xy 9.802446 -13.680589)
			(xy 9.85587 -13.76863) (xy 9.902279 -13.860563) (xy 9.941392 -13.955829) (xy 9.97297 -14.05385) (xy 9.996824 -14.154032)
			(xy 10.012807 -14.255767) (xy 10.020823 -14.358437) (xy 10.021316 -14.409928) (xy 10.020824 -14.461419)
			(xy 10.012807 -14.564089) (xy 9.996822 -14.665824) (xy 9.972968 -14.766005) (xy 9.941389 -14.864027)
			(xy 9.902277 -14.959293) (xy 9.855868 -15.051226) (xy 9.802445 -15.139267) (xy 9.742332 -15.222884)
			(xy 9.675892 -15.301568) (xy 9.640062 -15.338552) (xy 9.632696 -15.345664) (xy 9.62533 -15.363952)
			(xy 9.62533 -15.4559) (xy 9.632696 -15.474188) (xy 9.640062 -15.4813) (xy 9.675893 -15.518283) (xy 9.742334 -15.596967)
			(xy 9.802448 -15.680583) (xy 9.855872 -15.768624) (xy 9.902281 -15.860557) (xy 9.941393 -15.955824)
			(xy 9.972972 -16.053845) (xy 9.996825 -16.154027) (xy 10.012808 -16.255762) (xy 10.020823 -16.358433)
			(xy 10.021316 -16.409924) (xy 10.020822 -16.461415) (xy 10.012804 -16.564085) (xy 9.99682 -16.665819)
			(xy 9.972967 -16.766001) (xy 9.941388 -16.864022) (xy 9.902276 -16.959288) (xy 9.864082 -17.034948)
			(xy 14.681196 -17.034948) (xy 14.681196 -16.950252) (xy 14.689247 -16.865938) (xy 14.705276 -16.782772)
			(xy 14.729137 -16.701505) (xy 14.760616 -16.622875) (xy 14.799427 -16.547594) (xy 14.845217 -16.476342)
			(xy 14.897573 -16.409766) (xy 14.956021 -16.348468) (xy 15.020031 -16.293003) (xy 15.089023 -16.243874)
			(xy 15.162373 -16.201525) (xy 15.239416 -16.166341) (xy 15.319455 -16.138639) (xy 15.401764 -16.118671)
			(xy 15.485599 -16.106618) (xy 15.5702 -16.102588) (xy 15.654801 -16.106618) (xy 15.738636 -16.118671)
			(xy 15.820945 -16.138639) (xy 15.900984 -16.166341) (xy 15.978027 -16.201525) (xy 16.00287 -16.215868)
			(xy 16.488156 -16.215868) (xy 16.48866 -16.17352) (xy 16.496711 -16.089206) (xy 16.51274 -16.00604)
			(xy 16.536601 -15.924773) (xy 16.56808 -15.846143) (xy 16.606891 -15.770862) (xy 16.652681 -15.69961)
			(xy 16.705037 -15.633034) (xy 16.763485 -15.571736) (xy 16.827495 -15.516271) (xy 16.896487 -15.467142)
			(xy 16.969837 -15.424793) (xy 17.04688 -15.389609) (xy 17.126919 -15.361907) (xy 17.209228 -15.341939)
			(xy 17.293063 -15.329886) (xy 17.377664 -15.325856) (xy 17.462265 -15.329886) (xy 17.5461 -15.341939)
			(xy 17.628409 -15.361907) (xy 17.708448 -15.389609) (xy 17.785491 -15.424793) (xy 17.858841 -15.467142)
			(xy 17.927833 -15.516271) (xy 17.991843 -15.571736) (xy 18.050291 -15.633034) (xy 18.102647 -15.69961)
			(xy 18.148437 -15.770862) (xy 18.187248 -15.846143) (xy 18.218727 -15.924773) (xy 18.242588 -16.00604)
			(xy 18.258617 -16.089206) (xy 18.266668 -16.17352) (xy 18.267172 -16.215868) (xy 18.266583 -16.260147)
			(xy 18.257792 -16.348268) (xy 18.257615 -16.349148) (xy 20.548596 -16.349148) (xy 20.548596 -16.264452)
			(xy 20.556647 -16.180138) (xy 20.572676 -16.096972) (xy 20.596537 -16.015705) (xy 20.628016 -15.937075)
			(xy 20.666827 -15.861794) (xy 20.712617 -15.790542) (xy 20.764973 -15.723966) (xy 20.823421 -15.662668)
			(xy 20.887431 -15.607203) (xy 20.956423 -15.558074) (xy 21.029773 -15.515725) (xy 21.106816 -15.480541)
			(xy 21.186855 -15.452839) (xy 21.269164 -15.432871) (xy 21.352999 -15.420818) (xy 21.4376 -15.416788)
			(xy 21.522201 -15.420818) (xy 21.606036 -15.432871) (xy 21.688345 -15.452839) (xy 21.768384 -15.480541)
			(xy 21.797855 -15.494) (xy 24.256492 -15.494) (xy 24.25695 -15.451946) (xy 24.264901 -15.368214)
			(xy 24.280721 -15.285607) (xy 24.30427 -15.204863) (xy 24.335337 -15.126703) (xy 24.373645 -15.051825)
			(xy 24.418851 -14.980898) (xy 24.470552 -14.914557) (xy 24.499062 -14.883638) (xy 24.504788 -14.87709)
			(xy 24.511824 -14.861195) (xy 24.51317 -14.843863) (xy 24.511254 -14.835378) (xy 24.501564 -14.797755)
			(xy 24.488025 -14.721246) (xy 24.481208 -14.643848) (xy 24.480774 -14.605) (xy 24.481278 -14.562652)
			(xy 24.489329 -14.478338) (xy 24.505358 -14.395172) (xy 24.529219 -14.313905) (xy 24.560698 -14.235275)
			(xy 24.599509 -14.159994) (xy 24.645299 -14.088742) (xy 24.697655 -14.022166) (xy 24.756103 -13.960868)
			(xy 24.820113 -13.905403) (xy 24.889105 -13.856274) (xy 24.962455 -13.813925) (xy 25.039498 -13.778741)
			(xy 25.119537 -13.751039) (xy 25.201846 -13.731071) (xy 25.285681 -13.719018) (xy 25.370282 -13.714988)
			(xy 25.454883 -13.719018) (xy 25.538718 -13.731071) (xy 25.621027 -13.751039) (xy 25.701066 -13.778741)
			(xy 25.778109 -13.813925) (xy 25.851459 -13.856274) (xy 25.920451 -13.905403) (xy 25.984461 -13.960868)
			(xy 26.042909 -14.022166) (xy 26.095265 -14.088742) (xy 26.141055 -14.159994) (xy 26.179866 -14.235275)
			(xy 26.211345 -14.313905) (xy 26.235206 -14.395172) (xy 26.251235 -14.478338) (xy 26.259286 -14.562652)
			(xy 26.25979 -14.605) (xy 26.25931 -14.647053) (xy 26.25136 -14.730784) (xy 26.235541 -14.81339)
			(xy 26.211995 -14.894133) (xy 26.180931 -14.972293) (xy 26.142626 -15.047171) (xy 26.097424 -15.118099)
			(xy 26.068399 -15.155348) (xy 30.479996 -15.155348) (xy 30.479996 -15.070652) (xy 30.488047 -14.986338)
			(xy 30.504076 -14.903172) (xy 30.527937 -14.821905) (xy 30.559416 -14.743275) (xy 30.598227 -14.667994)
			(xy 30.644017 -14.596742) (xy 30.696373 -14.530166) (xy 30.754821 -14.468868) (xy 30.818831 -14.413403)
			(xy 30.887823 -14.364274) (xy 30.961173 -14.321925) (xy 31.038216 -14.286741) (xy 31.118255 -14.259039)
			(xy 31.200564 -14.239071) (xy 31.284399 -14.227018) (xy 31.369 -14.222988) (xy 31.453601 -14.227018)
			(xy 31.537436 -14.239071) (xy 31.619745 -14.259039) (xy 31.699784 -14.286741) (xy 31.776827 -14.321925)
			(xy 31.850177 -14.364274) (xy 31.919169 -14.413403) (xy 31.983179 -14.468868) (xy 32.041627 -14.530166)
			(xy 32.093983 -14.596742) (xy 32.139773 -14.667994) (xy 32.178584 -14.743275) (xy 32.210063 -14.821905)
			(xy 32.233924 -14.903172) (xy 32.249953 -14.986338) (xy 32.258004 -15.070652) (xy 32.258508 -15.113)
			(xy 32.258004 -15.155348) (xy 32.249953 -15.239662) (xy 32.233924 -15.322828) (xy 32.210063 -15.404095)
			(xy 32.178584 -15.482725) (xy 32.139773 -15.558006) (xy 32.093983 -15.629258) (xy 32.041627 -15.695834)
			(xy 31.983179 -15.757132) (xy 31.919169 -15.812597) (xy 31.850177 -15.861726) (xy 31.776827 -15.904075)
			(xy 31.699784 -15.939259) (xy 31.619745 -15.966961) (xy 31.537436 -15.986929) (xy 31.453601 -15.998982)
			(xy 31.369 -16.003013) (xy 31.284399 -15.998982) (xy 31.200564 -15.986929) (xy 31.118255 -15.966961)
			(xy 31.038216 -15.939259) (xy 30.961173 -15.904075) (xy 30.887823 -15.861726) (xy 30.818831 -15.812597)
			(xy 30.754821 -15.757132) (xy 30.696373 -15.695834) (xy 30.644017 -15.629258) (xy 30.598227 -15.558006)
			(xy 30.559416 -15.482725) (xy 30.527937 -15.404095) (xy 30.504076 -15.322828) (xy 30.488047 -15.239662)
			(xy 30.479996 -15.155348) (xy 26.068399 -15.155348) (xy 26.045728 -15.184443) (xy 26.01722 -15.215362)
			(xy 26.011503 -15.221917) (xy 26.004457 -15.237808) (xy 26.00311 -15.255138) (xy 26.005028 -15.263622)
			(xy 26.014718 -15.301245) (xy 26.028257 -15.377754) (xy 26.035074 -15.455152) (xy 26.035508 -15.494)
			(xy 26.035004 -15.536348) (xy 26.026953 -15.620662) (xy 26.010924 -15.703828) (xy 25.987063 -15.785095)
			(xy 25.955584 -15.863725) (xy 25.916773 -15.939006) (xy 25.870983 -16.010258) (xy 25.818627 -16.076834)
			(xy 25.760179 -16.138132) (xy 25.696169 -16.193597) (xy 25.627177 -16.242726) (xy 25.553827 -16.285075)
			(xy 25.476784 -16.320259) (xy 25.396745 -16.347961) (xy 25.314436 -16.367929) (xy 25.230601 -16.379982)
			(xy 25.146 -16.384013) (xy 25.061399 -16.379982) (xy 24.977564 -16.367929) (xy 24.895255 -16.347961)
			(xy 24.815216 -16.320259) (xy 24.738173 -16.285075) (xy 24.664823 -16.242726) (xy 24.595831 -16.193597)
			(xy 24.531821 -16.138132) (xy 24.473373 -16.076834) (xy 24.421017 -16.010258) (xy 24.375227 -15.939006)
			(xy 24.336416 -15.863725) (xy 24.304937 -15.785095) (xy 24.281076 -15.703828) (xy 24.265047 -15.620662)
			(xy 24.256996 -15.536348) (xy 24.256492 -15.494) (xy 21.797855 -15.494) (xy 21.845427 -15.515725)
			(xy 21.918777 -15.558074) (xy 21.987769 -15.607203) (xy 22.051779 -15.662668) (xy 22.110227 -15.723966)
			(xy 22.162583 -15.790542) (xy 22.208373 -15.861794) (xy 22.247184 -15.937075) (xy 22.278663 -16.015705)
			(xy 22.302524 -16.096972) (xy 22.318553 -16.180138) (xy 22.326604 -16.264452) (xy 22.327108 -16.3068)
			(xy 22.326604 -16.349148) (xy 22.318553 -16.433462) (xy 22.302524 -16.516628) (xy 22.278663 -16.597895)
			(xy 22.247184 -16.676525) (xy 22.208373 -16.751806) (xy 22.162583 -16.823058) (xy 22.110227 -16.889634)
			(xy 22.051779 -16.950932) (xy 21.987769 -17.006397) (xy 21.918777 -17.055526) (xy 21.845427 -17.097875)
			(xy 21.768384 -17.133059) (xy 21.688345 -17.160761) (xy 21.606036 -17.180729) (xy 21.522201 -17.192782)
			(xy 21.4376 -17.196813) (xy 21.352999 -17.192782) (xy 21.269164 -17.180729) (xy 21.186855 -17.160761)
			(xy 21.106816 -17.133059) (xy 21.029773 -17.097875) (xy 20.956423 -17.055526) (xy 20.887431 -17.006397)
			(xy 20.823421 -16.950932) (xy 20.764973 -16.889634) (xy 20.712617 -16.823058) (xy 20.666827 -16.751806)
			(xy 20.628016 -16.676525) (xy 20.596537 -16.597895) (xy 20.572676 -16.516628) (xy 20.556647 -16.433462)
			(xy 20.548596 -16.349148) (xy 18.257615 -16.349148) (xy 18.240284 -16.435079) (xy 18.214232 -16.519719)
			(xy 18.179895 -16.601349) (xy 18.137612 -16.679162) (xy 18.087803 -16.752385) (xy 18.030961 -16.820294)
			(xy 17.96765 -16.882215) (xy 17.933416 -16.910304) (xy 17.924272 -16.91767) (xy 17.914366 -16.938752)
			(xy 17.915636 -17.042638) (xy 17.926304 -17.063466) (xy 17.935702 -17.070578) (xy 17.968164 -17.095732)
			(xy 18.028812 -17.151115) (xy 18.084096 -17.211853) (xy 18.133545 -17.277428) (xy 18.17674 -17.347282)
			(xy 18.213311 -17.42082) (xy 18.242949 -17.497417) (xy 18.265399 -17.576419) (xy 18.280471 -17.657154)
			(xy 18.288037 -17.738935) (xy 18.288508 -17.78) (xy 18.287945 -17.824782) (xy 18.278932 -17.913893)
			(xy 18.261009 -18.001646) (xy 18.234357 -18.087153) (xy 18.199246 -18.169549) (xy 18.15603 -18.247998)
			(xy 18.105149 -18.321707) (xy 18.047117 -18.389928) (xy 18.015204 -18.42135) (xy 18.006822 -18.429478)
			(xy 17.998694 -18.451322) (xy 18.008854 -18.553938) (xy 18.021046 -18.574004) (xy 18.030952 -18.5801)
			(xy 18.067468 -18.604091) (xy 18.136086 -18.658189) (xy 18.199072 -18.718752) (xy 18.255817 -18.785197)
			(xy 18.305776 -18.856885) (xy 18.348468 -18.933124) (xy 18.383482 -19.013181) (xy 18.397474 -19.054572)
			(xy 18.401284 -19.06651) (xy 18.418556 -19.083528) (xy 18.521426 -19.115786) (xy 18.545556 -19.111468)
			(xy 18.555462 -19.104102) (xy 18.588626 -19.079442) (xy 18.65875 -19.035698) (xy 18.732634 -18.998654)
			(xy 18.809637 -18.968631) (xy 18.889096 -18.945886) (xy 18.970323 -18.930618) (xy 19.052617 -18.922957)
			(xy 19.093942 -18.922492) (xy 19.136064 -18.922985) (xy 19.219932 -18.930945) (xy 19.302673 -18.946791)
			(xy 19.383548 -18.97038) (xy 19.422872 -18.985484) (xy 19.435572 -18.990564) (xy 19.46148 -18.987008)
			(xy 19.552412 -18.918682) (xy 19.562826 -18.894806) (xy 19.561556 -18.881344) (xy 19.559639 -18.86006)
			(xy 19.557606 -18.81737) (xy 19.557492 -18.796) (xy 19.557976 -18.754075) (xy 19.565867 -18.670596)
			(xy 19.581579 -18.588231) (xy 19.604972 -18.507709) (xy 19.63584 -18.429747) (xy 19.673907 -18.355036)
			(xy 19.718837 -18.284238) (xy 19.770229 -18.217983) (xy 19.827629 -18.156859) (xy 19.890526 -18.101407)
			(xy 19.958363 -18.052121) (xy 20.030537 -18.009438) (xy 20.106407 -17.973736) (xy 20.1853 -17.945332)
			(xy 20.266517 -17.924479) (xy 20.349335 -17.911362) (xy 20.43302 -17.906097) (xy 20.51683 -17.908731)
			(xy 20.600019 -17.91924) (xy 20.667669 -17.934362) (xy 33.527996 -17.934362) (xy 33.527996 -17.849666)
			(xy 33.536047 -17.765352) (xy 33.552076 -17.682186) (xy 33.575937 -17.600919) (xy 33.607416 -17.522289)
			(xy 33.646227 -17.447008) (xy 33.692017 -17.375756) (xy 33.744373 -17.30918) (xy 33.802821 -17.247882)
			(xy 33.866831 -17.192417) (xy 33.935823 -17.143288) (xy 34.009173 -17.100939) (xy 34.086216 -17.065755)
			(xy 34.166255 -17.038053) (xy 34.248564 -17.018085) (xy 34.332399 -17.006032) (xy 34.417 -17.002002)
			(xy 34.501601 -17.006032) (xy 34.585436 -17.018085) (xy 34.667745 -17.038053) (xy 34.747784 -17.065755)
			(xy 34.824827 -17.100939) (xy 34.898177 -17.143288) (xy 34.967169 -17.192417) (xy 35.031179 -17.247882)
			(xy 35.089627 -17.30918) (xy 35.141983 -17.375756) (xy 35.187773 -17.447008) (xy 35.226584 -17.522289)
			(xy 35.258063 -17.600919) (xy 35.281924 -17.682186) (xy 35.297953 -17.765352) (xy 35.306004 -17.849666)
			(xy 35.306508 -17.892014) (xy 35.306004 -17.934362) (xy 35.297953 -18.018676) (xy 35.281924 -18.101842)
			(xy 35.258063 -18.183109) (xy 35.226584 -18.261739) (xy 35.187773 -18.33702) (xy 35.141983 -18.408272)
			(xy 35.089627 -18.474848) (xy 35.031179 -18.536146) (xy 34.967169 -18.591611) (xy 34.898177 -18.64074)
			(xy 34.824827 -18.683089) (xy 34.747784 -18.718273) (xy 34.667745 -18.745975) (xy 34.585436 -18.765943)
			(xy 34.501601 -18.777996) (xy 34.417 -18.782027) (xy 34.332399 -18.777996) (xy 34.248564 -18.765943)
			(xy 34.166255 -18.745975) (xy 34.086216 -18.718273) (xy 34.009173 -18.683089) (xy 33.935823 -18.64074)
			(xy 33.866831 -18.591611) (xy 33.802821 -18.536146) (xy 33.744373 -18.474848) (xy 33.692017 -18.408272)
			(xy 33.646227 -18.33702) (xy 33.607416 -18.261739) (xy 33.575937 -18.183109) (xy 33.552076 -18.101842)
			(xy 33.536047 -18.018676) (xy 33.527996 -17.934362) (xy 20.667669 -17.934362) (xy 20.68185 -17.937532)
			(xy 20.761597 -17.963443) (xy 20.838551 -17.996744) (xy 20.91203 -18.03714) (xy 20.981382 -18.084271)
			(xy 21.04599 -18.137719) (xy 21.105281 -18.19701) (xy 21.158729 -18.261618) (xy 21.20586 -18.33097)
			(xy 21.246256 -18.404449) (xy 21.279557 -18.481403) (xy 21.305468 -18.56115) (xy 21.32376 -18.642981)
			(xy 21.334269 -18.72617) (xy 21.336903 -18.80998) (xy 21.331638 -18.893665) (xy 21.318521 -18.976483)
			(xy 21.297668 -19.0577) (xy 21.269264 -19.136593) (xy 21.233562 -19.212463) (xy 21.190879 -19.284637)
			(xy 21.176811 -19.304) (xy 27.684988 -19.304) (xy 27.689018 -19.219399) (xy 27.701071 -19.135564)
			(xy 27.721039 -19.053255) (xy 27.748741 -18.973216) (xy 27.783925 -18.896173) (xy 27.826274 -18.822823)
			(xy 27.875403 -18.753831) (xy 27.930868 -18.689821) (xy 27.992166 -18.631373) (xy 28.058742 -18.579017)
			(xy 28.129994 -18.533227) (xy 28.205275 -18.494416) (xy 28.283905 -18.462937) (xy 28.365172 -18.439076)
			(xy 28.448338 -18.423047) (xy 28.532652 -18.414996) (xy 28.575 -18.414492) (xy 28.617325 -18.414987)
			(xy 28.701594 -18.423) (xy 28.784723 -18.438973) (xy 28.865961 -18.462762) (xy 28.905454 -18.477992)
			(xy 28.917098 -18.481922) (xy 28.94152 -18.479521) (xy 28.95219 -18.47342) (xy 28.988628 -18.449924)
			(xy 29.065237 -18.409315) (xy 29.145435 -18.376354) (xy 29.22846 -18.351355) (xy 29.313524 -18.334555)
			(xy 29.399819 -18.326114) (xy 29.443172 -18.325592) (xy 29.48552 -18.326096) (xy 29.569834 -18.334147)
			(xy 29.653 -18.350176) (xy 29.734266 -18.374038) (xy 29.812896 -18.405517) (xy 29.888177 -18.444327)
			(xy 29.959429 -18.490118) (xy 30.026005 -18.542474) (xy 30.087303 -18.600922) (xy 30.142768 -18.664931)
			(xy 30.191897 -18.733924) (xy 30.234245 -18.807273) (xy 30.269429 -18.884316) (xy 30.297131 -18.964355)
			(xy 30.317099 -19.046664) (xy 30.329152 -19.130499) (xy 30.333183 -19.2151) (xy 30.329152 -19.299701)
			(xy 30.317099 -19.383536) (xy 30.297131 -19.465845) (xy 30.269429 -19.545884) (xy 30.234245 -19.622927)
			(xy 30.191897 -19.696276) (xy 30.169771 -19.727348) (xy 31.368996 -19.727348) (xy 31.368996 -19.642652)
			(xy 31.377047 -19.558338) (xy 31.393076 -19.475172) (xy 31.416937 -19.393905) (xy 31.448416 -19.315275)
			(xy 31.487227 -19.239994) (xy 31.533017 -19.168742) (xy 31.585373 -19.102166) (xy 31.643821 -19.040868)
			(xy 31.707831 -18.985403) (xy 31.776823 -18.936274) (xy 31.850173 -18.893925) (xy 31.927216 -18.858741)
			(xy 32.007255 -18.831039) (xy 32.089564 -18.811071) (xy 32.173399 -18.799018) (xy 32.258 -18.794988)
			(xy 32.342601 -18.799018) (xy 32.426436 -18.811071) (xy 32.508745 -18.831039) (xy 32.588784 -18.858741)
			(xy 32.665827 -18.893925) (xy 32.739177 -18.936274) (xy 32.747288 -18.94205) (xy 35.178492 -18.94205)
			(xy 35.178996 -18.899702) (xy 35.187047 -18.815388) (xy 35.203076 -18.732222) (xy 35.226937 -18.650955)
			(xy 35.258416 -18.572325) (xy 35.297227 -18.497044) (xy 35.343017 -18.425792) (xy 35.395373 -18.359216)
			(xy 35.453821 -18.297918) (xy 35.517831 -18.242453) (xy 35.586823 -18.193324) (xy 35.660173 -18.150975)
			(xy 35.737216 -18.115791) (xy 35.817255 -18.088089) (xy 35.899564 -18.068121) (xy 35.983399 -18.056068)
			(xy 36.068 -18.052038) (xy 36.152601 -18.056068) (xy 36.236436 -18.068121) (xy 36.318745 -18.088089)
			(xy 36.398784 -18.115791) (xy 36.475827 -18.150975) (xy 36.549177 -18.193324) (xy 36.618169 -18.242453)
			(xy 36.682179 -18.297918) (xy 36.740627 -18.359216) (xy 36.792983 -18.425792) (xy 36.838773 -18.497044)
			(xy 36.877584 -18.572325) (xy 36.909063 -18.650955) (xy 36.932924 -18.732222) (xy 36.948953 -18.815388)
			(xy 36.957004 -18.899702) (xy 36.957508 -18.94205) (xy 36.956977 -18.987453) (xy 36.947753 -19.077788)
			(xy 36.929365 -19.166712) (xy 36.902005 -19.253298) (xy 36.865959 -19.336642) (xy 36.821601 -19.415876)
			(xy 36.795964 -19.453352) (xy 36.790122 -19.46148) (xy 36.785804 -19.479768) (xy 36.797996 -19.567906)
			(xy 36.80714 -19.584416) (xy 36.81476 -19.590512) (xy 36.848418 -19.618592) (xy 36.91058 -19.680398)
			(xy 36.96636 -19.748021) (xy 37.015217 -19.820804) (xy 37.056675 -19.89804) (xy 37.090334 -19.97898)
			(xy 37.115867 -20.062839) (xy 37.133025 -20.148803) (xy 37.141643 -20.236038) (xy 37.142166 -20.279868)
			(xy 37.141662 -20.322216) (xy 37.133611 -20.40653) (xy 37.117582 -20.489696) (xy 37.093721 -20.570963)
			(xy 37.062242 -20.649593) (xy 37.023431 -20.724874) (xy 36.977641 -20.796126) (xy 36.925285 -20.862702)
			(xy 36.866837 -20.924) (xy 36.802827 -20.979465) (xy 36.733835 -21.028594) (xy 36.660485 -21.070943)
			(xy 36.583442 -21.106127) (xy 36.503403 -21.133829) (xy 36.421094 -21.153797) (xy 36.337259 -21.16585)
			(xy 36.252658 -21.169881) (xy 36.168057 -21.16585) (xy 36.084222 -21.153797) (xy 36.001913 -21.133829)
			(xy 35.921874 -21.106127) (xy 35.844831 -21.070943) (xy 35.771481 -21.028594) (xy 35.702489 -20.979465)
			(xy 35.638479 -20.924) (xy 35.580031 -20.862702) (xy 35.527675 -20.796126) (xy 35.481885 -20.724874)
			(xy 35.443074 -20.649593) (xy 35.411595 -20.570963) (xy 35.387734 -20.489696) (xy 35.371705 -20.40653)
			(xy 35.363654 -20.322216) (xy 35.36315 -20.279868) (xy 35.363698 -20.234466) (xy 35.37292 -20.144131)
			(xy 35.391305 -20.055207) (xy 35.418662 -19.968622) (xy 35.454705 -19.885278) (xy 35.499059 -19.806043)
			(xy 35.524694 -19.768566) (xy 35.530536 -19.760438) (xy 35.534854 -19.74215) (xy 35.522662 -19.654012)
			(xy 35.513518 -19.637502) (xy 35.505898 -19.631406) (xy 35.472262 -19.603301) (xy 35.410097 -19.541499)
			(xy 35.354314 -19.473881) (xy 35.305455 -19.401102) (xy 35.263993 -19.323869) (xy 35.230331 -19.242932)
			(xy 35.204796 -19.159075) (xy 35.187636 -19.073113) (xy 35.179016 -18.985879) (xy 35.178492 -18.94205)
			(xy 32.747288 -18.94205) (xy 32.808169 -18.985403) (xy 32.872179 -19.040868) (xy 32.930627 -19.102166)
			(xy 32.982983 -19.168742) (xy 33.028773 -19.239994) (xy 33.067584 -19.315275) (xy 33.099063 -19.393905)
			(xy 33.122924 -19.475172) (xy 33.138953 -19.558338) (xy 33.147004 -19.642652) (xy 33.147508 -19.685)
			(xy 33.147004 -19.727348) (xy 33.138953 -19.811662) (xy 33.122924 -19.894828) (xy 33.099063 -19.976095)
			(xy 33.067584 -20.054725) (xy 33.028773 -20.130006) (xy 32.982983 -20.201258) (xy 32.930627 -20.267834)
			(xy 32.872179 -20.329132) (xy 32.808169 -20.384597) (xy 32.739177 -20.433726) (xy 32.665827 -20.476075)
			(xy 32.588784 -20.511259) (xy 32.508745 -20.538961) (xy 32.426436 -20.558929) (xy 32.342601 -20.570982)
			(xy 32.258 -20.575013) (xy 32.173399 -20.570982) (xy 32.089564 -20.558929) (xy 32.007255 -20.538961)
			(xy 31.927216 -20.511259) (xy 31.850173 -20.476075) (xy 31.776823 -20.433726) (xy 31.707831 -20.384597)
			(xy 31.643821 -20.329132) (xy 31.585373 -20.267834) (xy 31.533017 -20.201258) (xy 31.487227 -20.130006)
			(xy 31.448416 -20.054725) (xy 31.416937 -19.976095) (xy 31.393076 -19.894828) (xy 31.377047 -19.811662)
			(xy 31.368996 -19.727348) (xy 30.169771 -19.727348) (xy 30.142768 -19.765269) (xy 30.087303 -19.829278)
			(xy 30.026005 -19.887726) (xy 29.959429 -19.940082) (xy 29.888177 -19.985873) (xy 29.812896 -20.024683)
			(xy 29.734266 -20.056162) (xy 29.653 -20.080024) (xy 29.569834 -20.096053) (xy 29.48552 -20.104104)
			(xy 29.443172 -20.104608) (xy 29.400847 -20.104122) (xy 29.316577 -20.096106) (xy 29.233449 -20.08013)
			(xy 29.152211 -20.056339) (xy 29.112718 -20.041108) (xy 29.101062 -20.037226) (xy 29.076652 -20.039596)
			(xy 29.065982 -20.04568) (xy 29.029551 -20.069188) (xy 28.95294 -20.109796) (xy 28.872741 -20.142754)
			(xy 28.789715 -20.167751) (xy 28.70465 -20.184549) (xy 28.618354 -20.192988) (xy 28.575 -20.193508)
			(xy 28.532652 -20.193004) (xy 28.448338 -20.184953) (xy 28.365172 -20.168924) (xy 28.283905 -20.145063)
			(xy 28.205275 -20.113584) (xy 28.129994 -20.074773) (xy 28.058742 -20.028983) (xy 27.992166 -19.976627)
			(xy 27.930868 -19.918179) (xy 27.875403 -19.854169) (xy 27.826274 -19.785177) (xy 27.783925 -19.711827)
			(xy 27.748741 -19.634784) (xy 27.721039 -19.554745) (xy 27.701071 -19.472436) (xy 27.689018 -19.388601)
			(xy 27.684988 -19.304) (xy 21.176811 -19.304) (xy 21.141593 -19.352474) (xy 21.086141 -19.415371)
			(xy 21.025017 -19.472771) (xy 20.958762 -19.524163) (xy 20.887964 -19.569093) (xy 20.813253 -19.60716)
			(xy 20.735291 -19.638028) (xy 20.654769 -19.661421) (xy 20.572404 -19.677133) (xy 20.488925 -19.685024)
			(xy 20.447 -19.685508) (xy 20.404878 -19.685002) (xy 20.321011 -19.677045) (xy 20.23827 -19.661204)
			(xy 20.157394 -19.637619) (xy 20.11807 -19.622516) (xy 20.10537 -19.617436) (xy 20.079462 -19.620992)
			(xy 19.98853 -19.689318) (xy 19.978116 -19.713194) (xy 19.979386 -19.726656) (xy 19.981303 -19.74794)
			(xy 19.983336 -19.79063) (xy 19.98345 -19.812) (xy 19.982933 -19.853101) (xy 19.975349 -19.934953)
			(xy 19.960245 -20.015756) (xy 19.93775 -20.094821) (xy 19.908055 -20.171473) (xy 19.871416 -20.245058)
			(xy 19.828143 -20.314949) (xy 19.778606 -20.380549) (xy 19.723228 -20.441298) (xy 19.662481 -20.496679)
			(xy 19.596883 -20.546219) (xy 19.526995 -20.589495) (xy 19.453411 -20.626139) (xy 19.376761 -20.655836)
			(xy 19.297697 -20.678335) (xy 19.216895 -20.693443) (xy 19.135043 -20.701031) (xy 19.093942 -20.701508)
			(xy 19.050935 -20.701028) (xy 18.96532 -20.692738) (xy 18.880906 -20.676222) (xy 18.798481 -20.651634)
			(xy 18.718814 -20.619204) (xy 18.64265 -20.579234) (xy 18.570701 -20.532099) (xy 18.503637 -20.478237)
			(xy 18.442087 -20.418154) (xy 18.386624 -20.352409) (xy 18.337767 -20.281616) (xy 18.295973 -20.206438)
			(xy 18.261631 -20.127577) (xy 18.247868 -20.086828) (xy 18.244058 -20.07489) (xy 18.226786 -20.057872)
			(xy 18.123916 -20.025614) (xy 18.099786 -20.029932) (xy 18.08988 -20.037298) (xy 18.056702 -20.061939)
			(xy 17.98658 -20.105685) (xy 17.9127 -20.142731) (xy 17.835698 -20.172757) (xy 17.756242 -20.195505)
			(xy 17.675017 -20.210776) (xy 17.592724 -20.218441) (xy 17.5514 -20.218908) (xy 17.510298 -20.218433)
			(xy 17.428443 -20.210848) (xy 17.347638 -20.195743) (xy 17.268571 -20.173247) (xy 17.191917 -20.143551)
			(xy 17.11833 -20.106909) (xy 17.048438 -20.063634) (xy 16.982837 -20.014094) (xy 16.922087 -19.958713)
			(xy 16.866706 -19.897963) (xy 16.817166 -19.832362) (xy 16.773891 -19.76247) (xy 16.737249 -19.688883)
			(xy 16.707553 -19.612229) (xy 16.685057 -19.533162) (xy 16.669952 -19.452357) (xy 16.662367 -19.370502)
			(xy 16.661892 -19.3294) (xy 16.662455 -19.284618) (xy 16.671468 -19.195507) (xy 16.689391 -19.107754)
			(xy 16.716043 -19.022247) (xy 16.751154 -18.939851) (xy 16.79437 -18.861402) (xy 16.845251 -18.787693)
			(xy 16.903283 -18.719472) (xy 16.935196 -18.68805) (xy 16.943578 -18.679922) (xy 16.951706 -18.658078)
			(xy 16.941546 -18.555462) (xy 16.929354 -18.535396) (xy 16.919448 -18.5293) (xy 16.885598 -18.507059)
			(xy 16.821634 -18.457362) (xy 16.762452 -18.402056) (xy 16.708542 -18.341599) (xy 16.660352 -18.276493)
			(xy 16.618279 -18.207275) (xy 16.582672 -18.13452) (xy 16.553827 -18.058829) (xy 16.531981 -17.980829)
			(xy 16.517315 -17.901166) (xy 16.509952 -17.820501) (xy 16.509492 -17.78) (xy 16.510033 -17.735719)
			(xy 16.518828 -17.647596) (xy 16.536341 -17.560784) (xy 16.562398 -17.476142) (xy 16.596741 -17.394511)
			(xy 16.639029 -17.316699) (xy 16.688845 -17.243477) (xy 16.745693 -17.17557) (xy 16.809011 -17.113651)
			(xy 16.843248 -17.085564) (xy 16.852392 -17.078198) (xy 16.862298 -17.057116) (xy 16.861028 -16.95323)
			(xy 16.85036 -16.932402) (xy 16.840962 -16.92529) (xy 16.808511 -16.900121) (xy 16.747863 -16.84474)
			(xy 16.692579 -16.784004) (xy 16.643128 -16.718431) (xy 16.599932 -16.648579) (xy 16.563359 -16.575042)
			(xy 16.533721 -16.498447) (xy 16.511269 -16.419447) (xy 16.496195 -16.338712) (xy 16.488627 -16.256933)
			(xy 16.488156 -16.215868) (xy 16.00287 -16.215868) (xy 16.051377 -16.243874) (xy 16.120369 -16.293003)
			(xy 16.184379 -16.348468) (xy 16.242827 -16.409766) (xy 16.295183 -16.476342) (xy 16.340973 -16.547594)
			(xy 16.379784 -16.622875) (xy 16.411263 -16.701505) (xy 16.435124 -16.782772) (xy 16.451153 -16.865938)
			(xy 16.459204 -16.950252) (xy 16.459708 -16.9926) (xy 16.459204 -17.034948) (xy 16.451153 -17.119262)
			(xy 16.435124 -17.202428) (xy 16.411263 -17.283695) (xy 16.379784 -17.362325) (xy 16.340973 -17.437606)
			(xy 16.295183 -17.508858) (xy 16.242827 -17.575434) (xy 16.184379 -17.636732) (xy 16.120369 -17.692197)
			(xy 16.051377 -17.741326) (xy 15.978027 -17.783675) (xy 15.900984 -17.818859) (xy 15.820945 -17.846561)
			(xy 15.738636 -17.866529) (xy 15.654801 -17.878582) (xy 15.5702 -17.882613) (xy 15.485599 -17.878582)
			(xy 15.401764 -17.866529) (xy 15.319455 -17.846561) (xy 15.239416 -17.818859) (xy 15.162373 -17.783675)
			(xy 15.089023 -17.741326) (xy 15.020031 -17.692197) (xy 14.956021 -17.636732) (xy 14.897573 -17.575434)
			(xy 14.845217 -17.508858) (xy 14.799427 -17.437606) (xy 14.760616 -17.362325) (xy 14.729137 -17.283695)
			(xy 14.705276 -17.202428) (xy 14.689247 -17.119262) (xy 14.681196 -17.034948) (xy 9.864082 -17.034948)
			(xy 9.855867 -17.051221) (xy 9.802445 -17.139263) (xy 9.742331 -17.22288) (xy 9.675892 -17.301564)
			(xy 9.640062 -17.338548) (xy 9.632696 -17.34566) (xy 9.62533 -17.363948) (xy 9.62533 -17.455896)
			(xy 9.632696 -17.474184) (xy 9.640062 -17.481296) (xy 9.675893 -17.518279) (xy 9.742333 -17.596963)
			(xy 9.802447 -17.680579) (xy 9.85587 -17.768621) (xy 9.902278 -17.860554) (xy 9.94139 -17.95582)
			(xy 9.972969 -18.053842) (xy 9.996822 -18.154024) (xy 10.012804 -18.255759) (xy 10.02082 -18.358429)
			(xy 10.02082 -18.461411) (xy 10.012804 -18.564081) (xy 9.996822 -18.665816) (xy 9.972969 -18.765998)
			(xy 9.94139 -18.86402) (xy 9.902278 -18.959286) (xy 9.85587 -19.051219) (xy 9.802447 -19.139261)
			(xy 9.742333 -19.222877) (xy 9.675893 -19.301561) (xy 9.640062 -19.338544) (xy 9.632696 -19.345656)
			(xy 9.62533 -19.363944) (xy 9.62533 -19.455892) (xy 9.632696 -19.47418) (xy 9.640062 -19.481292)
			(xy 9.675889 -19.518279) (xy 9.742329 -19.596963) (xy 9.802443 -19.680579) (xy 9.855866 -19.76862)
			(xy 9.902275 -19.860553) (xy 9.941387 -19.955819) (xy 9.972965 -20.05384) (xy 9.996818 -20.154022)
			(xy 10.010603 -20.241768) (xy 14.471142 -20.241768) (xy 14.471646 -20.19942) (xy 14.479697 -20.115106)
			(xy 14.495726 -20.03194) (xy 14.519587 -19.950673) (xy 14.551066 -19.872043) (xy 14.589877 -19.796762)
			(xy 14.635667 -19.72551) (xy 14.688023 -19.658934) (xy 14.746471 -19.597636) (xy 14.810481 -19.542171)
			(xy 14.879473 -19.493042) (xy 14.952823 -19.450693) (xy 15.029866 -19.415509) (xy 15.109905 -19.387807)
			(xy 15.192214 -19.367839) (xy 15.276049 -19.355786) (xy 15.36065 -19.351756) (xy 15.445251 -19.355786)
			(xy 15.529086 -19.367839) (xy 15.611395 -19.387807) (xy 15.691434 -19.415509) (xy 15.768477 -19.450693)
			(xy 15.841827 -19.493042) (xy 15.910819 -19.542171) (xy 15.974829 -19.597636) (xy 16.033277 -19.658934)
			(xy 16.085633 -19.72551) (xy 16.131423 -19.796762) (xy 16.170234 -19.872043) (xy 16.201713 -19.950673)
			(xy 16.225574 -20.03194) (xy 16.241603 -20.115106) (xy 16.249654 -20.19942) (xy 16.250158 -20.241768)
			(xy 16.24972 -20.281962) (xy 16.24247 -20.362023) (xy 16.228027 -20.441103) (xy 16.206508 -20.518558)
			(xy 16.17809 -20.593756) (xy 16.143002 -20.666082) (xy 16.12265 -20.700746) (xy 16.117354 -20.710681)
			(xy 16.114962 -20.733033) (xy 16.122326 -20.754273) (xy 16.129762 -20.762722) (xy 16.159521 -20.793855)
			(xy 16.213531 -20.860949) (xy 16.260802 -20.932949) (xy 16.300891 -21.009181) (xy 16.333423 -21.088932)
			(xy 16.358094 -21.171455) (xy 16.374671 -21.255975) (xy 16.383 -21.341703) (xy 16.383508 -21.384768)
			(xy 16.383004 -21.427116) (xy 16.374953 -21.51143) (xy 16.358924 -21.594596) (xy 16.335063 -21.675863)
			(xy 16.303584 -21.754493) (xy 16.264773 -21.829774) (xy 16.218983 -21.901026) (xy 16.166627 -21.967602)
			(xy 16.108179 -22.0289) (xy 16.044169 -22.084365) (xy 15.992304 -22.121298) (xy 19.303996 -22.121298)
			(xy 19.303996 -22.036602) (xy 19.312047 -21.952288) (xy 19.328076 -21.869122) (xy 19.351937 -21.787855)
			(xy 19.383416 -21.709225) (xy 19.422227 -21.633944) (xy 19.468017 -21.562692) (xy 19.520373 -21.496116)
			(xy 19.578821 -21.434818) (xy 19.642831 -21.379353) (xy 19.711823 -21.330224) (xy 19.785173 -21.287875)
			(xy 19.862216 -21.252691) (xy 19.942255 -21.224989) (xy 20.024564 -21.205021) (xy 20.108399 -21.192968)
			(xy 20.193 -21.188938) (xy 20.277601 -21.192968) (xy 20.330324 -21.200548) (xy 21.335996 -21.200548)
			(xy 21.335996 -21.115852) (xy 21.344047 -21.031538) (xy 21.360076 -20.948372) (xy 21.383937 -20.867105)
			(xy 21.415416 -20.788475) (xy 21.454227 -20.713194) (xy 21.500017 -20.641942) (xy 21.552373 -20.575366)
			(xy 21.610821 -20.514068) (xy 21.674831 -20.458603) (xy 21.743823 -20.409474) (xy 21.817173 -20.367125)
			(xy 21.894216 -20.331941) (xy 21.974255 -20.304239) (xy 22.056564 -20.284271) (xy 22.140399 -20.272218)
			(xy 22.225 -20.268188) (xy 22.309601 -20.272218) (xy 22.393436 -20.284271) (xy 22.475745 -20.304239)
			(xy 22.555784 -20.331941) (xy 22.632827 -20.367125) (xy 22.706177 -20.409474) (xy 22.775169 -20.458603)
			(xy 22.839179 -20.514068) (xy 22.897627 -20.575366) (xy 22.949983 -20.641942) (xy 22.995773 -20.713194)
			(xy 23.034584 -20.788475) (xy 23.066063 -20.867105) (xy 23.089924 -20.948372) (xy 23.105953 -21.031538)
			(xy 23.114004 -21.115852) (xy 23.114508 -21.1582) (xy 23.114004 -21.200548) (xy 23.109153 -21.251348)
			(xy 29.203646 -21.251348) (xy 29.203646 -21.166652) (xy 29.211697 -21.082338) (xy 29.227726 -20.999172)
			(xy 29.251587 -20.917905) (xy 29.283066 -20.839275) (xy 29.321877 -20.763994) (xy 29.367667 -20.692742)
			(xy 29.420023 -20.626166) (xy 29.478471 -20.564868) (xy 29.542481 -20.509403) (xy 29.611473 -20.460274)
			(xy 29.684823 -20.417925) (xy 29.761866 -20.382741) (xy 29.841905 -20.355039) (xy 29.924214 -20.335071)
			(xy 30.008049 -20.323018) (xy 30.09265 -20.318988) (xy 30.177251 -20.323018) (xy 30.261086 -20.335071)
			(xy 30.343395 -20.355039) (xy 30.423434 -20.382741) (xy 30.500477 -20.417925) (xy 30.573827 -20.460274)
			(xy 30.642819 -20.509403) (xy 30.706829 -20.564868) (xy 30.765277 -20.626166) (xy 30.817633 -20.692742)
			(xy 30.863423 -20.763994) (xy 30.902234 -20.839275) (xy 30.933713 -20.917905) (xy 30.957574 -20.999172)
			(xy 30.973603 -21.082338) (xy 30.981654 -21.166652) (xy 30.982158 -21.209) (xy 30.981654 -21.251348)
			(xy 30.973603 -21.335662) (xy 30.957574 -21.418828) (xy 30.933713 -21.500095) (xy 30.902234 -21.578725)
			(xy 30.863423 -21.654006) (xy 30.817633 -21.725258) (xy 30.765277 -21.791834) (xy 30.706829 -21.853132)
			(xy 30.642819 -21.908597) (xy 30.573827 -21.957726) (xy 30.500477 -22.000075) (xy 30.423434 -22.035259)
			(xy 30.343395 -22.062961) (xy 30.261086 -22.082929) (xy 30.177251 -22.094982) (xy 30.09265 -22.099013)
			(xy 30.008049 -22.094982) (xy 29.924214 -22.082929) (xy 29.841905 -22.062961) (xy 29.761866 -22.035259)
			(xy 29.684823 -22.000075) (xy 29.611473 -21.957726) (xy 29.542481 -21.908597) (xy 29.478471 -21.853132)
			(xy 29.420023 -21.791834) (xy 29.367667 -21.725258) (xy 29.321877 -21.654006) (xy 29.283066 -21.578725)
			(xy 29.251587 -21.500095) (xy 29.227726 -21.418828) (xy 29.211697 -21.335662) (xy 29.203646 -21.251348)
			(xy 23.109153 -21.251348) (xy 23.105953 -21.284862) (xy 23.089924 -21.368028) (xy 23.066063 -21.449295)
			(xy 23.034584 -21.527925) (xy 22.995773 -21.603206) (xy 22.949983 -21.674458) (xy 22.897627 -21.741034)
			(xy 22.839179 -21.802332) (xy 22.775169 -21.857797) (xy 22.706177 -21.906926) (xy 22.632827 -21.949275)
			(xy 22.555784 -21.984459) (xy 22.475745 -22.012161) (xy 22.393436 -22.032129) (xy 22.309601 -22.044182)
			(xy 22.225 -22.048213) (xy 22.140399 -22.044182) (xy 22.056564 -22.032129) (xy 21.974255 -22.012161)
			(xy 21.894216 -21.984459) (xy 21.817173 -21.949275) (xy 21.743823 -21.906926) (xy 21.674831 -21.857797)
			(xy 21.610821 -21.802332) (xy 21.552373 -21.741034) (xy 21.500017 -21.674458) (xy 21.454227 -21.603206)
			(xy 21.415416 -21.527925) (xy 21.383937 -21.449295) (xy 21.360076 -21.368028) (xy 21.344047 -21.284862)
			(xy 21.335996 -21.200548) (xy 20.330324 -21.200548) (xy 20.361436 -21.205021) (xy 20.443745 -21.224989)
			(xy 20.523784 -21.252691) (xy 20.600827 -21.287875) (xy 20.674177 -21.330224) (xy 20.743169 -21.379353)
			(xy 20.807179 -21.434818) (xy 20.865627 -21.496116) (xy 20.917983 -21.562692) (xy 20.963773 -21.633944)
			(xy 21.002584 -21.709225) (xy 21.034063 -21.787855) (xy 21.057924 -21.869122) (xy 21.073953 -21.952288)
			(xy 21.082004 -22.036602) (xy 21.082508 -22.07895) (xy 21.082004 -22.121298) (xy 21.073953 -22.205612)
			(xy 21.057924 -22.288778) (xy 21.034063 -22.370045) (xy 21.002584 -22.448675) (xy 20.963773 -22.523956)
			(xy 20.917983 -22.595208) (xy 20.865627 -22.661784) (xy 20.807179 -22.723082) (xy 20.743169 -22.778547)
			(xy 20.674177 -22.827676) (xy 20.600827 -22.870025) (xy 20.523784 -22.905209) (xy 20.443745 -22.932911)
			(xy 20.361436 -22.952879) (xy 20.277601 -22.964932) (xy 20.193 -22.968963) (xy 20.108399 -22.964932)
			(xy 20.024564 -22.952879) (xy 19.942255 -22.932911) (xy 19.862216 -22.905209) (xy 19.785173 -22.870025)
			(xy 19.711823 -22.827676) (xy 19.642831 -22.778547) (xy 19.578821 -22.723082) (xy 19.520373 -22.661784)
			(xy 19.468017 -22.595208) (xy 19.422227 -22.523956) (xy 19.383416 -22.448675) (xy 19.351937 -22.370045)
			(xy 19.328076 -22.288778) (xy 19.312047 -22.205612) (xy 19.303996 -22.121298) (xy 15.992304 -22.121298)
			(xy 15.975177 -22.133494) (xy 15.901827 -22.175843) (xy 15.824784 -22.211027) (xy 15.744745 -22.238729)
			(xy 15.662436 -22.258697) (xy 15.578601 -22.27075) (xy 15.494 -22.274781) (xy 15.409399 -22.27075)
			(xy 15.325564 -22.258697) (xy 15.243255 -22.238729) (xy 15.163216 -22.211027) (xy 15.086173 -22.175843)
			(xy 15.012823 -22.133494) (xy 14.943831 -22.084365) (xy 14.879821 -22.0289) (xy 14.821373 -21.967602)
			(xy 14.769017 -21.901026) (xy 14.723227 -21.829774) (xy 14.684416 -21.754493) (xy 14.652937 -21.675863)
			(xy 14.629076 -21.594596) (xy 14.613047 -21.51143) (xy 14.604996 -21.427116) (xy 14.604492 -21.384768)
			(xy 14.60494 -21.344574) (xy 14.612187 -21.264513) (xy 14.626627 -21.185433) (xy 14.648144 -21.107978)
			(xy 14.676562 -21.03278) (xy 14.711648 -20.960453) (xy 14.732 -20.92579) (xy 14.737367 -20.915886)
			(xy 14.739741 -20.893511) (xy 14.732343 -20.87226) (xy 14.724888 -20.863814) (xy 14.695155 -20.832656)
			(xy 14.641142 -20.765567) (xy 14.593868 -20.693572) (xy 14.553775 -20.617343) (xy 14.52124 -20.537595)
			(xy 14.496565 -20.455076) (xy 14.479984 -20.370558) (xy 14.471651 -20.284833) (xy 14.471142 -20.241768)
			(xy 10.010603 -20.241768) (xy 10.012801 -20.255756) (xy 10.020817 -20.358426) (xy 10.020817 -20.461408)
			(xy 10.012802 -20.564078) (xy 9.996819 -20.665813) (xy 9.972967 -20.765995) (xy 9.941389 -20.864016)
			(xy 9.902277 -20.959282) (xy 9.855869 -21.051215) (xy 9.802446 -21.139257) (xy 9.742332 -21.222873)
			(xy 9.675892 -21.301557) (xy 9.640062 -21.33854) (xy 9.632696 -21.345652) (xy 9.62533 -21.36394)
			(xy 9.62533 -21.455888) (xy 9.632696 -21.474176) (xy 9.640062 -21.481288) (xy 9.675895 -21.518269)
			(xy 9.742335 -21.596953) (xy 9.802449 -21.68057) (xy 9.855872 -21.768612) (xy 9.90228 -21.860545)
			(xy 9.941392 -21.955811) (xy 9.97297 -22.053833) (xy 9.996823 -22.154015) (xy 10.012806 -22.25575)
			(xy 10.020822 -22.35842) (xy 10.020821 -22.461403) (xy 10.012806 -22.564073) (xy 9.996823 -22.665808)
			(xy 9.97297 -22.76599) (xy 9.941391 -22.864011) (xy 9.902279 -22.959278) (xy 9.85587 -23.051211)
			(xy 9.802447 -23.139253) (xy 9.742333 -23.222869) (xy 9.675893 -23.301553) (xy 9.640062 -23.338536)
			(xy 9.632696 -23.345648) (xy 9.62533 -23.363936) (xy 9.62533 -23.455884) (xy 9.632696 -23.474172)
			(xy 9.640062 -23.481284) (xy 9.675891 -23.518269) (xy 9.742331 -23.596953) (xy 9.802445 -23.680569)
			(xy 9.855868 -23.768611) (xy 9.902277 -23.860543) (xy 9.941389 -23.955809) (xy 9.972967 -24.053831)
			(xy 9.99682 -24.154013) (xy 10.012803 -24.255747) (xy 10.020819 -24.358417) (xy 10.020819 -24.4614)
			(xy 10.012803 -24.56407) (xy 9.99682 -24.665804) (xy 9.973203 -24.765) (xy 14.731492 -24.765) (xy 14.731926 -24.721812)
			(xy 14.740292 -24.635843) (xy 14.756955 -24.55109) (xy 14.781757 -24.468352) (xy 14.814465 -24.38841)
			(xy 14.854771 -24.312015) (xy 14.902295 -24.239889) (xy 14.956589 -24.172711) (xy 15.017141 -24.111115)
			(xy 15.083381 -24.05568) (xy 15.154683 -24.006929) (xy 15.230377 -23.965322) (xy 15.309749 -23.931252)
			(xy 15.350744 -23.917656) (xy 15.360396 -23.914354) (xy 15.37589 -23.9014) (xy 15.418054 -23.819104)
			(xy 15.419578 -23.799038) (xy 15.41653 -23.789386) (xy 15.402639 -23.74483) (xy 15.383202 -23.65354)
			(xy 15.373433 -23.560718) (xy 15.372842 -23.51405) (xy 15.373346 -23.471702) (xy 15.381397 -23.387388)
			(xy 15.397426 -23.304222) (xy 15.421287 -23.222955) (xy 15.452766 -23.144325) (xy 15.491577 -23.069044)
			(xy 15.537367 -22.997792) (xy 15.589723 -22.931216) (xy 15.648171 -22.869918) (xy 15.712181 -22.814453)
			(xy 15.781173 -22.765324) (xy 15.854523 -22.722975) (xy 15.931566 -22.687791) (xy 16.011605 -22.660089)
			(xy 16.093914 -22.640121) (xy 16.177749 -22.628068) (xy 16.26235 -22.624038) (xy 16.346951 -22.628068)
			(xy 16.430786 -22.640121) (xy 16.513095 -22.660089) (xy 16.593134 -22.687791) (xy 16.670177 -22.722975)
			(xy 16.743527 -22.765324) (xy 16.812519 -22.814453) (xy 16.876529 -22.869918) (xy 16.934977 -22.931216)
			(xy 16.987333 -22.997792) (xy 17.033123 -23.069044) (xy 17.071934 -23.144325) (xy 17.103413 -23.222955)
			(xy 17.127274 -23.304222) (xy 17.143303 -23.387388) (xy 17.151354 -23.471702) (xy 17.151858 -23.51405)
			(xy 17.151344 -23.557236) (xy 17.142984 -23.643201) (xy 17.126327 -23.727951) (xy 17.10153 -23.810686)
			(xy 17.068828 -23.890627) (xy 17.028529 -23.967021) (xy 17.017255 -23.984134) (xy 17.310096 -23.984134)
			(xy 17.310096 -23.899438) (xy 17.318147 -23.815124) (xy 17.334176 -23.731958) (xy 17.358037 -23.650691)
			(xy 17.389516 -23.572061) (xy 17.428327 -23.49678) (xy 17.474117 -23.425528) (xy 17.526473 -23.358952)
			(xy 17.584921 -23.297654) (xy 17.648931 -23.242189) (xy 17.717923 -23.19306) (xy 17.791273 -23.150711)
			(xy 17.868316 -23.115527) (xy 17.948355 -23.087825) (xy 18.030664 -23.067857) (xy 18.114499 -23.055804)
			(xy 18.1991 -23.051774) (xy 18.283701 -23.055804) (xy 18.367536 -23.067857) (xy 18.449845 -23.087825)
			(xy 18.529884 -23.115527) (xy 18.606927 -23.150711) (xy 18.680277 -23.19306) (xy 18.749269 -23.242189)
			(xy 18.813279 -23.297654) (xy 18.871727 -23.358952) (xy 18.878842 -23.368) (xy 20.953988 -23.368)
			(xy 20.958018 -23.283399) (xy 20.970071 -23.199564) (xy 20.990039 -23.117255) (xy 21.017741 -23.037216)
			(xy 21.052925 -22.960173) (xy 21.095274 -22.886823) (xy 21.144403 -22.817831) (xy 21.199868 -22.753821)
			(xy 21.261166 -22.695373) (xy 21.327742 -22.643017) (xy 21.398994 -22.597227) (xy 21.474275 -22.558416)
			(xy 21.552905 -22.526937) (xy 21.634172 -22.503076) (xy 21.717338 -22.487047) (xy 21.801652 -22.478996)
			(xy 21.844 -22.478492) (xy 21.885264 -22.478992) (xy 21.967435 -22.486644) (xy 22.048545 -22.501875)
			(xy 22.127895 -22.524553) (xy 22.204804 -22.554482) (xy 22.240115 -22.572148) (xy 27.558996 -22.572148)
			(xy 27.558996 -22.487452) (xy 27.567047 -22.403138) (xy 27.583076 -22.319972) (xy 27.606937 -22.238705)
			(xy 27.638416 -22.160075) (xy 27.677227 -22.084794) (xy 27.723017 -22.013542) (xy 27.775373 -21.946966)
			(xy 27.833821 -21.885668) (xy 27.897831 -21.830203) (xy 27.966823 -21.781074) (xy 28.040173 -21.738725)
			(xy 28.117216 -21.703541) (xy 28.197255 -21.675839) (xy 28.279564 -21.655871) (xy 28.363399 -21.643818)
			(xy 28.448 -21.639788) (xy 28.532601 -21.643818) (xy 28.616436 -21.655871) (xy 28.698745 -21.675839)
			(xy 28.778784 -21.703541) (xy 28.855827 -21.738725) (xy 28.929177 -21.781074) (xy 28.998169 -21.830203)
			(xy 29.062179 -21.885668) (xy 29.120627 -21.946966) (xy 29.172983 -22.013542) (xy 29.218773 -22.084794)
			(xy 29.257584 -22.160075) (xy 29.289063 -22.238705) (xy 29.312924 -22.319972) (xy 29.328953 -22.403138)
			(xy 29.337004 -22.487452) (xy 29.337508 -22.5298) (xy 29.337004 -22.572148) (xy 29.328953 -22.656462)
			(xy 29.312924 -22.739628) (xy 29.289063 -22.820895) (xy 29.257584 -22.899525) (xy 29.218773 -22.974806)
			(xy 29.172983 -23.046058) (xy 29.120627 -23.112634) (xy 29.062179 -23.173932) (xy 28.998169 -23.229397)
			(xy 28.929177 -23.278526) (xy 28.855827 -23.320875) (xy 28.778784 -23.356059) (xy 28.698745 -23.383761)
			(xy 28.616436 -23.403729) (xy 28.532601 -23.415782) (xy 28.448 -23.419813) (xy 28.363399 -23.415782)
			(xy 28.279564 -23.403729) (xy 28.197255 -23.383761) (xy 28.117216 -23.356059) (xy 28.040173 -23.320875)
			(xy 27.966823 -23.278526) (xy 27.897831 -23.229397) (xy 27.833821 -23.173932) (xy 27.775373 -23.112634)
			(xy 27.723017 -23.046058) (xy 27.677227 -22.974806) (xy 27.638416 -22.899525) (xy 27.606937 -22.820895)
			(xy 27.583076 -22.739628) (xy 27.567047 -22.656462) (xy 27.558996 -22.572148) (xy 22.240115 -22.572148)
			(xy 22.27861 -22.591407) (xy 22.348678 -22.635008) (xy 22.414408 -22.684912) (xy 22.475232 -22.740689)
			(xy 22.530629 -22.80186) (xy 22.580123 -22.867899) (xy 22.623287 -22.938238) (xy 22.65975 -23.012273)
			(xy 22.6892 -23.089367) (xy 22.700742 -23.128986) (xy 22.703536 -23.139146) (xy 22.716744 -23.155402)
			(xy 22.80158 -23.199344) (xy 22.822408 -23.200868) (xy 22.832568 -23.197312) (xy 22.868325 -23.185113)
			(xy 22.941449 -23.166088) (xy 23.015921 -23.153326) (xy 23.091207 -23.146916) (xy 23.128986 -23.146512)
			(xy 23.17009 -23.146966) (xy 23.251946 -23.15455) (xy 23.332753 -23.169654) (xy 23.411822 -23.19215)
			(xy 23.488478 -23.221847) (xy 23.562067 -23.258489) (xy 23.631961 -23.301765) (xy 23.697564 -23.351306)
			(xy 23.758315 -23.406689) (xy 23.813698 -23.467441) (xy 23.863238 -23.533044) (xy 23.906514 -23.602938)
			(xy 23.943156 -23.676527) (xy 23.972851 -23.753183) (xy 23.995347 -23.832252) (xy 24.010451 -23.91306)
			(xy 24.013442 -23.945342) (xy 32.727392 -23.945342) (xy 32.727892 -23.90424) (xy 32.735473 -23.822385)
			(xy 32.750575 -23.741579) (xy 32.773069 -23.662511) (xy 32.802762 -23.585857) (xy 32.839401 -23.512269)
			(xy 32.882674 -23.442375) (xy 32.932212 -23.376773) (xy 32.987592 -23.316021) (xy 33.048341 -23.260639)
			(xy 33.11394 -23.211098) (xy 33.183832 -23.167822) (xy 33.257418 -23.131179) (xy 33.334072 -23.101482)
			(xy 33.413138 -23.078985) (xy 33.493943 -23.063879) (xy 33.575798 -23.056294) (xy 33.6169 -23.055834)
			(xy 33.661262 -23.056393) (xy 33.749544 -23.065224) (xy 33.836509 -23.082797) (xy 33.921294 -23.108939)
			(xy 34.003055 -23.14339) (xy 34.080982 -23.185807) (xy 34.154299 -23.23577) (xy 34.22228 -23.292782)
			(xy 34.284249 -23.356277) (xy 34.312352 -23.390606) (xy 34.319972 -23.400258) (xy 34.341816 -23.410418)
			(xy 34.448496 -23.405592) (xy 34.469578 -23.393908) (xy 34.476436 -23.383494) (xy 34.501139 -23.347356)
			(xy 34.556528 -23.279564) (xy 34.618309 -23.217542) (xy 34.685886 -23.161892) (xy 34.758604 -23.11315)
			(xy 34.835759 -23.07179) (xy 34.916605 -23.038211) (xy 35.000359 -23.012738) (xy 35.086211 -22.995617)
			(xy 35.173329 -22.987016) (xy 35.2171 -22.986492) (xy 35.260329 -22.986995) (xy 35.346379 -22.995397)
			(xy 35.431207 -23.012112) (xy 35.514011 -23.036982) (xy 35.594011 -23.069772) (xy 35.67045 -23.110173)
			(xy 35.706812 -23.133558) (xy 35.715377 -23.138617) (xy 35.734879 -23.142434) (xy 35.754381 -23.138617)
			(xy 35.762946 -23.133558) (xy 35.799321 -23.110197) (xy 35.875764 -23.069812) (xy 35.955763 -23.03703)
			(xy 36.038564 -23.012161) (xy 36.123386 -22.995439) (xy 36.209431 -22.987022) (xy 36.252658 -22.986492)
			(xy 36.29376 -22.986992) (xy 36.375615 -22.994573) (xy 36.456421 -23.009675) (xy 36.535489 -23.032169)
			(xy 36.612143 -23.061862) (xy 36.685731 -23.098501) (xy 36.755625 -23.141774) (xy 36.821227 -23.191312)
			(xy 36.881979 -23.246692) (xy 36.937361 -23.307441) (xy 36.986902 -23.37304) (xy 37.030178 -23.442932)
			(xy 37.066821 -23.516518) (xy 37.096518 -23.593172) (xy 37.119015 -23.672238) (xy 37.134121 -23.753043)
			(xy 37.141706 -23.834898) (xy 37.142166 -23.876) (xy 37.141636 -23.919075) (xy 37.133298 -24.004822)
			(xy 37.116711 -24.089361) (xy 37.09203 -24.1719) (xy 37.059485 -24.251667) (xy 37.019382 -24.327915)
			(xy 36.972097 -24.399929) (xy 36.918072 -24.467035) (xy 36.857812 -24.528605) (xy 36.825174 -24.55672)
			(xy 36.818373 -24.562958) (xy 36.809379 -24.579057) (xy 36.806665 -24.597298) (xy 36.810581 -24.615318)
			(xy 36.815268 -24.623268) (xy 36.837907 -24.659258) (xy 36.876998 -24.73477) (xy 36.908707 -24.813666)
			(xy 36.932747 -24.895228) (xy 36.948897 -24.97871) (xy 36.957011 -25.063353) (xy 36.957508 -25.105868)
			(xy 36.957036 -25.146439) (xy 36.949615 -25.22724) (xy 36.934868 -25.30703) (xy 36.912917 -25.385147)
			(xy 36.883946 -25.46094) (xy 36.848194 -25.53378) (xy 36.82746 -25.568656) (xy 36.822143 -25.578562)
			(xy 36.819711 -25.600884) (xy 36.826954 -25.622138) (xy 36.834318 -25.630632) (xy 36.863684 -25.661685)
			(xy 36.916941 -25.728538) (xy 36.963541 -25.800191) (xy 37.003053 -25.875983) (xy 37.035114 -25.955216)
			(xy 37.059428 -26.037158) (xy 37.07577 -26.121054) (xy 37.08399 -26.206131) (xy 37.084508 -26.248868)
			(xy 37.084004 -26.291216) (xy 37.075953 -26.37553) (xy 37.069328 -26.409904) (xy 41.678606 -26.409904)
			(xy 41.679113 -26.358413) (xy 41.687128 -26.255743) (xy 41.70311 -26.154009) (xy 41.726962 -26.053827)
			(xy 41.758539 -25.955806) (xy 41.79765 -25.86054) (xy 41.844057 -25.768607) (xy 41.897479 -25.680565)
			(xy 41.957592 -25.596948) (xy 42.02403 -25.518264) (xy 42.05986 -25.48128) (xy 42.067226 -25.474168)
			(xy 42.074592 -25.45588) (xy 42.074592 -25.363932) (xy 42.067226 -25.345644) (xy 42.05986 -25.338532)
			(xy 42.024038 -25.301541) (xy 41.957599 -25.222857) (xy 41.897486 -25.139241) (xy 41.844064 -25.0512)
			(xy 41.797656 -24.959267) (xy 41.758545 -24.864002) (xy 41.726967 -24.765981) (xy 41.703115 -24.6658)
			(xy 41.687132 -24.564066) (xy 41.679116 -24.461397) (xy 41.679115 -24.358415) (xy 41.68713 -24.255746)
			(xy 41.703112 -24.154012) (xy 41.726964 -24.05383) (xy 41.758541 -23.955809) (xy 41.797652 -23.860543)
			(xy 41.844059 -23.76861) (xy 41.89748 -23.680569) (xy 41.957592 -23.596952) (xy 42.02403 -23.518268)
			(xy 42.05986 -23.481284) (xy 42.067226 -23.474172) (xy 42.074592 -23.455884) (xy 42.074592 -23.363936)
			(xy 42.067226 -23.345648) (xy 42.05986 -23.338536) (xy 42.024042 -23.301541) (xy 41.957603 -23.222858)
			(xy 41.89749 -23.139242) (xy 41.844068 -23.051201) (xy 41.79766 -22.959269) (xy 41.758549 -22.864003)
			(xy 41.726971 -22.765983) (xy 41.703118 -22.665802) (xy 41.687135 -22.564068) (xy 41.679119 -22.461399)
			(xy 41.679118 -22.358418) (xy 41.687133 -22.255749) (xy 41.703115 -22.154015) (xy 41.726966 -22.053834)
			(xy 41.758543 -21.955813) (xy 41.797653 -21.860547) (xy 41.84406 -21.768614) (xy 41.897481 -21.680573)
			(xy 41.957593 -21.596956) (xy 42.024031 -21.518272) (xy 42.05986 -21.481288) (xy 42.067226 -21.474176)
			(xy 42.074592 -21.455888) (xy 42.074592 -21.36394) (xy 42.067226 -21.345652) (xy 42.05986 -21.33854)
			(xy 42.024046 -21.301541) (xy 41.957607 -21.222858) (xy 41.897494 -21.139243) (xy 41.844072 -21.051202)
			(xy 41.797664 -20.95927) (xy 41.758552 -20.864005) (xy 41.726974 -20.765985) (xy 41.703121 -20.665804)
			(xy 41.687138 -20.564071) (xy 41.679122 -20.461402) (xy 41.679121 -20.358421) (xy 41.687135 -20.255752)
			(xy 41.703117 -20.154018) (xy 41.726968 -20.053837) (xy 41.758544 -19.955816) (xy 41.797654 -19.860551)
			(xy 41.844061 -19.768618) (xy 41.897482 -19.680576) (xy 41.957593 -19.59696) (xy 42.024031 -19.518276)
			(xy 42.05986 -19.481292) (xy 42.067226 -19.47418) (xy 42.074592 -19.455892) (xy 42.074592 -19.363944)
			(xy 42.067226 -19.345656) (xy 42.05986 -19.338544) (xy 42.02405 -19.301541) (xy 41.957611 -19.222859)
			(xy 41.897498 -19.139243) (xy 41.844076 -19.051203) (xy 41.797668 -18.959271) (xy 41.758556 -18.864007)
			(xy 41.726978 -18.765987) (xy 41.703124 -18.665806) (xy 41.687141 -18.564073) (xy 41.679125 -18.461405)
			(xy 41.679123 -18.358424) (xy 41.687138 -18.255755) (xy 41.703119 -18.154022) (xy 41.72697 -18.053841)
			(xy 41.758546 -17.95582) (xy 41.797656 -17.860554) (xy 41.844062 -17.768622) (xy 41.897483 -17.68058)
			(xy 41.957594 -17.596964) (xy 42.024031 -17.51828) (xy 42.05986 -17.481296) (xy 42.067226 -17.474184)
			(xy 42.074592 -17.455896) (xy 42.074592 -17.363948) (xy 42.067226 -17.34566) (xy 42.05986 -17.338548)
			(xy 42.024034 -17.301561) (xy 41.957594 -17.222877) (xy 41.89748 -17.139261) (xy 41.844056 -17.05122)
			(xy 41.797647 -16.959287) (xy 41.758535 -16.864022) (xy 41.726956 -16.766001) (xy 41.703102 -16.665819)
			(xy 41.687117 -16.564085) (xy 41.6791 -16.461415) (xy 41.678606 -16.409924) (xy 41.679126 -16.358433)
			(xy 41.68714 -16.255764) (xy 41.70312 -16.15403) (xy 41.726971 -16.053848) (xy 41.758546 -15.955827)
			(xy 41.797656 -15.860561) (xy 41.844062 -15.768628) (xy 41.897482 -15.680586) (xy 41.957594 -15.596969)
			(xy 42.024031 -15.518284) (xy 42.05986 -15.4813) (xy 42.067226 -15.474188) (xy 42.074592 -15.4559)
			(xy 42.074592 -15.363952) (xy 42.067226 -15.345664) (xy 42.05986 -15.338552) (xy 42.024027 -15.301571)
			(xy 41.957587 -15.222887) (xy 41.897473 -15.13927) (xy 41.84405 -15.051228) (xy 41.797641 -14.959295)
			(xy 41.758529 -14.864029) (xy 41.726951 -14.766007) (xy 41.703098 -14.665825) (xy 41.687116 -14.56409)
			(xy 41.6791 -14.46142) (xy 41.6791 -14.358437) (xy 41.687116 -14.255767) (xy 41.703099 -14.154032)
			(xy 41.726952 -14.05385) (xy 41.75853 -13.955828) (xy 41.797643 -13.860562) (xy 41.844051 -13.768629)
			(xy 41.897475 -13.680587) (xy 41.957589 -13.596971) (xy 42.024029 -13.518287) (xy 42.05986 -13.481304)
			(xy 42.067226 -13.474192) (xy 42.074592 -13.455904) (xy 42.074592 -13.363956) (xy 42.067226 -13.345668)
			(xy 42.05986 -13.338556) (xy 42.024038 -13.301565) (xy 41.957598 -13.222882) (xy 41.897483 -13.139266)
			(xy 41.84406 -13.051225) (xy 41.79765 -12.959293) (xy 41.758537 -12.864028) (xy 41.726958 -12.766008)
			(xy 41.703103 -12.665826) (xy 41.687118 -12.564092) (xy 41.6791 -12.461423) (xy 41.678606 -12.409932)
			(xy 41.679119 -12.358037) (xy 41.68726 -12.254568) (xy 41.703494 -12.152056) (xy 41.727722 -12.051133)
			(xy 41.759793 -11.952423) (xy 41.79951 -11.856534) (xy 41.846628 -11.764056) (xy 41.900857 -11.67556)
			(xy 41.961862 -11.591592) (xy 42.029267 -11.51267) (xy 42.102656 -11.439279) (xy 42.181578 -11.371873)
			(xy 42.265545 -11.310867) (xy 42.35404 -11.256637) (xy 42.446517 -11.209517) (xy 42.542406 -11.169799)
			(xy 42.641116 -11.137726) (xy 42.742038 -11.113498) (xy 42.84455 -11.097262) (xy 42.948019 -11.08912)
			(xy 42.999914 -11.088624) (xy 43.051405 -11.089114) (xy 43.154076 -11.09713) (xy 43.25581 -11.113114)
			(xy 43.355992 -11.136968) (xy 43.454014 -11.168547) (xy 43.54928 -11.207659) (xy 43.641213 -11.254069)
			(xy 43.729255 -11.307492) (xy 43.812871 -11.367607) (xy 43.891555 -11.434047) (xy 43.928538 -11.469878)
			(xy 43.93565 -11.477244) (xy 43.953938 -11.48461) (xy 44.045886 -11.48461) (xy 44.064174 -11.477244)
			(xy 44.071286 -11.469878) (xy 44.108261 -11.434039) (xy 44.186946 -11.367599) (xy 44.270563 -11.307485)
			(xy 44.358606 -11.254063) (xy 44.45054 -11.207655) (xy 44.545807 -11.168543) (xy 44.643829 -11.136966)
			(xy 44.744012 -11.113114) (xy 44.845748 -11.097132) (xy 44.948418 -11.089117) (xy 44.99991 -11.088624)
			(xy 45.051806 -11.089079) (xy 45.155277 -11.097223) (xy 45.257791 -11.113461) (xy 45.358714 -11.137691)
			(xy 45.457426 -11.169766) (xy 45.553316 -11.209486) (xy 45.645794 -11.256608) (xy 45.73429 -11.31084)
			(xy 45.818259 -11.371848) (xy 45.897181 -11.439257) (xy 45.970572 -11.51265) (xy 46.037978 -11.591574)
			(xy 46.098983 -11.675545) (xy 46.153213 -11.764042) (xy 46.200331 -11.856522) (xy 46.240049 -11.952414)
			(xy 46.27212 -12.051126) (xy 46.296347 -12.15205) (xy 46.312582 -12.254564) (xy 46.320723 -12.358036)
			(xy 46.321218 -12.409932) (xy 46.320728 -12.461423) (xy 46.31271 -12.564093) (xy 46.296726 -12.665828)
			(xy 46.272872 -12.76601) (xy 46.241292 -12.864031) (xy 46.20218 -12.959297) (xy 46.155771 -13.05123)
			(xy 46.102348 -13.139271) (xy 46.042234 -13.222888) (xy 45.975794 -13.301572) (xy 45.939964 -13.338556)
			(xy 45.932598 -13.345668) (xy 45.925232 -13.363956) (xy 45.925232 -13.455904) (xy 45.932598 -13.474192)
			(xy 45.939964 -13.481304) (xy 45.975793 -13.518289) (xy 46.042232 -13.596973) (xy 46.102346 -13.680589)
			(xy 46.15577 -13.768631) (xy 46.202178 -13.860564) (xy 46.24129 -13.95583) (xy 46.272868 -14.053851)
			(xy 46.296721 -14.154033) (xy 46.312704 -14.255767) (xy 46.32072 -14.358437) (xy 46.32072 -14.46142)
			(xy 46.312705 -14.56409) (xy 46.296722 -14.665824) (xy 46.272869 -14.766006) (xy 46.241291 -14.864028)
			(xy 46.202179 -14.959294) (xy 46.155771 -15.051227) (xy 46.102348 -15.139268) (xy 46.042234 -15.222885)
			(xy 45.975794 -15.301569) (xy 45.939964 -15.338552) (xy 45.932598 -15.345664) (xy 45.925232 -15.363952)
			(xy 45.925232 -15.4559) (xy 45.932598 -15.474188) (xy 45.939964 -15.4813) (xy 45.975799 -15.518279)
			(xy 46.04224 -15.596962) (xy 46.102355 -15.680579) (xy 46.155779 -15.768621) (xy 46.202188 -15.860554)
			(xy 46.2413 -15.955821) (xy 46.272878 -16.053843) (xy 46.29673 -16.154026) (xy 46.312712 -16.255762)
			(xy 46.320726 -16.358432) (xy 46.321218 -16.409924) (xy 46.320723 -16.461415) (xy 46.312706 -16.564085)
			(xy 46.296722 -16.665819) (xy 46.272868 -16.766001) (xy 46.241289 -16.864022) (xy 46.202177 -16.959288)
			(xy 46.155769 -17.051221) (xy 46.102346 -17.139263) (xy 46.042233 -17.22288) (xy 45.975794 -17.301564)
			(xy 45.939964 -17.338548) (xy 45.932598 -17.34566) (xy 45.925232 -17.363948) (xy 45.925232 -17.455896)
			(xy 45.932598 -17.474184) (xy 45.939964 -17.481296) (xy 45.975816 -17.51826) (xy 46.042258 -17.596944)
			(xy 46.102374 -17.680561) (xy 46.155799 -17.768604) (xy 46.202208 -17.860539) (xy 46.241321 -17.955806)
			(xy 46.2729 -18.05383) (xy 46.296753 -18.154013) (xy 46.312735 -18.25575) (xy 46.32075 -18.358422)
			(xy 46.320749 -18.461406) (xy 46.312732 -18.564078) (xy 46.296747 -18.665814) (xy 46.272892 -18.765998)
			(xy 46.241311 -18.86402) (xy 46.202196 -18.959287) (xy 46.155785 -19.051221) (xy 46.102358 -19.139262)
			(xy 46.04224 -19.222878) (xy 45.975797 -19.301561) (xy 45.939964 -19.338544) (xy 45.932598 -19.345656)
			(xy 45.925232 -19.363944) (xy 45.925232 -19.455892) (xy 45.932598 -19.47418) (xy 45.939964 -19.481292)
			(xy 45.975812 -19.518259) (xy 46.042254 -19.596943) (xy 46.10237 -19.68056) (xy 46.155795 -19.768603)
			(xy 46.202205 -19.860537) (xy 46.241318 -19.955805) (xy 46.272896 -20.053828) (xy 46.29675 -20.154011)
			(xy 46.312732 -20.255748) (xy 46.320748 -20.358419) (xy 46.320747 -20.461403) (xy 46.31273 -20.564075)
			(xy 46.296745 -20.665811) (xy 46.27289 -20.765994) (xy 46.24131 -20.864017) (xy 46.202195 -20.959284)
			(xy 46.155784 -21.051217) (xy 46.102357 -21.139259) (xy 46.04224 -21.222874) (xy 45.975796 -21.301557)
			(xy 45.939964 -21.33854) (xy 45.932598 -21.345652) (xy 45.925232 -21.36394) (xy 45.925232 -21.455888)
			(xy 45.932598 -21.474176) (xy 45.939964 -21.481288) (xy 45.975808 -21.518259) (xy 46.04225 -21.596943)
			(xy 46.102366 -21.68056) (xy 46.155791 -21.768602) (xy 46.202201 -21.860536) (xy 46.241314 -21.955803)
			(xy 46.272893 -22.053826) (xy 46.296746 -22.154009) (xy 46.312729 -22.255745) (xy 46.320745 -22.358417)
			(xy 46.320744 -22.4614) (xy 46.312727 -22.564072) (xy 46.296743 -22.665808) (xy 46.272888 -22.765991)
			(xy 46.241308 -22.864013) (xy 46.202194 -22.95928) (xy 46.155783 -23.051213) (xy 46.102356 -23.139255)
			(xy 46.042239 -23.222871) (xy 45.975796 -23.301553) (xy 45.939964 -23.338536) (xy 45.932598 -23.345648)
			(xy 45.925232 -23.363936) (xy 45.925232 -23.455884) (xy 45.932598 -23.474172) (xy 45.939964 -23.481284)
			(xy 45.975804 -23.518259) (xy 46.042246 -23.596942) (xy 46.102362 -23.680559) (xy 46.155787 -23.768601)
			(xy 46.202197 -23.860534) (xy 46.24131 -23.955801) (xy 46.27289 -24.053824) (xy 46.296743 -24.154007)
			(xy 46.312726 -24.255743) (xy 46.320742 -24.358414) (xy 46.320741 -24.461398) (xy 46.312725 -24.564069)
			(xy 46.296741 -24.665804) (xy 46.272886 -24.765987) (xy 46.241306 -24.864009) (xy 46.202192 -24.959276)
			(xy 46.155782 -25.051209) (xy 46.102356 -25.139251) (xy 46.042239 -25.222867) (xy 45.975796 -25.301549)
			(xy 45.939964 -25.338532) (xy 45.932598 -25.345644) (xy 45.925232 -25.363932) (xy 45.925232 -25.45588)
			(xy 45.932598 -25.474168) (xy 45.939964 -25.48128) (xy 45.97579 -25.518268) (xy 46.042231 -25.596951)
			(xy 46.102347 -25.680566) (xy 46.155771 -25.768607) (xy 46.202181 -25.860539) (xy 46.241294 -25.955805)
			(xy 46.272873 -26.053826) (xy 46.296726 -26.154008) (xy 46.312709 -26.255743) (xy 46.320725 -26.358413)
			(xy 46.321218 -26.409904) (xy 46.320664 -26.460722) (xy 46.312862 -26.562058) (xy 46.297296 -26.662494)
			(xy 46.274059 -26.761438) (xy 46.243288 -26.858304) (xy 46.205165 -26.952519) (xy 46.159915 -27.043526)
			(xy 46.107807 -27.130787) (xy 46.049147 -27.213786) (xy 45.984283 -27.292032) (xy 45.913598 -27.365063)
			(xy 45.837511 -27.432447) (xy 45.756471 -27.493785) (xy 45.670958 -27.548715) (xy 45.581477 -27.596912)
			(xy 45.488556 -27.63809) (xy 45.392747 -27.672007) (xy 45.294615 -27.698462) (xy 45.244766 -27.708352)
			(xy 45.233336 -27.710384) (xy 45.215048 -27.723592) (xy 45.16628 -27.812492) (xy 45.164756 -27.835098)
			(xy 45.169074 -27.845766) (xy 45.187081 -27.892447) (xy 45.21649 -27.98809) (xy 45.238206 -28.085767)
			(xy 45.252093 -28.184861) (xy 45.258064 -28.284745) (xy 45.256079 -28.384788) (xy 45.246151 -28.484356)
			(xy 45.228345 -28.582821) (xy 45.202771 -28.67956) (xy 45.169592 -28.773962) (xy 45.129017 -28.865428)
			(xy 45.081303 -28.953382) (xy 45.026752 -29.037267) (xy 44.965709 -29.116552) (xy 44.898559 -29.190737)
			(xy 44.825728 -29.259352) (xy 44.747674 -29.321963) (xy 44.664894 -29.378175) (xy 44.577908 -29.427632)
			(xy 44.487268 -29.470021) (xy 44.393547 -29.505075) (xy 44.297337 -29.532572) (xy 44.199246 -29.552338)
			(xy 44.099895 -29.564247) (xy 43.999912 -29.568225) (xy 43.899929 -29.564247) (xy 43.800578 -29.552338)
			(xy 43.702487 -29.532572) (xy 43.606277 -29.505075) (xy 43.512556 -29.470021) (xy 43.421916 -29.427632)
			(xy 43.33493 -29.378175) (xy 43.25215 -29.321963) (xy 43.174096 -29.259352) (xy 43.101265 -29.190737)
			(xy 43.034115 -29.116552) (xy 42.973072 -29.037267) (xy 42.918521 -28.953382) (xy 42.870807 -28.865428)
			(xy 42.830232 -28.773962) (xy 42.797053 -28.67956) (xy 42.771479 -28.582821) (xy 42.753673 -28.484356)
			(xy 42.743745 -28.384788) (xy 42.74176 -28.284745) (xy 42.747731 -28.184861) (xy 42.761618 -28.085767)
			(xy 42.783334 -27.98809) (xy 42.812743 -27.892447) (xy 42.83075 -27.845766) (xy 42.835068 -27.835098)
			(xy 42.833544 -27.812492) (xy 42.784776 -27.723592) (xy 42.766488 -27.710384) (xy 42.755058 -27.708352)
			(xy 42.705201 -27.6985) (xy 42.607066 -27.672041) (xy 42.511255 -27.63812) (xy 42.418333 -27.596938)
			(xy 42.32885 -27.548738) (xy 42.243334 -27.493806) (xy 42.162292 -27.432466) (xy 42.086202 -27.36508)
			(xy 42.015515 -27.292048) (xy 41.950648 -27.2138) (xy 41.891984 -27.1308) (xy 41.839871 -27.043538)
			(xy 41.794617 -26.952529) (xy 41.756488 -26.858313) (xy 41.725712 -26.761446) (xy 41.702468 -26.662501)
			(xy 41.686896 -26.562062) (xy 41.679086 -26.460723) (xy 41.678606 -26.409904) (xy 37.069328 -26.409904)
			(xy 37.059924 -26.458696) (xy 37.036063 -26.539963) (xy 37.004584 -26.618593) (xy 36.965773 -26.693874)
			(xy 36.919983 -26.765126) (xy 36.867627 -26.831702) (xy 36.809179 -26.893) (xy 36.745169 -26.948465)
			(xy 36.676177 -26.997594) (xy 36.602827 -27.039943) (xy 36.525784 -27.075127) (xy 36.445745 -27.102829)
			(xy 36.363436 -27.122797) (xy 36.279601 -27.13485) (xy 36.195 -27.138881) (xy 36.110399 -27.13485)
			(xy 36.026564 -27.122797) (xy 35.944255 -27.102829) (xy 35.864216 -27.075127) (xy 35.787173 -27.039943)
			(xy 35.713823 -26.997594) (xy 35.644831 -26.948465) (xy 35.580821 -26.893) (xy 35.522373 -26.831702)
			(xy 35.470017 -26.765126) (xy 35.424227 -26.693874) (xy 35.385416 -26.618593) (xy 35.353937 -26.539963)
			(xy 35.330076 -26.458696) (xy 35.314047 -26.37553) (xy 35.305996 -26.291216) (xy 35.305492 -26.248868)
			(xy 35.305981 -26.208298) (xy 35.313399 -26.127497) (xy 35.328143 -26.047707) (xy 35.35009 -25.969591)
			(xy 35.379059 -25.893797) (xy 35.414808 -25.820956) (xy 35.43554 -25.78608) (xy 35.440917 -25.776201)
			(xy 35.443328 -25.75386) (xy 35.436059 -25.732597) (xy 35.428682 -25.724104) (xy 35.399334 -25.693035)
			(xy 35.346075 -25.626184) (xy 35.299474 -25.554534) (xy 35.259959 -25.478744) (xy 35.227896 -25.399514)
			(xy 35.20358 -25.317574) (xy 35.187235 -25.233679) (xy 35.179011 -25.148604) (xy 35.178492 -25.105868)
			(xy 35.178894 -25.068859) (xy 35.185084 -24.995099) (xy 35.197383 -24.922109) (xy 35.206178 -24.886158)
			(xy 35.208718 -24.875236) (xy 35.204908 -24.8539) (xy 35.14852 -24.772366) (xy 35.129978 -24.76119)
			(xy 35.118802 -24.760174) (xy 35.075373 -24.754823) (xy 34.989773 -24.736654) (xy 34.906369 -24.710169)
			(xy 34.825969 -24.675624) (xy 34.749348 -24.633353) (xy 34.677247 -24.583764) (xy 34.610363 -24.527336)
			(xy 34.549341 -24.464615) (xy 34.521648 -24.430736) (xy 34.514028 -24.421084) (xy 34.492184 -24.410924)
			(xy 34.385504 -24.41575) (xy 34.364422 -24.427434) (xy 34.357564 -24.437848) (xy 34.348354 -24.451559)
			(xy 34.329044 -24.478363) (xy 34.318956 -24.491442) (xy 34.312121 -24.501128) (xy 34.307422 -24.524339)
			(xy 34.313585 -24.547204) (xy 34.320988 -24.556466) (xy 34.347361 -24.586927) (xy 34.395105 -24.651835)
			(xy 34.436781 -24.720796) (xy 34.472047 -24.793246) (xy 34.500613 -24.868589) (xy 34.522245 -24.946208)
			(xy 34.536766 -25.025465) (xy 34.544056 -25.105712) (xy 34.544508 -25.146) (xy 34.544004 -25.188348)
			(xy 34.535953 -25.272662) (xy 34.519924 -25.355828) (xy 34.496063 -25.437095) (xy 34.464584 -25.515725)
			(xy 34.425773 -25.591006) (xy 34.379983 -25.662258) (xy 34.327627 -25.728834) (xy 34.269179 -25.790132)
			(xy 34.205169 -25.845597) (xy 34.136177 -25.894726) (xy 34.062827 -25.937075) (xy 33.985784 -25.972259)
			(xy 33.905745 -25.999961) (xy 33.823436 -26.019929) (xy 33.739601 -26.031982) (xy 33.655 -26.036013)
			(xy 33.570399 -26.031982) (xy 33.486564 -26.019929) (xy 33.404255 -25.999961) (xy 33.324216 -25.972259)
			(xy 33.247173 -25.937075) (xy 33.173823 -25.894726) (xy 33.104831 -25.845597) (xy 33.040821 -25.790132)
			(xy 32.982373 -25.728834) (xy 32.930017 -25.662258) (xy 32.884227 -25.591006) (xy 32.845416 -25.515725)
			(xy 32.813937 -25.437095) (xy 32.790076 -25.355828) (xy 32.774047 -25.272662) (xy 32.765996 -25.188348)
			(xy 32.765492 -25.146) (xy 32.765947 -25.103989) (xy 32.773881 -25.020342) (xy 32.789669 -24.937816)
			(xy 32.813171 -24.857147) (xy 32.844176 -24.779055) (xy 32.882409 -24.704235) (xy 32.927528 -24.633354)
			(xy 32.952944 -24.5999) (xy 32.959739 -24.590191) (xy 32.964451 -24.566995) (xy 32.958306 -24.544137)
			(xy 32.950912 -24.534876) (xy 32.924512 -24.504439) (xy 32.876769 -24.439527) (xy 32.835096 -24.370561)
			(xy 32.799833 -24.298108) (xy 32.771271 -24.222762) (xy 32.749643 -24.14514) (xy 32.735126 -24.06588)
			(xy 32.727841 -23.985631) (xy 32.727392 -23.945342) (xy 24.013442 -23.945342) (xy 24.018035 -23.994916)
			(xy 24.018494 -24.03602) (xy 24.017962 -24.079264) (xy 24.009548 -24.165341) (xy 23.992821 -24.250196)
			(xy 23.967939 -24.333027) (xy 23.935136 -24.413053) (xy 23.894723 -24.489518) (xy 23.84708 -24.561701)
			(xy 23.792658 -24.628919) (xy 23.73197 -24.69054) (xy 23.665588 -24.74598) (xy 23.59414 -24.794718)
			(xy 23.5183 -24.836292) (xy 23.438784 -24.870311) (xy 23.397718 -24.883872) (xy 23.38705 -24.887428)
			(xy 23.370286 -24.902668) (xy 23.33244 -24.996394) (xy 23.33371 -25.018746) (xy 23.339044 -25.028906)
			(xy 23.359381 -25.067826) (xy 23.393167 -25.148885) (xy 23.4188 -25.232879) (xy 23.436028 -25.318992)
			(xy 23.444685 -25.406383) (xy 23.445216 -25.450292) (xy 23.444708 -25.480772) (xy 23.4442 -25.494234)
			(xy 23.456392 -25.517856) (xy 23.552658 -25.579832) (xy 23.579074 -25.581356) (xy 23.591266 -25.57526)
			(xy 23.628068 -25.557598) (xy 23.704275 -25.528323) (xy 23.782842 -25.506147) (xy 23.863109 -25.491256)
			(xy 23.944402 -25.483776) (xy 23.98522 -25.483312) (xy 24.027144 -25.483796) (xy 24.11062 -25.491689)
			(xy 24.192982 -25.507402) (xy 24.2735 -25.530797) (xy 24.35146 -25.561665) (xy 24.426168 -25.599732)
			(xy 24.496962 -25.644661) (xy 24.563215 -25.696053) (xy 24.624336 -25.753452) (xy 24.679785 -25.816348)
			(xy 24.729069 -25.884184) (xy 24.768197 -25.950348) (xy 30.225996 -25.950348) (xy 30.225996 -25.865652)
			(xy 30.234047 -25.781338) (xy 30.250076 -25.698172) (xy 30.273937 -25.616905) (xy 30.305416 -25.538275)
			(xy 30.344227 -25.462994) (xy 30.390017 -25.391742) (xy 30.442373 -25.325166) (xy 30.500821 -25.263868)
			(xy 30.564831 -25.208403) (xy 30.633823 -25.159274) (xy 30.707173 -25.116925) (xy 30.784216 -25.081741)
			(xy 30.864255 -25.054039) (xy 30.946564 -25.034071) (xy 31.030399 -25.022018) (xy 31.115 -25.017988)
			(xy 31.199601 -25.022018) (xy 31.283436 -25.034071) (xy 31.365745 -25.054039) (xy 31.445784 -25.081741)
			(xy 31.522827 -25.116925) (xy 31.596177 -25.159274) (xy 31.665169 -25.208403) (xy 31.729179 -25.263868)
			(xy 31.787627 -25.325166) (xy 31.839983 -25.391742) (xy 31.885773 -25.462994) (xy 31.924584 -25.538275)
			(xy 31.956063 -25.616905) (xy 31.979924 -25.698172) (xy 31.995953 -25.781338) (xy 32.004004 -25.865652)
			(xy 32.004508 -25.908) (xy 32.004004 -25.950348) (xy 31.995953 -26.034662) (xy 31.979924 -26.117828)
			(xy 31.956063 -26.199095) (xy 31.924584 -26.277725) (xy 31.885773 -26.353006) (xy 31.839983 -26.424258)
			(xy 31.787627 -26.490834) (xy 31.729179 -26.552132) (xy 31.665169 -26.607597) (xy 31.596177 -26.656726)
			(xy 31.522827 -26.699075) (xy 31.445784 -26.734259) (xy 31.365745 -26.761961) (xy 31.283436 -26.781929)
			(xy 31.199601 -26.793982) (xy 31.115 -26.798013) (xy 31.030399 -26.793982) (xy 30.946564 -26.781929)
			(xy 30.864255 -26.761961) (xy 30.784216 -26.734259) (xy 30.707173 -26.699075) (xy 30.633823 -26.656726)
			(xy 30.564831 -26.607597) (xy 30.500821 -26.552132) (xy 30.442373 -26.490834) (xy 30.390017 -26.424258)
			(xy 30.344227 -26.353006) (xy 30.305416 -26.277725) (xy 30.273937 -26.199095) (xy 30.250076 -26.117828)
			(xy 30.234047 -26.034662) (xy 30.225996 -25.950348) (xy 24.768197 -25.950348) (xy 24.77175 -25.956356)
			(xy 24.80745 -26.032224) (xy 24.835851 -26.111115) (xy 24.856703 -26.192329) (xy 24.869819 -26.275145)
			(xy 24.875083 -26.358827) (xy 24.872448 -26.442634) (xy 24.861939 -26.525821) (xy 24.843648 -26.607649)
			(xy 24.817737 -26.687393) (xy 24.784437 -26.764345) (xy 24.744042 -26.837822) (xy 24.696913 -26.90717)
			(xy 24.643466 -26.971776) (xy 24.584176 -27.031066) (xy 24.51957 -27.084513) (xy 24.450222 -27.131642)
			(xy 24.376745 -27.172037) (xy 24.299793 -27.205337) (xy 24.220049 -27.231248) (xy 24.138221 -27.249539)
			(xy 24.055034 -27.260048) (xy 23.971227 -27.262683) (xy 23.887545 -27.257419) (xy 23.804729 -27.244303)
			(xy 23.723515 -27.223451) (xy 23.644624 -27.19505) (xy 23.568756 -27.15935) (xy 23.496584 -27.116669)
			(xy 23.428748 -27.067385) (xy 23.365852 -27.011936) (xy 23.308453 -26.950815) (xy 23.257061 -26.884562)
			(xy 23.212132 -26.813768) (xy 23.174065 -26.73906) (xy 23.143197 -26.6611) (xy 23.119802 -26.580582)
			(xy 23.104089 -26.49822) (xy 23.096196 -26.414744) (xy 23.095712 -26.37282) (xy 23.09622 -26.34234)
			(xy 23.096728 -26.328878) (xy 23.084536 -26.305256) (xy 22.98827 -26.24328) (xy 22.961854 -26.241756)
			(xy 22.949662 -26.247852) (xy 22.912852 -26.265497) (xy 22.836648 -26.294777) (xy 22.758083 -26.316957)
			(xy 22.677818 -26.331851) (xy 22.596526 -26.339335) (xy 22.555708 -26.3398) (xy 22.514605 -26.33934)
			(xy 22.432749 -26.331756) (xy 22.351942 -26.316651) (xy 22.272873 -26.294155) (xy 22.196218 -26.264458)
			(xy 22.12263 -26.227816) (xy 22.052736 -26.18454) (xy 21.987134 -26.135) (xy 21.926382 -26.079618)
			(xy 21.871 -26.018866) (xy 21.82146 -25.953264) (xy 21.778184 -25.88337) (xy 21.741542 -25.809782)
			(xy 21.711845 -25.733127) (xy 21.689349 -25.654058) (xy 21.674244 -25.573251) (xy 21.66666 -25.491395)
			(xy 21.6662 -25.450292) (xy 21.666678 -25.407046) (xy 21.675091 -25.320965) (xy 21.691819 -25.236107)
			(xy 21.716704 -25.153272) (xy 21.749509 -25.073244) (xy 21.789927 -24.996777) (xy 21.837574 -24.924593)
			(xy 21.892002 -24.857374) (xy 21.952696 -24.795754) (xy 22.019083 -24.740315) (xy 22.090538 -24.691581)
			(xy 22.166384 -24.650011) (xy 22.245907 -24.615998) (xy 22.286976 -24.60244) (xy 22.297644 -24.598884)
			(xy 22.314408 -24.583644) (xy 22.352254 -24.489918) (xy 22.350984 -24.467566) (xy 22.34565 -24.457406)
			(xy 22.322915 -24.4137) (xy 22.286124 -24.322304) (xy 22.272244 -24.275034) (xy 22.26945 -24.264874)
			(xy 22.256242 -24.248618) (xy 22.171406 -24.204676) (xy 22.150578 -24.203152) (xy 22.140418 -24.206708)
			(xy 22.104662 -24.218912) (xy 22.031538 -24.237935) (xy 21.957065 -24.250696) (xy 21.881779 -24.257104)
			(xy 21.844 -24.257508) (xy 21.801652 -24.257004) (xy 21.717338 -24.248953) (xy 21.634172 -24.232924)
			(xy 21.552905 -24.209063) (xy 21.474275 -24.177584) (xy 21.398994 -24.138773) (xy 21.327742 -24.092983)
			(xy 21.261166 -24.040627) (xy 21.199868 -23.982179) (xy 21.144403 -23.918169) (xy 21.095274 -23.849177)
			(xy 21.052925 -23.775827) (xy 21.017741 -23.698784) (xy 20.990039 -23.618745) (xy 20.970071 -23.536436)
			(xy 20.958018 -23.452601) (xy 20.953988 -23.368) (xy 18.878842 -23.368) (xy 18.924083 -23.425528)
			(xy 18.969873 -23.49678) (xy 19.008684 -23.572061) (xy 19.040163 -23.650691) (xy 19.064024 -23.731958)
			(xy 19.080053 -23.815124) (xy 19.088104 -23.899438) (xy 19.088608 -23.941786) (xy 19.088104 -23.984134)
			(xy 19.080053 -24.068448) (xy 19.064024 -24.151614) (xy 19.040163 -24.232881) (xy 19.008684 -24.311511)
			(xy 18.969873 -24.386792) (xy 18.924083 -24.458044) (xy 18.871727 -24.52462) (xy 18.813279 -24.585918)
			(xy 18.749269 -24.641383) (xy 18.680277 -24.690512) (xy 18.606927 -24.732861) (xy 18.529884 -24.768045)
			(xy 18.449845 -24.795747) (xy 18.367536 -24.815715) (xy 18.283701 -24.827768) (xy 18.1991 -24.831799)
			(xy 18.114499 -24.827768) (xy 18.030664 -24.815715) (xy 17.948355 -24.795747) (xy 17.868316 -24.768045)
			(xy 17.791273 -24.732861) (xy 17.717923 -24.690512) (xy 17.648931 -24.641383) (xy 17.584921 -24.585918)
			(xy 17.526473 -24.52462) (xy 17.474117 -24.458044) (xy 17.428327 -24.386792) (xy 17.389516 -24.311511)
			(xy 17.358037 -24.232881) (xy 17.334176 -24.151614) (xy 17.318147 -24.068448) (xy 17.310096 -23.984134)
			(xy 17.017255 -23.984134) (xy 16.981012 -24.039146) (xy 16.926725 -24.106324) (xy 16.86618 -24.167922)
			(xy 16.799947 -24.223359) (xy 16.728651 -24.272112) (xy 16.652964 -24.313721) (xy 16.573598 -24.347796)
			(xy 16.532606 -24.361394) (xy 16.522954 -24.364696) (xy 16.50746 -24.37765) (xy 16.465296 -24.459946)
			(xy 16.463772 -24.480012) (xy 16.46682 -24.489664) (xy 16.4807 -24.534224) (xy 16.500141 -24.625511)
			(xy 16.509915 -24.718333) (xy 16.510508 -24.765) (xy 16.51021 -24.799237) (xy 16.504995 -24.867512)
			(xy 16.500094 -24.901398) (xy 16.498316 -24.91232) (xy 16.504412 -24.933656) (xy 16.568928 -25.009094)
			(xy 16.588994 -25.018492) (xy 16.60017 -25.018492) (xy 16.641234 -25.019024) (xy 16.723004 -25.026712)
			(xy 16.803717 -25.041905) (xy 16.882686 -25.064474) (xy 16.959237 -25.094227) (xy 17.03272 -25.13091)
			(xy 17.102509 -25.17421) (xy 17.168009 -25.22376) (xy 17.228662 -25.279136) (xy 17.283952 -25.339869)
			(xy 17.333408 -25.405439) (xy 17.376609 -25.475289) (xy 17.413187 -25.548825) (xy 17.44283 -25.625419)
			(xy 17.465286 -25.70442) (xy 17.480364 -25.785154) (xy 17.487935 -25.866935) (xy 17.488408 -25.908)
			(xy 17.487904 -25.950348) (xy 17.479853 -26.034662) (xy 17.463824 -26.117828) (xy 17.439963 -26.199095)
			(xy 17.408484 -26.277725) (xy 17.369673 -26.353006) (xy 17.323883 -26.424258) (xy 17.271527 -26.490834)
			(xy 17.213079 -26.552132) (xy 17.196731 -26.566298) (xy 19.303996 -26.566298) (xy 19.303996 -26.481602)
			(xy 19.312047 -26.397288) (xy 19.328076 -26.314122) (xy 19.351937 -26.232855) (xy 19.383416 -26.154225)
			(xy 19.422227 -26.078944) (xy 19.468017 -26.007692) (xy 19.520373 -25.941116) (xy 19.578821 -25.879818)
			(xy 19.642831 -25.824353) (xy 19.711823 -25.775224) (xy 19.785173 -25.732875) (xy 19.862216 -25.697691)
			(xy 19.942255 -25.669989) (xy 20.024564 -25.650021) (xy 20.108399 -25.637968) (xy 20.193 -25.633938)
			(xy 20.277601 -25.637968) (xy 20.361436 -25.650021) (xy 20.443745 -25.669989) (xy 20.523784 -25.697691)
			(xy 20.600827 -25.732875) (xy 20.674177 -25.775224) (xy 20.743169 -25.824353) (xy 20.807179 -25.879818)
			(xy 20.865627 -25.941116) (xy 20.917983 -26.007692) (xy 20.963773 -26.078944) (xy 21.002584 -26.154225)
			(xy 21.034063 -26.232855) (xy 21.057924 -26.314122) (xy 21.073953 -26.397288) (xy 21.082004 -26.481602)
			(xy 21.082508 -26.52395) (xy 21.082004 -26.566298) (xy 21.073953 -26.650612) (xy 21.057924 -26.733778)
			(xy 21.034063 -26.815045) (xy 21.002584 -26.893675) (xy 20.963773 -26.968956) (xy 20.917983 -27.040208)
			(xy 20.865627 -27.106784) (xy 20.807179 -27.168082) (xy 20.743169 -27.223547) (xy 20.674177 -27.272676)
			(xy 20.600827 -27.315025) (xy 20.523784 -27.350209) (xy 20.443745 -27.377911) (xy 20.386214 -27.391868)
			(xy 33.279842 -27.391868) (xy 33.280346 -27.34952) (xy 33.288397 -27.265206) (xy 33.304426 -27.18204)
			(xy 33.328287 -27.100773) (xy 33.359766 -27.022143) (xy 33.398577 -26.946862) (xy 33.444367 -26.87561)
			(xy 33.496723 -26.809034) (xy 33.555171 -26.747736) (xy 33.619181 -26.692271) (xy 33.688173 -26.643142)
			(xy 33.761523 -26.600793) (xy 33.838566 -26.565609) (xy 33.918605 -26.537907) (xy 34.000914 -26.517939)
			(xy 34.084749 -26.505886) (xy 34.16935 -26.501856) (xy 34.253951 -26.505886) (xy 34.337786 -26.517939)
			(xy 34.420095 -26.537907) (xy 34.500134 -26.565609) (xy 34.577177 -26.600793) (xy 34.650527 -26.643142)
			(xy 34.719519 -26.692271) (xy 34.783529 -26.747736) (xy 34.841977 -26.809034) (xy 34.894333 -26.87561)
			(xy 34.940123 -26.946862) (xy 34.978934 -27.022143) (xy 35.010413 -27.100773) (xy 35.034274 -27.18204)
			(xy 35.050303 -27.265206) (xy 35.058354 -27.34952) (xy 35.058858 -27.391868) (xy 35.058438 -27.430573)
			(xy 35.051739 -27.507693) (xy 35.038356 -27.583937) (xy 35.018388 -27.658728) (xy 34.991989 -27.731497)
			(xy 34.976054 -27.766772) (xy 34.970974 -27.777694) (xy 34.971482 -27.801316) (xy 35.021012 -27.89428)
			(xy 35.040062 -27.907996) (xy 35.052 -27.910028) (xy 35.09207 -27.916835) (xy 35.170848 -27.936866)
			(xy 35.247469 -27.964004) (xy 35.321292 -27.998023) (xy 35.391701 -28.03864) (xy 35.458108 -28.085515)
			(xy 35.519959 -28.138256) (xy 35.576737 -28.196423) (xy 35.627968 -28.259531) (xy 35.673224 -28.327052)
			(xy 35.712127 -28.398422) (xy 35.728656 -28.435554) (xy 35.733529 -28.445393) (xy 35.749864 -28.460035)
			(xy 35.770793 -28.466606) (xy 35.781742 -28.46578) (xy 35.810439 -28.462228) (xy 35.868143 -28.458415)
			(xy 35.897058 -28.45816) (xy 35.939407 -28.458652) (xy 36.023722 -28.466703) (xy 36.10689 -28.482732)
			(xy 36.188158 -28.506594) (xy 36.266789 -28.538073) (xy 36.342072 -28.576884) (xy 36.413325 -28.622676)
			(xy 36.479902 -28.675033) (xy 36.541201 -28.733481) (xy 36.596667 -28.797492) (xy 36.645797 -28.866485)
			(xy 36.688146 -28.939836) (xy 36.723331 -29.01688) (xy 36.751034 -29.09692) (xy 36.771002 -29.179231)
			(xy 36.783056 -29.263068) (xy 36.787086 -29.34767) (xy 36.783056 -29.432272) (xy 36.771002 -29.516109)
			(xy 36.751034 -29.59842) (xy 36.723331 -29.67846) (xy 36.688146 -29.755504) (xy 36.645797 -29.828855)
			(xy 36.596667 -29.897848) (xy 36.541201 -29.961859) (xy 36.479902 -30.020307) (xy 36.413325 -30.072664)
			(xy 36.342072 -30.118456) (xy 36.266789 -30.157267) (xy 36.188158 -30.188746) (xy 36.10689 -30.212608)
			(xy 36.023722 -30.228637) (xy 35.939407 -30.236688) (xy 35.897058 -30.237176) (xy 35.853943 -30.236666)
			(xy 35.768117 -30.228335) (xy 35.683501 -30.211738) (xy 35.600887 -30.187028) (xy 35.521054 -30.154439)
			(xy 35.444749 -30.114277) (xy 35.372689 -30.066918) (xy 35.305551 -30.012807) (xy 35.243965 -29.952452)
			(xy 35.18851 -29.88642) (xy 35.139706 -29.815331) (xy 35.098012 -29.739852) (xy 35.080448 -29.700474)
			(xy 35.075561 -29.690642) (xy 35.059234 -29.675997) (xy 35.03831 -29.669423) (xy 35.027362 -29.670248)
			(xy 34.998665 -29.673799) (xy 34.940961 -29.677613) (xy 34.912046 -29.677868) (xy 34.870942 -29.677404)
			(xy 34.789086 -29.669823) (xy 34.708278 -29.65472) (xy 34.629208 -29.632226) (xy 34.552551 -29.602532)
			(xy 34.478962 -29.56589) (xy 34.409067 -29.522615) (xy 34.343464 -29.473075) (xy 34.282711 -29.417693)
			(xy 34.227329 -29.356941) (xy 34.177788 -29.291338) (xy 34.134513 -29.221444) (xy 34.097871 -29.147854)
			(xy 34.068176 -29.071198) (xy 34.045681 -28.992128) (xy 34.030578 -28.91132) (xy 34.022996 -28.829464)
			(xy 34.022538 -28.78836) (xy 34.022931 -28.749654) (xy 34.029636 -28.672534) (xy 34.043026 -28.596289)
			(xy 34.062999 -28.521499) (xy 34.089404 -28.448731) (xy 34.105342 -28.413456) (xy 34.110422 -28.402534)
			(xy 34.109914 -28.378912) (xy 34.060384 -28.285948) (xy 34.041334 -28.272232) (xy 34.029396 -28.2702)
			(xy 33.98811 -28.26306) (xy 33.906965 -28.242172) (xy 33.828145 -28.213743) (xy 33.752349 -28.178027)
			(xy 33.680248 -28.135338) (xy 33.612483 -28.086057) (xy 33.549654 -28.03062) (xy 33.492318 -27.969518)
			(xy 33.440985 -27.903295) (xy 33.396108 -27.832535) (xy 33.358086 -27.757869) (xy 33.327257 -27.679956)
			(xy 33.303893 -27.59949) (xy 33.288202 -27.517182) (xy 33.280323 -27.433763) (xy 33.279842 -27.391868)
			(xy 20.386214 -27.391868) (xy 20.361436 -27.397879) (xy 20.277601 -27.409932) (xy 20.193 -27.413963)
			(xy 20.108399 -27.409932) (xy 20.024564 -27.397879) (xy 19.942255 -27.377911) (xy 19.862216 -27.350209)
			(xy 19.785173 -27.315025) (xy 19.711823 -27.272676) (xy 19.642831 -27.223547) (xy 19.578821 -27.168082)
			(xy 19.520373 -27.106784) (xy 19.468017 -27.040208) (xy 19.422227 -26.968956) (xy 19.383416 -26.893675)
			(xy 19.351937 -26.815045) (xy 19.328076 -26.733778) (xy 19.312047 -26.650612) (xy 19.303996 -26.566298)
			(xy 17.196731 -26.566298) (xy 17.149069 -26.607597) (xy 17.080077 -26.656726) (xy 17.006727 -26.699075)
			(xy 16.929684 -26.734259) (xy 16.849645 -26.761961) (xy 16.767336 -26.781929) (xy 16.683501 -26.793982)
			(xy 16.5989 -26.798013) (xy 16.514299 -26.793982) (xy 16.430464 -26.781929) (xy 16.348155 -26.761961)
			(xy 16.268116 -26.734259) (xy 16.191073 -26.699075) (xy 16.117723 -26.656726) (xy 16.048731 -26.607597)
			(xy 15.984721 -26.552132) (xy 15.926273 -26.490834) (xy 15.873917 -26.424258) (xy 15.828127 -26.353006)
			(xy 15.789316 -26.277725) (xy 15.757837 -26.199095) (xy 15.733976 -26.117828) (xy 15.717947 -26.034662)
			(xy 15.709896 -25.950348) (xy 15.709392 -25.908) (xy 15.70969 -25.873763) (xy 15.714905 -25.805488)
			(xy 15.719806 -25.771602) (xy 15.721584 -25.76068) (xy 15.715488 -25.739344) (xy 15.650972 -25.663906)
			(xy 15.630906 -25.654508) (xy 15.61973 -25.654508) (xy 15.578666 -25.653976) (xy 15.496896 -25.646288)
			(xy 15.416183 -25.631095) (xy 15.337214 -25.608526) (xy 15.260663 -25.578773) (xy 15.18718 -25.54209)
			(xy 15.117391 -25.49879) (xy 15.051891 -25.44924) (xy 14.991238 -25.393864) (xy 14.935948 -25.333131)
			(xy 14.886492 -25.267561) (xy 14.843291 -25.197711) (xy 14.806713 -25.124175) (xy 14.77707 -25.047581)
			(xy 14.754614 -24.96858) (xy 14.739536 -24.887846) (xy 14.731965 -24.806065) (xy 14.731492 -24.765)
			(xy 9.973203 -24.765) (xy 9.972968 -24.765986) (xy 9.94139 -24.864008) (xy 9.902278 -24.959274) (xy 9.855869 -25.051207)
			(xy 9.802446 -25.139249) (xy 9.742332 -25.222865) (xy 9.675892 -25.301549) (xy 9.640062 -25.338532)
			(xy 9.632696 -25.345644) (xy 9.62533 -25.363932) (xy 9.62533 -25.45588) (xy 9.632696 -25.474168)
			(xy 9.640062 -25.48128) (xy 9.675887 -25.518269) (xy 9.742329 -25.596951) (xy 9.802444 -25.680566)
			(xy 9.855869 -25.768607) (xy 9.902279 -25.860539) (xy 9.941392 -25.955805) (xy 9.972971 -26.053826)
			(xy 9.996824 -26.154008) (xy 10.012807 -26.255743) (xy 10.020823 -26.358413) (xy 10.021316 -26.409904)
			(xy 10.020802 -26.461798) (xy 10.012659 -26.565267) (xy 9.996423 -26.667777) (xy 9.972194 -26.768698)
			(xy 9.940121 -26.867406) (xy 9.900403 -26.963294) (xy 9.853284 -27.05577) (xy 9.799055 -27.144264)
			(xy 9.738049 -27.228231) (xy 9.670644 -27.307152) (xy 9.597255 -27.380542) (xy 9.518334 -27.447947)
			(xy 9.434368 -27.508952) (xy 9.345874 -27.563182) (xy 9.253398 -27.610301) (xy 9.15751 -27.65002)
			(xy 9.058802 -27.682092) (xy 8.957881 -27.706322) (xy 8.855371 -27.722558) (xy 8.751902 -27.730702)
			(xy 8.700008 -27.731212) (xy 8.648517 -27.730698) (xy 8.545848 -27.722683) (xy 8.444114 -27.706701)
			(xy 8.343932 -27.68285) (xy 8.245911 -27.651273) (xy 8.150645 -27.612163) (xy 8.058712 -27.565757)
			(xy 7.97067 -27.512336) (xy 7.887053 -27.452225) (xy 7.808368 -27.385787) (xy 7.771384 -27.349958)
			(xy 7.764272 -27.342592) (xy 7.745984 -27.335226) (xy 7.654036 -27.335226) (xy 7.635748 -27.342592)
			(xy 7.628636 -27.349958) (xy 7.591639 -27.385775) (xy 7.512958 -27.452217) (xy 7.429344 -27.512333)
			(xy 7.341304 -27.565758) (xy 7.249373 -27.612169) (xy 7.154108 -27.651283) (xy 7.056088 -27.682863)
			(xy 6.955906 -27.706717) (xy 6.854172 -27.722702) (xy 6.751503 -27.730718) (xy 6.700012 -27.731212)
			(xy 6.648117 -27.7307) (xy 6.544648 -27.722558) (xy 6.442137 -27.706322) (xy 6.341215 -27.682094)
			(xy 6.242506 -27.650022) (xy 6.146617 -27.610305) (xy 6.05414 -27.563186) (xy 5.965644 -27.508957)
			(xy 5.881677 -27.447952) (xy 5.802755 -27.380547) (xy 5.729364 -27.307157) (xy 5.661958 -27.228236)
			(xy 5.600952 -27.144269) (xy 5.546722 -27.055774) (xy 5.499602 -26.963298) (xy 5.459883 -26.867409)
			(xy 5.42781 -26.7687) (xy 5.403581 -26.667779) (xy 5.387344 -26.565268) (xy 5.379201 -26.461799)
			(xy 5.378704 -26.409904) (xy 1.651254 -26.409904) (xy 1.651254 -28.060904) (xy 1.652778 -28.11145)
			(xy 1.651254 -28.161996) (xy 1.651254 -28.210948) (xy 14.020796 -28.210948) (xy 14.020796 -28.126252)
			(xy 14.028847 -28.041938) (xy 14.044876 -27.958772) (xy 14.068737 -27.877505) (xy 14.100216 -27.798875)
			(xy 14.139027 -27.723594) (xy 14.184817 -27.652342) (xy 14.237173 -27.585766) (xy 14.295621 -27.524468)
			(xy 14.359631 -27.469003) (xy 14.428623 -27.419874) (xy 14.501973 -27.377525) (xy 14.579016 -27.342341)
			(xy 14.659055 -27.314639) (xy 14.741364 -27.294671) (xy 14.825199 -27.282618) (xy 14.9098 -27.278588)
			(xy 14.994401 -27.282618) (xy 15.078236 -27.294671) (xy 15.160545 -27.314639) (xy 15.240584 -27.342341)
			(xy 15.317627 -27.377525) (xy 15.390977 -27.419874) (xy 15.459969 -27.469003) (xy 15.523979 -27.524468)
			(xy 15.582427 -27.585766) (xy 15.634783 -27.652342) (xy 15.680573 -27.723594) (xy 15.719384 -27.798875)
			(xy 15.750863 -27.877505) (xy 15.774724 -27.958772) (xy 15.790753 -28.041938) (xy 15.798804 -28.126252)
			(xy 15.799308 -28.1686) (xy 15.798804 -28.210948) (xy 15.792804 -28.273784) (xy 17.309197 -28.273784)
			(xy 17.311831 -28.189975) (xy 17.322339 -28.106786) (xy 17.34063 -28.024955) (xy 17.366541 -27.945208)
			(xy 17.399842 -27.868254) (xy 17.440236 -27.794775) (xy 17.487367 -27.725424) (xy 17.540814 -27.660816)
			(xy 17.600105 -27.601524) (xy 17.664713 -27.548075) (xy 17.734063 -27.500944) (xy 17.807541 -27.460548)
			(xy 17.884495 -27.427246) (xy 17.964241 -27.401334) (xy 18.046072 -27.383042) (xy 18.129261 -27.372532)
			(xy 18.21307 -27.369897) (xy 18.296755 -27.375161) (xy 18.379573 -27.388277) (xy 18.46079 -27.409129)
			(xy 18.539683 -27.437532) (xy 18.615554 -27.473232) (xy 18.687728 -27.515915) (xy 18.755565 -27.5652)
			(xy 18.818463 -27.620651) (xy 18.875863 -27.681774) (xy 18.927256 -27.748028) (xy 18.972187 -27.818825)
			(xy 19.010255 -27.893535) (xy 19.041124 -27.971497) (xy 19.064518 -28.052018) (xy 19.080232 -28.134383)
			(xy 19.088124 -28.217861) (xy 19.088608 -28.259786) (xy 19.088178 -28.29905) (xy 19.081296 -28.377275)
			(xy 19.067541 -28.454589) (xy 19.047018 -28.530387) (xy 19.01989 -28.60408) (xy 19.003518 -28.63977)
			(xy 18.998097 -28.652353) (xy 18.993455 -28.679343) (xy 18.996154 -28.706597) (xy 19.005998 -28.732153)
			(xy 19.022282 -28.754173) (xy 19.043832 -28.771073) (xy 19.069098 -28.781638) (xy 19.096265 -28.785107)
			(xy 19.123376 -28.781232) (xy 19.136106 -28.776168) (xy 19.178375 -28.758323) (xy 19.265772 -28.730382)
			(xy 19.35558 -28.711575) (xy 19.446845 -28.702102) (xy 19.492722 -28.701492) (xy 19.534646 -28.701999)
			(xy 19.618122 -28.709891) (xy 19.700484 -28.725605) (xy 19.781003 -28.749) (xy 19.858962 -28.779868)
			(xy 19.933671 -28.817936) (xy 20.004465 -28.862866) (xy 20.070717 -28.914258) (xy 20.131838 -28.971657)
			(xy 20.187287 -29.034554) (xy 20.23657 -29.102389) (xy 20.279251 -29.174562) (xy 20.31495 -29.250431)
			(xy 20.343351 -29.329322) (xy 20.345322 -29.337) (xy 30.479492 -29.337) (xy 30.479967 -29.295898)
			(xy 30.487552 -29.214043) (xy 30.502657 -29.133238) (xy 30.525153 -29.054171) (xy 30.554849 -28.977517)
			(xy 30.591491 -28.90393) (xy 30.634766 -28.834038) (xy 30.684306 -28.768437) (xy 30.739687 -28.707687)
			(xy 30.800437 -28.652306) (xy 30.866038 -28.602766) (xy 30.93593 -28.559491) (xy 31.009517 -28.522849)
			(xy 31.086171 -28.493153) (xy 31.165238 -28.470657) (xy 31.246043 -28.455552) (xy 31.327898 -28.447967)
			(xy 31.369 -28.447492) (xy 31.411685 -28.447945) (xy 31.496665 -28.456115) (xy 31.58047 -28.47239)
			(xy 31.66233 -28.49662) (xy 31.741492 -28.528581) (xy 31.817228 -28.567981) (xy 31.88884 -28.614456)
			(xy 31.955669 -28.667578) (xy 32.017101 -28.72686) (xy 32.072571 -28.791754) (xy 32.121567 -28.861665)
			(xy 32.16364 -28.935949) (xy 32.198401 -29.013922) (xy 32.225532 -29.094868) (xy 32.235648 -29.13634)
			(xy 32.238828 -29.147307) (xy 32.253084 -29.165108) (xy 32.26308 -29.17063) (xy 32.300352 -29.189081)
			(xy 32.371583 -29.232025) (xy 32.438493 -29.28143) (xy 32.5005 -29.336865) (xy 32.557062 -29.397846)
			(xy 32.607685 -29.46384) (xy 32.651927 -29.534272) (xy 32.689402 -29.608525) (xy 32.719782 -29.685952)
			(xy 32.742802 -29.765877) (xy 32.758262 -29.847602) (xy 32.766025 -29.930413) (xy 32.766508 -29.972)
			(xy 32.766033 -30.013102) (xy 32.758448 -30.094957) (xy 32.743343 -30.175762) (xy 32.720847 -30.254829)
			(xy 32.691151 -30.331483) (xy 32.654509 -30.40507) (xy 32.611234 -30.474962) (xy 32.561694 -30.540563)
			(xy 32.506313 -30.601313) (xy 32.453621 -30.649348) (xy 33.400996 -30.649348) (xy 33.400996 -30.564652)
			(xy 33.409047 -30.480338) (xy 33.425076 -30.397172) (xy 33.448937 -30.315905) (xy 33.480416 -30.237275)
			(xy 33.519227 -30.161994) (xy 33.565017 -30.090742) (xy 33.617373 -30.024166) (xy 33.675821 -29.962868)
			(xy 33.739831 -29.907403) (xy 33.808823 -29.858274) (xy 33.882173 -29.815925) (xy 33.959216 -29.780741)
			(xy 34.039255 -29.753039) (xy 34.121564 -29.733071) (xy 34.205399 -29.721018) (xy 34.29 -29.716988)
			(xy 34.374601 -29.721018) (xy 34.458436 -29.733071) (xy 34.540745 -29.753039) (xy 34.620784 -29.780741)
			(xy 34.697827 -29.815925) (xy 34.771177 -29.858274) (xy 34.840169 -29.907403) (xy 34.904179 -29.962868)
			(xy 34.962627 -30.024166) (xy 35.014983 -30.090742) (xy 35.060773 -30.161994) (xy 35.099584 -30.237275)
			(xy 35.131063 -30.315905) (xy 35.154924 -30.397172) (xy 35.170953 -30.480338) (xy 35.179004 -30.564652)
			(xy 35.179508 -30.607) (xy 35.179004 -30.649348) (xy 35.170953 -30.733662) (xy 35.154924 -30.816828)
			(xy 35.131063 -30.898095) (xy 35.099584 -30.976725) (xy 35.060773 -31.052006) (xy 35.014983 -31.123258)
			(xy 34.962627 -31.189834) (xy 34.904179 -31.251132) (xy 34.840169 -31.306597) (xy 34.771177 -31.355726)
			(xy 34.697827 -31.398075) (xy 34.620784 -31.433259) (xy 34.540745 -31.460961) (xy 34.458436 -31.480929)
			(xy 34.374601 -31.492982) (xy 34.29 -31.497013) (xy 34.205399 -31.492982) (xy 34.121564 -31.480929)
			(xy 34.039255 -31.460961) (xy 33.959216 -31.433259) (xy 33.882173 -31.398075) (xy 33.808823 -31.355726)
			(xy 33.739831 -31.306597) (xy 33.675821 -31.251132) (xy 33.617373 -31.189834) (xy 33.565017 -31.123258)
			(xy 33.519227 -31.052006) (xy 33.480416 -30.976725) (xy 33.448937 -30.898095) (xy 33.425076 -30.816828)
			(xy 33.409047 -30.733662) (xy 33.400996 -30.649348) (xy 32.453621 -30.649348) (xy 32.445563 -30.656694)
			(xy 32.379962 -30.706234) (xy 32.31007 -30.749509) (xy 32.236483 -30.786151) (xy 32.159829 -30.815847)
			(xy 32.080762 -30.838343) (xy 31.999957 -30.853448) (xy 31.918102 -30.861033) (xy 31.877 -30.861508)
			(xy 31.834315 -30.861055) (xy 31.749335 -30.852885) (xy 31.66553 -30.83661) (xy 31.58367 -30.81238)
			(xy 31.504508 -30.780419) (xy 31.428772 -30.741019) (xy 31.35716 -30.694544) (xy 31.290331 -30.641422)
			(xy 31.228899 -30.58214) (xy 31.173429 -30.517246) (xy 31.124433 -30.447335) (xy 31.08236 -30.373051)
			(xy 31.047599 -30.295078) (xy 31.020468 -30.214132) (xy 31.010352 -30.17266) (xy 31.007172 -30.161693)
			(xy 30.992916 -30.143892) (xy 30.98292 -30.13837) (xy 30.945648 -30.119919) (xy 30.874417 -30.076975)
			(xy 30.807507 -30.02757) (xy 30.7455 -29.972135) (xy 30.688938 -29.911154) (xy 30.638315 -29.84516)
			(xy 30.594073 -29.774728) (xy 30.556598 -29.700475) (xy 30.526218 -29.623048) (xy 30.503198 -29.543123)
			(xy 30.487738 -29.461398) (xy 30.479975 -29.378587) (xy 30.479492 -29.337) (xy 20.345322 -29.337)
			(xy 20.364202 -29.410537) (xy 20.377317 -29.493353) (xy 20.382581 -29.577035) (xy 20.379946 -29.660842)
			(xy 20.369436 -29.744029) (xy 20.351143 -29.825857) (xy 20.325232 -29.905601) (xy 20.29193 -29.982553)
			(xy 20.251535 -30.056029) (xy 20.204405 -30.125378) (xy 20.150957 -30.189983) (xy 20.091667 -30.249272)
			(xy 20.02706 -30.302718) (xy 19.965507 -30.344548) (xy 21.691596 -30.344548) (xy 21.691596 -30.259852)
			(xy 21.699647 -30.175538) (xy 21.715676 -30.092372) (xy 21.739537 -30.011105) (xy 21.771016 -29.932475)
			(xy 21.809827 -29.857194) (xy 21.855617 -29.785942) (xy 21.907973 -29.719366) (xy 21.966421 -29.658068)
			(xy 22.030431 -29.602603) (xy 22.099423 -29.553474) (xy 22.172773 -29.511125) (xy 22.249816 -29.475941)
			(xy 22.329855 -29.448239) (xy 22.412164 -29.428271) (xy 22.495999 -29.416218) (xy 22.5806 -29.412188)
			(xy 22.665201 -29.416218) (xy 22.749036 -29.428271) (xy 22.831345 -29.448239) (xy 22.911384 -29.475941)
			(xy 22.988427 -29.511125) (xy 23.061777 -29.553474) (xy 23.130769 -29.602603) (xy 23.194779 -29.658068)
			(xy 23.253227 -29.719366) (xy 23.305583 -29.785942) (xy 23.351373 -29.857194) (xy 23.390184 -29.932475)
			(xy 23.421663 -30.011105) (xy 23.445524 -30.092372) (xy 23.461553 -30.175538) (xy 23.469604 -30.259852)
			(xy 23.470108 -30.3022) (xy 23.469604 -30.344548) (xy 23.461553 -30.428862) (xy 23.445524 -30.512028)
			(xy 23.421663 -30.593295) (xy 23.390184 -30.671925) (xy 23.351373 -30.747206) (xy 23.305583 -30.818458)
			(xy 23.253227 -30.885034) (xy 23.194779 -30.946332) (xy 23.130769 -31.001797) (xy 23.061777 -31.050926)
			(xy 22.988427 -31.093275) (xy 22.911384 -31.128459) (xy 22.831345 -31.156161) (xy 22.749036 -31.176129)
			(xy 22.665201 -31.188182) (xy 22.5806 -31.192213) (xy 22.495999 -31.188182) (xy 22.412164 -31.176129)
			(xy 22.329855 -31.156161) (xy 22.249816 -31.128459) (xy 22.172773 -31.093275) (xy 22.099423 -31.050926)
			(xy 22.030431 -31.001797) (xy 21.966421 -30.946332) (xy 21.907973 -30.885034) (xy 21.855617 -30.818458)
			(xy 21.809827 -30.747206) (xy 21.771016 -30.671925) (xy 21.739537 -30.593295) (xy 21.715676 -30.512028)
			(xy 21.699647 -30.428862) (xy 21.691596 -30.344548) (xy 19.965507 -30.344548) (xy 19.95771 -30.349847)
			(xy 19.884233 -30.39024) (xy 19.807281 -30.423539) (xy 19.727536 -30.449449) (xy 19.645707 -30.467739)
			(xy 19.56252 -30.478248) (xy 19.478713 -30.480881) (xy 19.395031 -30.475615) (xy 19.312215 -30.462498)
			(xy 19.231001 -30.441645) (xy 19.15211 -30.413242) (xy 19.076242 -30.377541) (xy 19.004071 -30.334858)
			(xy 18.936237 -30.285573) (xy 18.873342 -30.230123) (xy 18.815944 -30.169) (xy 18.764553 -30.102747)
			(xy 18.719625 -30.031951) (xy 18.681559 -29.957242) (xy 18.650693 -29.879282) (xy 18.6273 -29.798763)
			(xy 18.611588 -29.7164) (xy 18.603697 -29.632924) (xy 18.603214 -29.591) (xy 18.603636 -29.551736)
			(xy 18.61052 -29.47351) (xy 18.624277 -29.396197) (xy 18.644801 -29.320398) (xy 18.671932 -29.246706)
			(xy 18.688304 -29.211016) (xy 18.693712 -29.19843) (xy 18.698349 -29.171443) (xy 18.695648 -29.144194)
			(xy 18.685804 -29.118642) (xy 18.669523 -29.096626) (xy 18.647977 -29.079727) (xy 18.622715 -29.069161)
			(xy 18.595553 -29.065688) (xy 18.568446 -29.069558) (xy 18.555716 -29.074618) (xy 18.513451 -29.092474)
			(xy 18.426053 -29.120418) (xy 18.336244 -29.139227) (xy 18.244978 -29.148703) (xy 18.1991 -29.149294)
			(xy 18.157175 -29.148824) (xy 18.073697 -29.140933) (xy 17.991331 -29.125222) (xy 17.91081 -29.101828)
			(xy 17.832848 -29.070961) (xy 17.758137 -29.032894) (xy 17.68734 -28.987965) (xy 17.621085 -28.936572)
			(xy 17.55996 -28.879173) (xy 17.504509 -28.816276) (xy 17.455223 -28.74844) (xy 17.412539 -28.676266)
			(xy 17.376837 -28.600396) (xy 17.348433 -28.521503) (xy 17.32758 -28.440287) (xy 17.314463 -28.357469)
			(xy 17.309197 -28.273784) (xy 15.792804 -28.273784) (xy 15.790753 -28.295262) (xy 15.774724 -28.378428)
			(xy 15.750863 -28.459695) (xy 15.719384 -28.538325) (xy 15.680573 -28.613606) (xy 15.634783 -28.684858)
			(xy 15.582427 -28.751434) (xy 15.523979 -28.812732) (xy 15.459969 -28.868197) (xy 15.390977 -28.917326)
			(xy 15.317627 -28.959675) (xy 15.240584 -28.994859) (xy 15.160545 -29.022561) (xy 15.078236 -29.042529)
			(xy 14.994401 -29.054582) (xy 14.9098 -29.058613) (xy 14.825199 -29.054582) (xy 14.741364 -29.042529)
			(xy 14.659055 -29.022561) (xy 14.579016 -28.994859) (xy 14.501973 -28.959675) (xy 14.428623 -28.917326)
			(xy 14.359631 -28.868197) (xy 14.295621 -28.812732) (xy 14.237173 -28.751434) (xy 14.184817 -28.684858)
			(xy 14.139027 -28.613606) (xy 14.100216 -28.538325) (xy 14.068737 -28.459695) (xy 14.044876 -28.378428)
			(xy 14.028847 -28.295262) (xy 14.020796 -28.210948) (xy 1.651254 -28.210948) (xy 1.651254 -32.946016)
			(xy 15.04086 -32.946016) (xy 15.04086 -32.86132) (xy 15.048911 -32.777006) (xy 15.06494 -32.69384)
			(xy 15.088801 -32.612573) (xy 15.12028 -32.533943) (xy 15.159091 -32.458662) (xy 15.204881 -32.38741)
			(xy 15.257237 -32.320834) (xy 15.315685 -32.259536) (xy 15.379695 -32.204071) (xy 15.448687 -32.154942)
			(xy 15.522037 -32.112593) (xy 15.59908 -32.077409) (xy 15.679119 -32.049707) (xy 15.761428 -32.029739)
			(xy 15.845263 -32.017686) (xy 15.929864 -32.013656) (xy 16.014465 -32.017686) (xy 16.0983 -32.029739)
			(xy 16.180609 -32.049707) (xy 16.260648 -32.077409) (xy 16.337691 -32.112593) (xy 16.411041 -32.154942)
			(xy 16.480033 -32.204071) (xy 16.544043 -32.259536) (xy 16.602491 -32.320834) (xy 16.654847 -32.38741)
			(xy 16.700637 -32.458662) (xy 16.739448 -32.533943) (xy 16.770927 -32.612573) (xy 16.794788 -32.69384)
			(xy 16.810817 -32.777006) (xy 16.818868 -32.86132) (xy 16.819372 -32.903668) (xy 16.818868 -32.946016)
			(xy 16.811803 -33.02) (xy 17.270988 -33.02) (xy 17.275018 -32.935399) (xy 17.287071 -32.851564) (xy 17.307039 -32.769255)
			(xy 17.334741 -32.689216) (xy 17.369925 -32.612173) (xy 17.412274 -32.538823) (xy 17.461403 -32.469831)
			(xy 17.516868 -32.405821) (xy 17.578166 -32.347373) (xy 17.644742 -32.295017) (xy 17.715994 -32.249227)
			(xy 17.791275 -32.210416) (xy 17.869905 -32.178937) (xy 17.951172 -32.155076) (xy 18.034338 -32.139047)
			(xy 18.118652 -32.130996) (xy 18.161 -32.130492) (xy 18.203315 -32.130995) (xy 18.287563 -32.139026)
			(xy 18.370666 -32.155024) (xy 18.451875 -32.178845) (xy 18.530452 -32.210272) (xy 18.605689 -32.249023)
			(xy 18.641568 -32.271462) (xy 18.649957 -32.276345) (xy 18.669 -32.280016) (xy 18.688043 -32.276345)
			(xy 18.696432 -32.271462) (xy 18.732306 -32.249016) (xy 18.807547 -32.210273) (xy 18.886126 -32.178849)
			(xy 18.967335 -32.15503) (xy 19.050438 -32.13903) (xy 19.134685 -32.130994) (xy 19.177 -32.130492)
			(xy 19.218102 -32.130967) (xy 19.299957 -32.138552) (xy 19.380762 -32.153657) (xy 19.459829 -32.176153)
			(xy 19.536483 -32.205849) (xy 19.61007 -32.242491) (xy 19.679962 -32.285766) (xy 19.699272 -32.300348)
			(xy 28.193996 -32.300348) (xy 28.193996 -32.215652) (xy 28.202047 -32.131338) (xy 28.218076 -32.048172)
			(xy 28.241937 -31.966905) (xy 28.273416 -31.888275) (xy 28.312227 -31.812994) (xy 28.358017 -31.741742)
			(xy 28.410373 -31.675166) (xy 28.468821 -31.613868) (xy 28.532831 -31.558403) (xy 28.601823 -31.509274)
			(xy 28.675173 -31.466925) (xy 28.752216 -31.431741) (xy 28.832255 -31.404039) (xy 28.914564 -31.384071)
			(xy 28.998399 -31.372018) (xy 29.083 -31.367988) (xy 29.167601 -31.372018) (xy 29.251436 -31.384071)
			(xy 29.333745 -31.404039) (xy 29.413784 -31.431741) (xy 29.490827 -31.466925) (xy 29.564177 -31.509274)
			(xy 29.633169 -31.558403) (xy 29.697179 -31.613868) (xy 29.755627 -31.675166) (xy 29.807983 -31.741742)
			(xy 29.853773 -31.812994) (xy 29.892584 -31.888275) (xy 29.924063 -31.966905) (xy 29.947924 -32.048172)
			(xy 29.963953 -32.131338) (xy 29.972004 -32.215652) (xy 29.972508 -32.258) (xy 29.972004 -32.300348)
			(xy 29.963953 -32.384662) (xy 29.947924 -32.467828) (xy 29.924063 -32.549095) (xy 29.892584 -32.627725)
			(xy 29.853773 -32.703006) (xy 29.807983 -32.774258) (xy 29.755627 -32.840834) (xy 29.697179 -32.902132)
			(xy 29.658846 -32.935348) (xy 31.495996 -32.935348) (xy 31.495996 -32.850652) (xy 31.504047 -32.766338)
			(xy 31.520076 -32.683172) (xy 31.543937 -32.601905) (xy 31.575416 -32.523275) (xy 31.614227 -32.447994)
			(xy 31.660017 -32.376742) (xy 31.712373 -32.310166) (xy 31.770821 -32.248868) (xy 31.834831 -32.193403)
			(xy 31.903823 -32.144274) (xy 31.977173 -32.101925) (xy 32.054216 -32.066741) (xy 32.134255 -32.039039)
			(xy 32.216564 -32.019071) (xy 32.300399 -32.007018) (xy 32.385 -32.002988) (xy 32.469601 -32.007018)
			(xy 32.553436 -32.019071) (xy 32.635745 -32.039039) (xy 32.715784 -32.066741) (xy 32.792827 -32.101925)
			(xy 32.866177 -32.144274) (xy 32.935169 -32.193403) (xy 32.999179 -32.248868) (xy 33.057627 -32.310166)
			(xy 33.109983 -32.376742) (xy 33.155773 -32.447994) (xy 33.194584 -32.523275) (xy 33.226063 -32.601905)
			(xy 33.249924 -32.683172) (xy 33.265953 -32.766338) (xy 33.274004 -32.850652) (xy 33.274508 -32.893)
			(xy 33.274004 -32.935348) (xy 33.265953 -33.019662) (xy 33.249924 -33.102828) (xy 33.226063 -33.184095)
			(xy 33.194584 -33.262725) (xy 33.155773 -33.338006) (xy 33.109983 -33.409258) (xy 33.057627 -33.475834)
			(xy 32.999179 -33.537132) (xy 32.935169 -33.592597) (xy 32.866177 -33.641726) (xy 32.792827 -33.684075)
			(xy 32.715784 -33.719259) (xy 32.635745 -33.746961) (xy 32.578502 -33.760848) (xy 33.591496 -33.760848)
			(xy 33.591496 -33.676152) (xy 33.599547 -33.591838) (xy 33.615576 -33.508672) (xy 33.639437 -33.427405)
			(xy 33.670916 -33.348775) (xy 33.709727 -33.273494) (xy 33.755517 -33.202242) (xy 33.807873 -33.135666)
			(xy 33.866321 -33.074368) (xy 33.930331 -33.018903) (xy 33.999323 -32.969774) (xy 34.072673 -32.927425)
			(xy 34.149716 -32.892241) (xy 34.229755 -32.864539) (xy 34.312064 -32.844571) (xy 34.395899 -32.832518)
			(xy 34.4805 -32.828488) (xy 34.565101 -32.832518) (xy 34.648936 -32.844571) (xy 34.731245 -32.864539)
			(xy 34.811284 -32.892241) (xy 34.888327 -32.927425) (xy 34.961677 -32.969774) (xy 35.030669 -33.018903)
			(xy 35.094679 -33.074368) (xy 35.153127 -33.135666) (xy 35.205483 -33.202242) (xy 35.251273 -33.273494)
			(xy 35.290084 -33.348775) (xy 35.321563 -33.427405) (xy 35.345424 -33.508672) (xy 35.361453 -33.591838)
			(xy 35.369504 -33.676152) (xy 35.370008 -33.7185) (xy 35.369504 -33.760848) (xy 35.361453 -33.845162)
			(xy 35.345424 -33.928328) (xy 35.321563 -34.009595) (xy 35.290084 -34.088225) (xy 35.251273 -34.163506)
			(xy 35.205483 -34.234758) (xy 35.153127 -34.301334) (xy 35.094679 -34.362632) (xy 35.030669 -34.418097)
			(xy 34.961677 -34.467226) (xy 34.888327 -34.509575) (xy 34.811284 -34.544759) (xy 34.731245 -34.572461)
			(xy 34.648936 -34.592429) (xy 34.565101 -34.604482) (xy 34.4805 -34.608513) (xy 34.395899 -34.604482)
			(xy 34.312064 -34.592429) (xy 34.229755 -34.572461) (xy 34.149716 -34.544759) (xy 34.072673 -34.509575)
			(xy 33.999323 -34.467226) (xy 33.930331 -34.418097) (xy 33.866321 -34.362632) (xy 33.807873 -34.301334)
			(xy 33.755517 -34.234758) (xy 33.709727 -34.163506) (xy 33.670916 -34.088225) (xy 33.639437 -34.009595)
			(xy 33.615576 -33.928328) (xy 33.599547 -33.845162) (xy 33.591496 -33.760848) (xy 32.578502 -33.760848)
			(xy 32.553436 -33.766929) (xy 32.469601 -33.778982) (xy 32.385 -33.783013) (xy 32.300399 -33.778982)
			(xy 32.216564 -33.766929) (xy 32.134255 -33.746961) (xy 32.054216 -33.719259) (xy 31.977173 -33.684075)
			(xy 31.903823 -33.641726) (xy 31.834831 -33.592597) (xy 31.770821 -33.537132) (xy 31.712373 -33.475834)
			(xy 31.660017 -33.409258) (xy 31.614227 -33.338006) (xy 31.575416 -33.262725) (xy 31.543937 -33.184095)
			(xy 31.520076 -33.102828) (xy 31.504047 -33.019662) (xy 31.495996 -32.935348) (xy 29.658846 -32.935348)
			(xy 29.633169 -32.957597) (xy 29.564177 -33.006726) (xy 29.490827 -33.049075) (xy 29.413784 -33.084259)
			(xy 29.333745 -33.111961) (xy 29.251436 -33.131929) (xy 29.167601 -33.143982) (xy 29.083 -33.148013)
			(xy 28.998399 -33.143982) (xy 28.914564 -33.131929) (xy 28.832255 -33.111961) (xy 28.752216 -33.084259)
			(xy 28.675173 -33.049075) (xy 28.601823 -33.006726) (xy 28.532831 -32.957597) (xy 28.468821 -32.902132)
			(xy 28.410373 -32.840834) (xy 28.358017 -32.774258) (xy 28.312227 -32.703006) (xy 28.273416 -32.627725)
			(xy 28.241937 -32.549095) (xy 28.218076 -32.467828) (xy 28.202047 -32.384662) (xy 28.193996 -32.300348)
			(xy 19.699272 -32.300348) (xy 19.745563 -32.335306) (xy 19.806313 -32.390687) (xy 19.861694 -32.451437)
			(xy 19.911234 -32.517038) (xy 19.954509 -32.58693) (xy 19.991151 -32.660517) (xy 20.020847 -32.737171)
			(xy 20.043343 -32.816238) (xy 20.058448 -32.897043) (xy 20.066033 -32.978898) (xy 20.066508 -33.02)
			(xy 20.066081 -33.059569) (xy 20.059076 -33.138397) (xy 20.045096 -33.216291) (xy 20.02425 -33.292635)
			(xy 20.010882 -33.32988) (xy 20.008193 -33.3379) (xy 20.00781 -33.354805) (xy 20.012942 -33.370917)
			(xy 20.01774 -33.377886) (xy 20.041623 -33.410792) (xy 20.083993 -33.480195) (xy 20.119852 -33.553174)
			(xy 20.148902 -33.629122) (xy 20.170899 -33.707404) (xy 20.185661 -33.787367) (xy 20.193063 -33.868343)
			(xy 20.193508 -33.909) (xy 20.193033 -33.950102) (xy 20.185448 -34.031957) (xy 20.170343 -34.112762)
			(xy 20.147847 -34.191829) (xy 20.118151 -34.268483) (xy 20.081509 -34.34207) (xy 20.038234 -34.411962)
			(xy 19.988694 -34.477563) (xy 19.933313 -34.538313) (xy 19.872563 -34.593694) (xy 19.806962 -34.643234)
			(xy 19.73707 -34.686509) (xy 19.663483 -34.723151) (xy 19.586829 -34.752847) (xy 19.507762 -34.775343)
			(xy 19.426957 -34.790448) (xy 19.345102 -34.798033) (xy 19.304 -34.798508) (xy 19.262844 -34.798042)
			(xy 19.180883 -34.790455) (xy 19.099973 -34.775327) (xy 19.020808 -34.752788) (xy 18.944063 -34.723031)
			(xy 18.870397 -34.68631) (xy 18.800438 -34.64294) (xy 18.734786 -34.593291) (xy 18.674002 -34.537789)
			(xy 18.618607 -34.476907) (xy 18.569074 -34.411168) (xy 18.525827 -34.341133) (xy 18.489236 -34.267402)
			(xy 18.459614 -34.190605) (xy 18.437215 -34.111399) (xy 18.42223 -34.030463) (xy 18.418048 -33.989518)
			(xy 18.417286 -33.97885) (xy 18.407126 -33.960562) (xy 18.331688 -33.901888) (xy 18.311368 -33.896808)
			(xy 18.300954 -33.898332) (xy 18.266201 -33.903554) (xy 18.196141 -33.909147) (xy 18.161 -33.909508)
			(xy 18.118652 -33.909004) (xy 18.034338 -33.900953) (xy 17.951172 -33.884924) (xy 17.869905 -33.861063)
			(xy 17.791275 -33.829584) (xy 17.715994 -33.790773) (xy 17.644742 -33.744983) (xy 17.578166 -33.692627)
			(xy 17.516868 -33.634179) (xy 17.461403 -33.570169) (xy 17.412274 -33.501177) (xy 17.369925 -33.427827)
			(xy 17.334741 -33.350784) (xy 17.307039 -33.270745) (xy 17.287071 -33.188436) (xy 17.275018 -33.104601)
			(xy 17.270988 -33.02) (xy 16.811803 -33.02) (xy 16.810817 -33.03033) (xy 16.794788 -33.113496) (xy 16.770927 -33.194763)
			(xy 16.739448 -33.273393) (xy 16.700637 -33.348674) (xy 16.654847 -33.419926) (xy 16.602491 -33.486502)
			(xy 16.544043 -33.5478) (xy 16.480033 -33.603265) (xy 16.411041 -33.652394) (xy 16.337691 -33.694743)
			(xy 16.260648 -33.729927) (xy 16.180609 -33.757629) (xy 16.0983 -33.777597) (xy 16.014465 -33.78965)
			(xy 15.929864 -33.793681) (xy 15.845263 -33.78965) (xy 15.761428 -33.777597) (xy 15.679119 -33.757629)
			(xy 15.59908 -33.729927) (xy 15.522037 -33.694743) (xy 15.448687 -33.652394) (xy 15.379695 -33.603265)
			(xy 15.315685 -33.5478) (xy 15.257237 -33.486502) (xy 15.204881 -33.419926) (xy 15.159091 -33.348674)
			(xy 15.12028 -33.273393) (xy 15.088801 -33.194763) (xy 15.06494 -33.113496) (xy 15.048911 -33.03033)
			(xy 15.04086 -32.946016) (xy 1.651254 -32.946016) (xy 1.651254 -33.140904) (xy 1.652778 -33.19145)
			(xy 1.651254 -33.241996) (xy 1.651254 -38.220904) (xy 1.652778 -38.27145) (xy 1.651254 -38.321996)
			(xy 1.651254 -39.851838) (xy 1.651605 -39.86079) (xy 1.657761 -39.877603) (xy 1.669312 -39.891284)
			(xy 1.676908 -39.896034) (xy 1.766062 -39.946326) (xy 1.79324 -39.946072) (xy 1.805178 -39.93896)
			(xy 1.841319 -39.917832) (xy 1.91684 -39.881693) (xy 1.995425 -39.852819) (xy 2.076378 -39.831465)
			(xy 2.117598 -39.824152) (xy 2.129282 -39.82212) (xy 2.148078 -39.808912) (xy 2.198116 -39.718488)
			(xy 2.199386 -39.695882) (xy 2.194814 -39.684706) (xy 2.178438 -39.643999) (xy 2.15285 -39.560064)
			(xy 2.135652 -39.474018) (xy 2.127009 -39.386696) (xy 2.126488 -39.342822) (xy 2.126992 -39.300474)
			(xy 2.135043 -39.21616) (xy 2.151072 -39.132994) (xy 2.174933 -39.051727) (xy 2.206412 -38.973097)
			(xy 2.245223 -38.897816) (xy 2.291013 -38.826564) (xy 2.343369 -38.759988) (xy 2.401817 -38.69869)
			(xy 2.465827 -38.643225) (xy 2.534819 -38.594096) (xy 2.608169 -38.551747) (xy 2.685212 -38.516563)
			(xy 2.765251 -38.488861) (xy 2.84756 -38.468893) (xy 2.931395 -38.45684) (xy 3.015996 -38.45281)
			(xy 3.100597 -38.45684) (xy 3.184432 -38.468893) (xy 3.266741 -38.488861) (xy 3.34678 -38.516563)
			(xy 3.423823 -38.551747) (xy 3.497173 -38.594096) (xy 3.566165 -38.643225) (xy 3.573587 -38.649656)
			(xy 10.387838 -38.649656) (xy 10.388269 -38.611368) (xy 10.394891 -38.535077) (xy 10.408039 -38.459638)
			(xy 10.427617 -38.385605) (xy 10.440162 -38.349428) (xy 10.442827 -38.340996) (xy 10.442813 -38.323322)
			(xy 10.440162 -38.314884) (xy 10.427591 -38.278714) (xy 10.407999 -38.204683) (xy 10.394852 -38.12924)
			(xy 10.388247 -38.052946) (xy 10.387838 -38.014656) (xy 10.388364 -37.971538) (xy 10.396707 -37.885706)
			(xy 10.41332 -37.801085) (xy 10.438046 -37.71847) (xy 10.453878 -37.67836) (xy 10.45724 -37.668998)
			(xy 10.457224 -37.649122) (xy 10.453878 -37.639752) (xy 10.438056 -37.599638) (xy 10.413323 -37.517025)
			(xy 10.396702 -37.432405) (xy 10.388349 -37.346574) (xy 10.387838 -37.303456) (xy 10.388313 -37.262354)
			(xy 10.395898 -37.180499) (xy 10.411003 -37.099694) (xy 10.4335 -37.020628) (xy 10.463196 -36.943974)
			(xy 10.499838 -36.870387) (xy 10.543114 -36.800495) (xy 10.592653 -36.734894) (xy 10.648034 -36.674144)
			(xy 10.708784 -36.618763) (xy 10.774385 -36.569224) (xy 10.844277 -36.525948) (xy 10.917864 -36.489306)
			(xy 10.994518 -36.45961) (xy 11.073584 -36.437113) (xy 11.154389 -36.422008) (xy 11.236244 -36.414423)
			(xy 11.277346 -36.413948) (xy 11.323741 -36.414545) (xy 11.416029 -36.424185) (xy 11.506813 -36.443377)
			(xy 11.595107 -36.471912) (xy 11.637772 -36.490148) (xy 11.647712 -36.493968) (xy 11.66898 -36.493968)
			(xy 11.67892 -36.490148) (xy 11.721577 -36.471891) (xy 11.809871 -36.44335) (xy 11.900658 -36.42416)
			(xy 11.99295 -36.414531) (xy 12.039346 -36.413948) (xy 12.080448 -36.41443) (xy 12.162302 -36.422015)
			(xy 12.243107 -36.43712) (xy 12.322174 -36.459616) (xy 12.398828 -36.489311) (xy 12.472414 -36.525952)
			(xy 12.542306 -36.569227) (xy 12.607907 -36.618766) (xy 12.668657 -36.674147) (xy 12.724039 -36.734897)
			(xy 12.773578 -36.800497) (xy 12.816854 -36.870389) (xy 12.853496 -36.943975) (xy 12.883192 -37.020629)
			(xy 12.905689 -37.099695) (xy 12.920794 -37.1805) (xy 12.928379 -37.262354) (xy 12.928854 -37.303456)
			(xy 12.928332 -37.346574) (xy 12.919988 -37.432406) (xy 12.903374 -37.517027) (xy 12.878647 -37.599643)
			(xy 12.862814 -37.639752) (xy 12.859501 -37.649128) (xy 12.859485 -37.668991) (xy 12.862814 -37.67836)
			(xy 12.878639 -37.718473) (xy 12.903372 -37.801087) (xy 12.919992 -37.885706) (xy 12.928343 -37.971538)
			(xy 12.928854 -38.014656) (xy 12.928427 -38.052944) (xy 12.921804 -38.129235) (xy 12.908654 -38.204675)
			(xy 12.889075 -38.278707) (xy 12.87653 -38.314884) (xy 12.873909 -38.323327) (xy 12.873895 -38.34099)
			(xy 12.87653 -38.349428) (xy 12.889104 -38.385597) (xy 12.908695 -38.459628) (xy 12.921842 -38.535071)
			(xy 12.928446 -38.611366) (xy 12.928854 -38.649656) (xy 12.928394 -38.690759) (xy 12.920809 -38.772615)
			(xy 12.905704 -38.853422) (xy 12.883208 -38.93249) (xy 12.853511 -39.009145) (xy 12.816869 -39.082734)
			(xy 12.773593 -39.152627) (xy 12.724053 -39.218229) (xy 12.66867 -39.27898) (xy 12.607919 -39.334363)
			(xy 12.542317 -39.383903) (xy 12.472424 -39.427179) (xy 12.398835 -39.463821) (xy 12.32218 -39.493518)
			(xy 12.243112 -39.516014) (xy 12.162305 -39.531119) (xy 12.080449 -39.538704) (xy 12.039346 -39.539164)
			(xy 11.992951 -39.538569) (xy 11.900663 -39.528928) (xy 11.809879 -39.509736) (xy 11.721585 -39.4812)
			(xy 11.67892 -39.462964) (xy 11.66898 -39.459144) (xy 11.647712 -39.459144) (xy 11.637772 -39.462964)
			(xy 11.595102 -39.481191) (xy 11.506813 -39.50974) (xy 11.41603 -39.528938) (xy 11.323741 -39.538577)
			(xy 11.277346 -39.539164) (xy 11.236243 -39.538697) (xy 11.154389 -39.531112) (xy 11.073583 -39.516006)
			(xy 10.994516 -39.493509) (xy 10.917862 -39.463813) (xy 10.844275 -39.427171) (xy 10.774383 -39.383895)
			(xy 10.708782 -39.334355) (xy 10.648031 -39.278973) (xy 10.59265 -39.218222) (xy 10.543111 -39.152621)
			(xy 10.499835 -39.082728) (xy 10.463194 -39.009141) (xy 10.433498 -38.932486) (xy 10.411002 -38.853419)
			(xy 10.395897 -38.772613) (xy 10.388312 -38.690759) (xy 10.387838 -38.649656) (xy 3.573587 -38.649656)
			(xy 3.630175 -38.69869) (xy 3.688623 -38.759988) (xy 3.740979 -38.826564) (xy 3.786769 -38.897816)
			(xy 3.82558 -38.973097) (xy 3.857059 -39.051727) (xy 3.88092 -39.132994) (xy 3.896949 -39.21616)
			(xy 3.905 -39.300474) (xy 3.905504 -39.342822) (xy 3.905031 -39.384548) (xy 3.897217 -39.467634)
			(xy 3.881654 -39.549623) (xy 3.85848 -39.629793) (xy 3.827898 -39.70744) (xy 3.790177 -39.781882)
			(xy 3.745649 -39.852462) (xy 3.694706 -39.918561) (xy 3.637795 -39.979598) (xy 3.575417 -40.035036)
			(xy 3.508121 -40.084387) (xy 3.436497 -40.127217) (xy 3.361177 -40.16315) (xy 3.282822 -40.191869)
			(xy 3.202121 -40.213123) (xy 3.16103 -40.220392) (xy 3.149346 -40.222424) (xy 3.13055 -40.235632)
			(xy 3.080512 -40.326056) (xy 3.079242 -40.348662) (xy 3.083814 -40.359838) (xy 3.100188 -40.400545)
			(xy 3.12577 -40.484481) (xy 3.142964 -40.570527) (xy 3.151602 -40.657848) (xy 3.15214 -40.701722)
			(xy 3.151555 -40.748118) (xy 3.141921 -40.840408) (xy 3.122728 -40.931193) (xy 3.094184 -41.019485)
			(xy 3.07594 -41.062148) (xy 3.072127 -41.072088) (xy 3.072135 -41.093352) (xy 3.07594 -41.103296)
			(xy 3.094178 -41.145961) (xy 3.122716 -41.234254) (xy 3.141912 -41.325038) (xy 3.151555 -41.417326)
			(xy 3.15214 -41.463722) (xy 3.151665 -41.504824) (xy 3.14408 -41.586679) (xy 3.128975 -41.667484)
			(xy 3.106478 -41.746551) (xy 3.076782 -41.823204) (xy 3.04014 -41.896791) (xy 2.996865 -41.966683)
			(xy 2.947326 -42.032284) (xy 2.891944 -42.093034) (xy 2.831194 -42.148416) (xy 2.765593 -42.197955)
			(xy 2.695701 -42.24123) (xy 2.622114 -42.277872) (xy 2.545461 -42.307568) (xy 2.466394 -42.330065)
			(xy 2.385589 -42.34517) (xy 2.303734 -42.352755) (xy 2.262632 -42.35323) (xy 2.222584 -42.352774)
			(xy 2.142813 -42.345545) (xy 2.064015 -42.331177) (xy 1.986826 -42.309788) (xy 1.911871 -42.281551)
			(xy 1.839757 -42.246693) (xy 1.805178 -42.226484) (xy 1.79324 -42.219372) (xy 1.766062 -42.219118)
			(xy 1.676908 -42.26941) (xy 1.669286 -42.274135) (xy 1.657704 -42.287811) (xy 1.651553 -42.304645)
			(xy 1.651254 -42.313606) (xy 1.651254 -43.300904) (xy 1.652778 -43.35145) (xy 1.651254 -43.401996)
			(xy 1.651254 -44.181522) (xy 1.957324 -44.181522) (xy 1.957912 -44.135127) (xy 1.967555 -44.042838)
			(xy 1.986749 -43.952054) (xy 2.015287 -43.863761) (xy 2.033524 -43.821096) (xy 2.037331 -43.811152)
			(xy 2.037339 -43.789888) (xy 2.033524 -43.779948) (xy 2.015281 -43.737285) (xy 1.986736 -43.648993)
			(xy 1.967543 -43.558208) (xy 1.957909 -43.465918) (xy 1.957324 -43.419522) (xy 1.957784 -43.378419)
			(xy 1.965369 -43.296563) (xy 1.980474 -43.215756) (xy 2.002971 -43.136688) (xy 2.032667 -43.060033)
			(xy 2.06931 -42.986445) (xy 2.112586 -42.916552) (xy 2.162126 -42.850949) (xy 2.217508 -42.790198)
			(xy 2.278259 -42.734816) (xy 2.343862 -42.685276) (xy 2.413755 -42.642) (xy 2.487343 -42.605357)
			(xy 2.563998 -42.575661) (xy 2.643066 -42.553164) (xy 2.723873 -42.538059) (xy 2.805729 -42.530474)
			(xy 2.846832 -42.530014) (xy 2.88512 -42.53045) (xy 2.96141 -42.537071) (xy 3.03685 -42.550218) (xy 3.110882 -42.569794)
			(xy 3.14706 -42.582338) (xy 3.155498 -42.58498) (xy 3.173166 -42.58498) (xy 3.181604 -42.582338)
			(xy 3.217776 -42.569773) (xy 3.291806 -42.550179) (xy 3.367248 -42.53703) (xy 3.443542 -42.530423)
			(xy 3.481832 -42.530014) (xy 3.522935 -42.530485) (xy 3.604789 -42.53807) (xy 3.685595 -42.553175)
			(xy 3.764661 -42.575672) (xy 3.841315 -42.605368) (xy 3.914902 -42.64201) (xy 3.984795 -42.685286)
			(xy 4.050396 -42.734826) (xy 4.111146 -42.790207) (xy 4.166527 -42.850957) (xy 4.216067 -42.916559)
			(xy 4.259342 -42.986451) (xy 4.295984 -43.060038) (xy 4.325679 -43.136692) (xy 4.348176 -43.215759)
			(xy 4.363281 -43.296565) (xy 4.370865 -43.378419) (xy 4.37134 -43.419522) (xy 4.370735 -43.465917)
			(xy 4.361098 -43.558205) (xy 4.341908 -43.648989) (xy 4.313375 -43.737283) (xy 4.29514 -43.779948)
			(xy 4.291309 -43.789884) (xy 4.291318 -43.811156) (xy 4.29514 -43.821096) (xy 4.313385 -43.863758)
			(xy 4.341929 -43.95205) (xy 4.361122 -44.042836) (xy 4.370755 -44.135126) (xy 4.37134 -44.181522)
			(xy 4.370826 -44.225331) (xy 4.367101 -44.263056) (xy 10.41019 -44.263056) (xy 10.410793 -44.216661)
			(xy 10.420432 -44.124373) (xy 10.439622 -44.033589) (xy 10.468155 -43.945295) (xy 10.48639 -43.90263)
			(xy 10.490321 -43.892716) (xy 10.490304 -43.871404) (xy 10.48639 -43.861482) (xy 10.468131 -43.818826)
			(xy 10.43959 -43.730531) (xy 10.420401 -43.639744) (xy 10.410773 -43.547453) (xy 10.41019 -43.501056)
			(xy 10.410625 -43.459953) (xy 10.418213 -43.378098) (xy 10.433322 -43.297292) (xy 10.455822 -43.218224)
			(xy 10.485522 -43.14157) (xy 10.522167 -43.067983) (xy 10.565445 -42.998092) (xy 10.614987 -42.932491)
			(xy 10.670371 -42.871741) (xy 10.731123 -42.81636) (xy 10.796726 -42.766821) (xy 10.86662 -42.723546)
			(xy 10.940209 -42.686905) (xy 11.016864 -42.657209) (xy 11.095932 -42.634713) (xy 11.176739 -42.619608)
			(xy 11.258595 -42.612023) (xy 11.299698 -42.611548) (xy 11.346094 -42.612127) (xy 11.438382 -42.621772)
			(xy 11.529166 -42.640969) (xy 11.617459 -42.669509) (xy 11.660124 -42.687748) (xy 11.670064 -42.691568)
			(xy 11.691332 -42.691568) (xy 11.701272 -42.687748) (xy 11.743936 -42.669507) (xy 11.832227 -42.640961)
			(xy 11.923012 -42.621767) (xy 12.015302 -42.612133) (xy 12.061698 -42.611548) (xy 12.1028 -42.612029)
			(xy 12.184654 -42.619613) (xy 12.265459 -42.634718) (xy 12.344526 -42.657214) (xy 12.42118 -42.68691)
			(xy 12.494766 -42.723551) (xy 12.564658 -42.766826) (xy 12.630259 -42.816366) (xy 12.691009 -42.871746)
			(xy 12.746391 -42.932496) (xy 12.79593 -42.998097) (xy 12.839206 -43.067988) (xy 12.875848 -43.141575)
			(xy 12.905544 -43.218228) (xy 12.928041 -43.297295) (xy 12.943146 -43.3781) (xy 12.950731 -43.459954)
			(xy 12.951206 -43.501056) (xy 12.950608 -43.547451) (xy 12.940967 -43.639739) (xy 12.921776 -43.730523)
			(xy 12.893242 -43.818817) (xy 12.875006 -43.861482) (xy 12.871127 -43.871412) (xy 12.87111 -43.892709)
			(xy 12.875006 -43.90263) (xy 12.893236 -43.945298) (xy 12.921784 -44.033588) (xy 12.940981 -44.124372)
			(xy 12.950619 -44.21666) (xy 12.951206 -44.263056) (xy 12.950706 -44.304159) (xy 12.943125 -44.386013)
			(xy 12.928023 -44.466819) (xy 12.90553 -44.545887) (xy 12.875837 -44.622542) (xy 12.839197 -44.69613)
			(xy 12.795924 -44.766023) (xy 12.746387 -44.831626) (xy 12.691007 -44.892377) (xy 12.630258 -44.94776)
			(xy 12.564658 -44.997301) (xy 12.494767 -45.040577) (xy 12.42118 -45.07722) (xy 12.344527 -45.106917)
			(xy 12.26546 -45.129414) (xy 12.184655 -45.144519) (xy 12.1028 -45.152104) (xy 12.061698 -45.152564)
			(xy 12.015302 -45.151986) (xy 11.923014 -45.14234) (xy 11.83223 -45.123143) (xy 11.743937 -45.094603)
			(xy 11.701272 -45.076364) (xy 11.691332 -45.072544) (xy 11.670064 -45.072544) (xy 11.660124 -45.076364)
			(xy 11.617461 -45.094607) (xy 11.529169 -45.123152) (xy 11.438384 -45.142346) (xy 11.346094 -45.151979)
			(xy 11.299698 -45.152564) (xy 11.258595 -45.15211) (xy 11.176739 -45.144524) (xy 11.095932 -45.129419)
			(xy 11.016864 -45.106922) (xy 10.940208 -45.077225) (xy 10.86662 -45.040582) (xy 10.796727 -44.997306)
			(xy 10.731124 -44.947765) (xy 10.670373 -44.892383) (xy 10.614991 -44.831631) (xy 10.565451 -44.766028)
			(xy 10.522175 -44.696135) (xy 10.485533 -44.622546) (xy 10.455836 -44.545891) (xy 10.43334 -44.466822)
			(xy 10.418235 -44.386015) (xy 10.41065 -44.304159) (xy 10.41019 -44.263056) (xy 4.367101 -44.263056)
			(xy 4.362216 -44.312526) (xy 4.34507 -44.39845) (xy 4.319556 -44.482272) (xy 4.285921 -44.563177)
			(xy 4.244491 -44.640382) (xy 4.195669 -44.713137) (xy 4.139926 -44.780737) (xy 4.077805 -44.842527)
			(xy 4.044188 -44.870624) (xy 4.036568 -44.876974) (xy 4.026916 -44.894246) (xy 4.016502 -44.984416)
			(xy 4.021836 -45.003466) (xy 4.027678 -45.01134) (xy 4.052644 -45.044643) (xy 4.096958 -45.115106)
			(xy 4.1345 -45.189399) (xy 4.164942 -45.266872) (xy 4.188017 -45.346848) (xy 4.203524 -45.42863)
			(xy 4.211328 -45.511503) (xy 4.211828 -45.553122) (xy 4.211216 -45.599517) (xy 4.201579 -45.691804)
			(xy 4.182392 -45.782588) (xy 4.153862 -45.870882) (xy 4.135628 -45.913548) (xy 4.131798 -45.923484)
			(xy 4.131806 -45.944756) (xy 4.135628 -45.954696) (xy 4.153873 -45.997358) (xy 4.182417 -46.085651)
			(xy 4.20161 -46.176436) (xy 4.211243 -46.268726) (xy 4.211828 -46.315122) (xy 4.211324 -46.35747)
			(xy 4.208092 -46.391322) (xy 7.843012 -46.391322) (xy 7.843601 -46.344927) (xy 7.853244 -46.252638)
			(xy 7.872438 -46.161855) (xy 7.900975 -46.073561) (xy 7.919212 -46.030896) (xy 7.923019 -46.020952)
			(xy 7.923028 -45.999687) (xy 7.919212 -45.989748) (xy 7.900976 -45.947082) (xy 7.872429 -45.858791)
			(xy 7.853234 -45.768007) (xy 7.843598 -45.675718) (xy 7.843012 -45.629322) (xy 7.843516 -45.586974)
			(xy 7.851567 -45.50266) (xy 7.867596 -45.419494) (xy 7.891457 -45.338227) (xy 7.922936 -45.259597)
			(xy 7.961747 -45.184316) (xy 8.007537 -45.113064) (xy 8.059893 -45.046488) (xy 8.118341 -44.98519)
			(xy 8.182351 -44.929725) (xy 8.251343 -44.880596) (xy 8.324693 -44.838247) (xy 8.401736 -44.803063)
			(xy 8.481775 -44.775361) (xy 8.564084 -44.755393) (xy 8.647919 -44.74334) (xy 8.73252 -44.73931)
			(xy 8.817121 -44.74334) (xy 8.900956 -44.755393) (xy 8.983265 -44.775361) (xy 9.063304 -44.803063)
			(xy 9.140347 -44.838247) (xy 9.213697 -44.880596) (xy 9.282689 -44.929725) (xy 9.346699 -44.98519)
			(xy 9.405147 -45.046488) (xy 9.457503 -45.113064) (xy 9.503293 -45.184316) (xy 9.542104 -45.259597)
			(xy 9.573583 -45.338227) (xy 9.597444 -45.419494) (xy 9.613473 -45.50266) (xy 9.621524 -45.586974)
			(xy 9.622028 -45.629322) (xy 9.621416 -45.675717) (xy 9.611779 -45.768004) (xy 9.592592 -45.858788)
			(xy 9.564062 -45.947082) (xy 9.545828 -45.989748) (xy 9.541998 -45.999684) (xy 9.542006 -46.020956)
			(xy 9.545828 -46.030896) (xy 9.564081 -46.073555) (xy 9.592623 -46.161848) (xy 9.611813 -46.252635)
			(xy 9.621444 -46.344926) (xy 9.622028 -46.391322) (xy 9.621525 -46.434214) (xy 9.613256 -46.519598)
			(xy 9.596807 -46.603789) (xy 9.57233 -46.686007) (xy 9.540053 -46.765486) (xy 9.500276 -46.84149)
			(xy 9.453367 -46.913312) (xy 9.399763 -46.980285) (xy 9.339961 -47.041787) (xy 9.274517 -47.097248)
			(xy 9.204038 -47.146151) (xy 9.16686 -47.167546) (xy 9.154414 -47.174658) (xy 9.140444 -47.198788)
			(xy 9.143492 -47.317152) (xy 9.158224 -47.340774) (xy 9.171178 -47.347124) (xy 9.207714 -47.365908)
			(xy 9.27754 -47.409202) (xy 9.343075 -47.45875) (xy 9.403763 -47.51413) (xy 9.459086 -47.57487) (xy 9.508572 -47.640452)
			(xy 9.551801 -47.710318) (xy 9.588403 -47.783872) (xy 9.618066 -47.860488) (xy 9.640539 -47.939513)
			(xy 9.655629 -48.020273) (xy 9.663209 -48.102081) (xy 9.663684 -48.14316) (xy 9.663089 -48.189555)
			(xy 9.653448 -48.281843) (xy 9.634255 -48.372627) (xy 9.60572 -48.460921) (xy 9.587484 -48.503586)
			(xy 9.583688 -48.513533) (xy 9.583672 -48.534795) (xy 9.587484 -48.544734) (xy 9.605714 -48.587402)
			(xy 9.634262 -48.675692) (xy 9.65346 -48.766475) (xy 9.663097 -48.858764) (xy 9.663684 -48.90516)
			(xy 9.663171 -48.947331) (xy 9.655174 -49.031292) (xy 9.639267 -49.11412) (xy 9.615592 -49.195071)
			(xy 9.584362 -49.273417) (xy 9.545857 -49.348457) (xy 9.500424 -49.419515) (xy 9.448469 -49.485955)
			(xy 9.39046 -49.547179) (xy 9.326917 -49.602639) (xy 9.25841 -49.651836) (xy 9.222232 -49.67351)
			(xy 9.210548 -49.680368) (xy 9.19734 -49.703228) (xy 9.19607 -49.817782) (xy 9.209024 -49.840896)
			(xy 9.220708 -49.848008) (xy 9.255817 -49.869949) (xy 9.322216 -49.919412) (xy 9.383731 -49.974831)
			(xy 9.439829 -50.035727) (xy 9.490027 -50.101572) (xy 9.533888 -50.171797) (xy 9.571033 -50.245794)
			(xy 9.601142 -50.322923) (xy 9.623953 -50.402516) (xy 9.639269 -50.483884) (xy 9.646957 -50.566323)
			(xy 9.647428 -50.607722) (xy 9.646816 -50.654117) (xy 9.637179 -50.746404) (xy 9.617992 -50.837188)
			(xy 9.589462 -50.925482) (xy 9.571228 -50.968148) (xy 9.567398 -50.978084) (xy 9.567406 -50.999356)
			(xy 9.571228 -51.009296) (xy 9.589481 -51.051955) (xy 9.618023 -51.140248) (xy 9.637213 -51.231035)
			(xy 9.646844 -51.323326) (xy 9.647428 -51.369722) (xy 9.646924 -51.41207) (xy 9.638873 -51.496384)
			(xy 9.622844 -51.57955) (xy 9.598983 -51.660817) (xy 9.567504 -51.739447) (xy 9.528693 -51.814728)
			(xy 9.482903 -51.88598) (xy 9.464029 -51.90998) (xy 21.349208 -51.90998) (xy 21.349208 -39.90975)
			(xy 21.349707 -39.814772) (xy 21.357731 -39.624987) (xy 21.373754 -39.435708) (xy 21.397749 -39.247275)
			(xy 21.429673 -39.060021) (xy 21.469469 -38.874282) (xy 21.517066 -38.690386) (xy 21.57238 -38.508663)
			(xy 21.635311 -38.329435) (xy 21.705749 -38.153022) (xy 21.783566 -37.979738) (xy 21.868626 -37.809891)
			(xy 21.960775 -37.643784) (xy 22.059851 -37.481713) (xy 22.165677 -37.323967) (xy 22.278064 -37.170826)
			(xy 22.396812 -37.022563) (xy 22.52171 -36.879442) (xy 22.652535 -36.741719) (xy 22.789054 -36.609637)
			(xy 22.931024 -36.483433) (xy 23.078193 -36.363332) (xy 23.230298 -36.249546) (xy 23.387068 -36.14228)
			(xy 23.548224 -36.041723) (xy 23.71348 -35.948055) (xy 23.88254 -35.861443) (xy 24.055104 -35.782041)
			(xy 24.230864 -35.70999) (xy 24.409508 -35.645419) (xy 24.590717 -35.588443) (xy 24.774168 -35.539163)
			(xy 24.959536 -35.497667) (xy 25.146489 -35.464028) (xy 25.334695 -35.438308) (xy 25.42921 -35.428936)
			(xy 25.443434 -35.427412) (xy 25.466294 -35.410394) (xy 25.510236 -35.299396) (xy 25.50541 -35.271202)
			(xy 25.495758 -35.26028) (xy 25.469411 -35.229827) (xy 25.42172 -35.164934) (xy 25.380091 -35.095995)
			(xy 25.344866 -35.023574) (xy 25.316334 -34.948266) (xy 25.294727 -34.870685) (xy 25.280224 -34.791469)
			(xy 25.272942 -34.711266) (xy 25.272492 -34.671) (xy 25.272996 -34.628652) (xy 25.281047 -34.544338)
			(xy 25.297076 -34.461172) (xy 25.320937 -34.379905) (xy 25.352416 -34.301275) (xy 25.391227 -34.225994)
			(xy 25.437017 -34.154742) (xy 25.489373 -34.088166) (xy 25.547821 -34.026868) (xy 25.611831 -33.971403)
			(xy 25.680823 -33.922274) (xy 25.754173 -33.879925) (xy 25.831216 -33.844741) (xy 25.911255 -33.817039)
			(xy 25.993564 -33.797071) (xy 26.077399 -33.785018) (xy 26.162 -33.780988) (xy 26.246601 -33.785018)
			(xy 26.330436 -33.797071) (xy 26.412745 -33.817039) (xy 26.492784 -33.844741) (xy 26.569827 -33.879925)
			(xy 26.643177 -33.922274) (xy 26.712169 -33.971403) (xy 26.776179 -34.026868) (xy 26.834627 -34.088166)
			(xy 26.886983 -34.154742) (xy 26.932773 -34.225994) (xy 26.971584 -34.301275) (xy 27.003063 -34.379905)
			(xy 27.026924 -34.461172) (xy 27.042953 -34.544338) (xy 27.051004 -34.628652) (xy 27.051508 -34.671)
			(xy 27.051029 -34.712675) (xy 27.043237 -34.795661) (xy 27.027713 -34.877552) (xy 27.004593 -34.957632)
			(xy 26.974079 -35.035196) (xy 26.93644 -35.109564) (xy 26.892007 -35.180083) (xy 26.841168 -35.246133)
			(xy 26.78437 -35.307136) (xy 26.753566 -35.33521) (xy 26.742898 -35.344862) (xy 26.734516 -35.372294)
			(xy 26.764996 -35.48761) (xy 26.78557 -35.507422) (xy 26.799794 -35.51047) (xy 26.893045 -35.531126)
			(xy 27.077882 -35.579335) (xy 27.260508 -35.635342) (xy 27.440593 -35.699048) (xy 27.617812 -35.770337)
			(xy 27.791848 -35.84908) (xy 27.962386 -35.935137) (xy 28.129119 -36.028351) (xy 28.291747 -36.128556)
			(xy 28.449977 -36.235571) (xy 28.603524 -36.349202) (xy 28.752112 -36.469246) (xy 28.895473 -36.595486)
			(xy 29.033349 -36.727694) (xy 29.165491 -36.865634) (xy 29.291662 -37.009056) (xy 29.411634 -37.157701)
			(xy 29.525192 -37.311303) (xy 29.63213 -37.469585) (xy 29.732256 -37.632261) (xy 29.825391 -37.799039)
			(xy 29.868135 -37.883846) (xy 36.848796 -37.883846) (xy 36.849226 -37.845558) (xy 36.855849 -37.769268)
			(xy 36.868998 -37.693828) (xy 36.888575 -37.619796) (xy 36.90112 -37.583618) (xy 36.903738 -37.575174)
			(xy 36.903753 -37.557512) (xy 36.90112 -37.549074) (xy 36.888548 -37.512904) (xy 36.868956 -37.438873)
			(xy 36.855809 -37.36343) (xy 36.849204 -37.287136) (xy 36.848796 -37.248846) (xy 36.849296 -37.207743)
			(xy 36.856877 -37.125889) (xy 36.871978 -37.045083) (xy 36.894472 -36.966015) (xy 36.924165 -36.88936)
			(xy 36.960804 -36.815772) (xy 37.004077 -36.745878) (xy 37.053615 -36.680276) (xy 37.108994 -36.619524)
			(xy 37.169743 -36.564142) (xy 37.235344 -36.514601) (xy 37.305235 -36.471324) (xy 37.378821 -36.434682)
			(xy 37.455475 -36.404985) (xy 37.534542 -36.382488) (xy 37.615347 -36.367383) (xy 37.697201 -36.359798)
			(xy 37.738304 -36.359338) (xy 37.7847 -36.359916) (xy 37.876988 -36.369562) (xy 37.967772 -36.388759)
			(xy 38.056065 -36.417299) (xy 38.09873 -36.435538) (xy 38.10867 -36.439358) (xy 38.129938 -36.439358)
			(xy 38.139878 -36.435538) (xy 38.182541 -36.417295) (xy 38.270833 -36.38875) (xy 38.361618 -36.369556)
			(xy 38.453908 -36.359923) (xy 38.500304 -36.359338) (xy 38.5467 -36.359916) (xy 38.638988 -36.369562)
			(xy 38.729772 -36.388759) (xy 38.818065 -36.417299) (xy 38.86073 -36.435538) (xy 38.87067 -36.439358)
			(xy 38.891938 -36.439358) (xy 38.901878 -36.435538) (xy 38.944541 -36.417295) (xy 39.032833 -36.38875)
			(xy 39.123618 -36.369556) (xy 39.215908 -36.359923) (xy 39.262304 -36.359338) (xy 39.303409 -36.359748)
			(xy 39.385267 -36.367334) (xy 39.466076 -36.382441) (xy 39.545147 -36.40494) (xy 39.621804 -36.434638)
			(xy 39.695394 -36.471283) (xy 39.765289 -36.514562) (xy 39.830892 -36.564106) (xy 39.891644 -36.619492)
			(xy 39.947026 -36.680247) (xy 39.996566 -36.745852) (xy 40.039841 -36.81575) (xy 40.076482 -36.889342)
			(xy 40.106176 -36.966001) (xy 40.12867 -37.045072) (xy 40.143773 -37.125883) (xy 40.151354 -37.207741)
			(xy 40.151812 -37.248846) (xy 40.151379 -37.287134) (xy 40.144757 -37.363424) (xy 40.131609 -37.438864)
			(xy 40.112032 -37.512896) (xy 40.099488 -37.549074) (xy 40.096824 -37.557506) (xy 40.096839 -37.57518)
			(xy 40.099488 -37.583618) (xy 40.112058 -37.619788) (xy 40.13165 -37.693819) (xy 40.144798 -37.769262)
			(xy 40.151403 -37.845556) (xy 40.151812 -37.883846) (xy 40.151377 -37.924949) (xy 40.143788 -38.006804)
			(xy 40.128679 -38.08761) (xy 40.106179 -38.166677) (xy 40.07648 -38.243331) (xy 40.039835 -38.316918)
			(xy 39.996556 -38.38681) (xy 39.947014 -38.452411) (xy 39.891631 -38.51316) (xy 39.830878 -38.568541)
			(xy 39.765275 -38.61808) (xy 39.695381 -38.661355) (xy 39.621793 -38.697997) (xy 39.545138 -38.727692)
			(xy 39.466069 -38.750189) (xy 39.385263 -38.765294) (xy 39.303407 -38.772879) (xy 39.262304 -38.773354)
			(xy 39.215908 -38.772774) (xy 39.12362 -38.763129) (xy 39.032836 -38.743932) (xy 38.944543 -38.715393)
			(xy 38.901878 -38.697154) (xy 38.891938 -38.693334) (xy 38.87067 -38.693334) (xy 38.86073 -38.697154)
			(xy 38.818066 -38.715394) (xy 38.729774 -38.74394) (xy 38.63899 -38.763135) (xy 38.5467 -38.772769)
			(xy 38.500304 -38.773354) (xy 38.453908 -38.772774) (xy 38.36162 -38.763129) (xy 38.270836 -38.743932)
			(xy 38.182543 -38.715393) (xy 38.139878 -38.697154) (xy 38.129938 -38.693334) (xy 38.10867 -38.693334)
			(xy 38.09873 -38.697154) (xy 38.056066 -38.715394) (xy 37.967774 -38.74394) (xy 37.87699 -38.763135)
			(xy 37.7847 -38.772769) (xy 37.738304 -38.773354) (xy 37.697203 -38.77283) (xy 37.615351 -38.765246)
			(xy 37.534549 -38.750142) (xy 37.455484 -38.727647) (xy 37.378833 -38.697953) (xy 37.305248 -38.661314)
			(xy 37.235357 -38.618042) (xy 37.169757 -38.568505) (xy 37.109008 -38.513128) (xy 37.053626 -38.452381)
			(xy 37.004087 -38.386784) (xy 36.96081 -38.316896) (xy 36.924167 -38.243313) (xy 36.894469 -38.166663)
			(xy 36.87197 -38.0876) (xy 36.856861 -38.006798) (xy 36.849273 -37.924947) (xy 36.848796 -37.883846)
			(xy 29.868135 -37.883846) (xy 29.911365 -37.969619) (xy 29.990025 -38.143692) (xy 30.061228 -38.320946)
			(xy 30.124847 -38.501061) (xy 30.180766 -38.683714) (xy 30.228886 -38.868574) (xy 30.269119 -39.05531)
			(xy 30.301393 -39.243584) (xy 30.32565 -39.433058) (xy 30.341846 -39.623391) (xy 30.349953 -39.81424)
			(xy 30.35046 -39.90975) (xy 30.35046 -44.308522) (xy 37.125148 -44.308522) (xy 37.125734 -44.262126)
			(xy 37.135377 -44.169838) (xy 37.154572 -44.079054) (xy 37.18311 -43.990761) (xy 37.201348 -43.948096)
			(xy 37.205154 -43.938152) (xy 37.205162 -43.916888) (xy 37.201348 -43.906948) (xy 37.183114 -43.864281)
			(xy 37.154566 -43.775991) (xy 37.13537 -43.685207) (xy 37.125734 -43.592918) (xy 37.125148 -43.546522)
			(xy 37.125734 -43.500126) (xy 37.135377 -43.407838) (xy 37.154572 -43.317054) (xy 37.18311 -43.228761)
			(xy 37.201348 -43.186096) (xy 37.205154 -43.176152) (xy 37.205162 -43.154888) (xy 37.201348 -43.144948)
			(xy 37.183114 -43.102281) (xy 37.154566 -43.013991) (xy 37.13537 -42.923207) (xy 37.125734 -42.830918)
			(xy 37.125148 -42.784522) (xy 37.125734 -42.738126) (xy 37.135377 -42.645838) (xy 37.154572 -42.555054)
			(xy 37.18311 -42.466761) (xy 37.201348 -42.424096) (xy 37.205154 -42.414152) (xy 37.205162 -42.392888)
			(xy 37.201348 -42.382948) (xy 37.183114 -42.340281) (xy 37.154566 -42.251991) (xy 37.13537 -42.161207)
			(xy 37.125734 -42.068918) (xy 37.125148 -42.022522) (xy 37.125652 -41.980174) (xy 37.133703 -41.89586)
			(xy 37.149732 -41.812694) (xy 37.173593 -41.731427) (xy 37.205072 -41.652797) (xy 37.243883 -41.577516)
			(xy 37.289673 -41.506264) (xy 37.342029 -41.439688) (xy 37.400477 -41.37839) (xy 37.464487 -41.322925)
			(xy 37.533479 -41.273796) (xy 37.606829 -41.231447) (xy 37.683872 -41.196263) (xy 37.763911 -41.168561)
			(xy 37.84622 -41.148593) (xy 37.930055 -41.13654) (xy 38.014656 -41.13251) (xy 38.099257 -41.13654)
			(xy 38.183092 -41.148593) (xy 38.265401 -41.168561) (xy 38.34544 -41.196263) (xy 38.422483 -41.231447)
			(xy 38.495833 -41.273796) (xy 38.564825 -41.322925) (xy 38.628835 -41.37839) (xy 38.687283 -41.439688)
			(xy 38.739639 -41.506264) (xy 38.785429 -41.577516) (xy 38.82424 -41.652797) (xy 38.855719 -41.731427)
			(xy 38.87958 -41.812694) (xy 38.895609 -41.89586) (xy 38.90366 -41.980174) (xy 38.904164 -42.022522)
			(xy 38.903557 -42.068917) (xy 38.89392 -42.161205) (xy 38.874731 -42.251989) (xy 38.846199 -42.340283)
			(xy 38.827964 -42.382948) (xy 38.824132 -42.392884) (xy 38.82414 -42.414156) (xy 38.827964 -42.424096)
			(xy 38.846213 -42.466756) (xy 38.874757 -42.555049) (xy 38.893949 -42.645835) (xy 38.90358 -42.738126)
			(xy 38.904164 -42.784522) (xy 38.903557 -42.830917) (xy 38.89392 -42.923205) (xy 38.874731 -43.013989)
			(xy 38.846199 -43.102283) (xy 38.827964 -43.144948) (xy 38.824132 -43.154884) (xy 38.82414 -43.176156)
			(xy 38.827964 -43.186096) (xy 38.846213 -43.228756) (xy 38.874757 -43.317049) (xy 38.893949 -43.407835)
			(xy 38.90358 -43.500126) (xy 38.904164 -43.546522) (xy 38.903557 -43.592917) (xy 38.89392 -43.685205)
			(xy 38.874731 -43.775989) (xy 38.846199 -43.864283) (xy 38.827964 -43.906948) (xy 38.824132 -43.916884)
			(xy 38.82414 -43.938156) (xy 38.827964 -43.948096) (xy 38.846213 -43.990756) (xy 38.874757 -44.079049)
			(xy 38.89105 -44.156122) (xy 47.285148 -44.156122) (xy 47.285734 -44.109726) (xy 47.295377 -44.017438)
			(xy 47.314572 -43.926654) (xy 47.34311 -43.838361) (xy 47.361348 -43.795696) (xy 47.365154 -43.785752)
			(xy 47.365162 -43.764488) (xy 47.361348 -43.754548) (xy 47.343114 -43.711881) (xy 47.314566 -43.623591)
			(xy 47.29537 -43.532807) (xy 47.285734 -43.440518) (xy 47.285148 -43.394122) (xy 47.285734 -43.347726)
			(xy 47.295377 -43.255438) (xy 47.314572 -43.164654) (xy 47.34311 -43.076361) (xy 47.361348 -43.033696)
			(xy 47.365154 -43.023752) (xy 47.365162 -43.002488) (xy 47.361348 -42.992548) (xy 47.343114 -42.949881)
			(xy 47.314566 -42.861591) (xy 47.29537 -42.770807) (xy 47.285734 -42.678518) (xy 47.285148 -42.632122)
			(xy 47.285734 -42.585726) (xy 47.295377 -42.493438) (xy 47.314572 -42.402654) (xy 47.34311 -42.314361)
			(xy 47.361348 -42.271696) (xy 47.365154 -42.261752) (xy 47.365162 -42.240488) (xy 47.361348 -42.230548)
			(xy 47.343114 -42.187881) (xy 47.314566 -42.099591) (xy 47.29537 -42.008807) (xy 47.285734 -41.916518)
			(xy 47.285148 -41.870122) (xy 47.285688 -41.829021) (xy 47.29327 -41.74717) (xy 47.308372 -41.666368)
			(xy 47.330866 -41.587303) (xy 47.360558 -41.510652) (xy 47.397196 -41.437066) (xy 47.440467 -41.367176)
			(xy 47.490003 -41.301576) (xy 47.545379 -41.240826) (xy 47.606125 -41.185445) (xy 47.671721 -41.135905)
			(xy 47.741609 -41.092628) (xy 47.815191 -41.055985) (xy 47.891841 -41.026287) (xy 47.970903 -41.003787)
			(xy 48.051705 -40.988679) (xy 48.133555 -40.981091) (xy 48.174656 -40.980614) (xy 48.212944 -40.981043)
			(xy 48.289235 -40.987666) (xy 48.364674 -41.000815) (xy 48.438707 -41.020393) (xy 48.474884 -41.032938)
			(xy 48.483322 -41.03558) (xy 48.50099 -41.03558) (xy 48.509428 -41.032938) (xy 48.545598 -41.020367)
			(xy 48.619629 -41.000774) (xy 48.695072 -40.987627) (xy 48.771366 -40.981022) (xy 48.809656 -40.980614)
			(xy 48.850759 -40.981094) (xy 48.932615 -40.988675) (xy 49.013422 -41.003778) (xy 49.092491 -41.026271)
			(xy 49.169147 -41.055965) (xy 49.242736 -41.092606) (xy 49.31263 -41.13588) (xy 49.378232 -41.185419)
			(xy 49.438984 -41.2408) (xy 49.494367 -41.301551) (xy 49.543908 -41.367152) (xy 49.587184 -41.437045)
			(xy 49.623826 -41.510633) (xy 49.653522 -41.587288) (xy 49.676017 -41.666357) (xy 49.691121 -41.747163)
			(xy 49.698705 -41.829019) (xy 49.699164 -41.870122) (xy 49.698557 -41.916517) (xy 49.68892 -42.008805)
			(xy 49.669731 -42.099589) (xy 49.641199 -42.187883) (xy 49.622964 -42.230548) (xy 49.619132 -42.240484)
			(xy 49.61914 -42.261756) (xy 49.622964 -42.271696) (xy 49.641213 -42.314356) (xy 49.669757 -42.402649)
			(xy 49.688949 -42.493435) (xy 49.69858 -42.585726) (xy 49.699164 -42.632122) (xy 49.698557 -42.678517)
			(xy 49.68892 -42.770805) (xy 49.669731 -42.861589) (xy 49.641199 -42.949883) (xy 49.622964 -42.992548)
			(xy 49.619132 -43.002484) (xy 49.61914 -43.023756) (xy 49.622964 -43.033696) (xy 49.641213 -43.076356)
			(xy 49.669757 -43.164649) (xy 49.688949 -43.255435) (xy 49.69858 -43.347726) (xy 49.699164 -43.394122)
			(xy 49.698557 -43.440517) (xy 49.68892 -43.532805) (xy 49.669731 -43.623589) (xy 49.641199 -43.711883)
			(xy 49.622964 -43.754548) (xy 49.619132 -43.764484) (xy 49.61914 -43.785756) (xy 49.622964 -43.795696)
			(xy 49.641213 -43.838356) (xy 49.669757 -43.926649) (xy 49.688949 -44.017435) (xy 49.69858 -44.109726)
			(xy 49.699164 -44.156122) (xy 49.698769 -44.197227) (xy 49.691181 -44.279086) (xy 49.676073 -44.359895)
			(xy 49.653573 -44.438966) (xy 49.623873 -44.515623) (xy 49.587227 -44.589213) (xy 49.543947 -44.659108)
			(xy 49.494402 -44.724711) (xy 49.439015 -44.785462) (xy 49.37826 -44.840844) (xy 49.312653 -44.890384)
			(xy 49.242755 -44.933659) (xy 49.169163 -44.9703) (xy 49.092503 -44.999994) (xy 49.013431 -45.022488)
			(xy 48.93262 -45.03759) (xy 48.850761 -45.045172) (xy 48.809656 -45.04563) (xy 48.771368 -45.045195)
			(xy 48.695078 -45.038574) (xy 48.619638 -45.025426) (xy 48.545606 -45.00585) (xy 48.509428 -44.993306)
			(xy 48.50099 -44.990664) (xy 48.483322 -44.990664) (xy 48.474884 -44.993306) (xy 48.438714 -45.005876)
			(xy 48.364683 -45.025468) (xy 48.28924 -45.038616) (xy 48.212946 -45.045221) (xy 48.174656 -45.04563)
			(xy 48.133553 -45.045175) (xy 48.051699 -45.037587) (xy 47.970894 -45.022478) (xy 47.891828 -44.999979)
			(xy 47.815175 -44.970281) (xy 47.741589 -44.933636) (xy 47.671698 -44.890359) (xy 47.606098 -44.840818)
			(xy 47.545348 -44.785436) (xy 47.489967 -44.724685) (xy 47.440428 -44.659084) (xy 47.397153 -44.589192)
			(xy 47.360511 -44.515605) (xy 47.330814 -44.438951) (xy 47.308317 -44.359884) (xy 47.29321 -44.279079)
			(xy 47.285624 -44.197225) (xy 47.285148 -44.156122) (xy 38.89105 -44.156122) (xy 38.893949 -44.169835)
			(xy 38.90358 -44.262126) (xy 38.904164 -44.308522) (xy 38.90366 -44.35087) (xy 38.895609 -44.435184)
			(xy 38.87958 -44.51835) (xy 38.855719 -44.599617) (xy 38.82424 -44.678247) (xy 38.785429 -44.753528)
			(xy 38.739639 -44.82478) (xy 38.687283 -44.891356) (xy 38.628835 -44.952654) (xy 38.564825 -45.008119)
			(xy 38.495833 -45.057248) (xy 38.422483 -45.099597) (xy 38.34544 -45.134781) (xy 38.265401 -45.162483)
			(xy 38.183092 -45.182451) (xy 38.099257 -45.194504) (xy 38.014656 -45.198535) (xy 37.930055 -45.194504)
			(xy 37.84622 -45.182451) (xy 37.763911 -45.162483) (xy 37.683872 -45.134781) (xy 37.606829 -45.099597)
			(xy 37.533479 -45.057248) (xy 37.464487 -45.008119) (xy 37.400477 -44.952654) (xy 37.342029 -44.891356)
			(xy 37.289673 -44.82478) (xy 37.243883 -44.753528) (xy 37.205072 -44.678247) (xy 37.173593 -44.599617)
			(xy 37.149732 -44.51835) (xy 37.133703 -44.435184) (xy 37.125652 -44.35087) (xy 37.125148 -44.308522)
			(xy 30.35046 -44.308522) (xy 30.35046 -51.90998) (xy 30.349966 -52.004244) (xy 30.342072 -52.192608)
			(xy 30.326296 -52.380475) (xy 30.302667 -52.567517) (xy 30.271226 -52.753406) (xy 30.232029 -52.937815)
			(xy 30.230307 -52.944522) (xy 40.985948 -52.944522) (xy 40.986534 -52.898126) (xy 40.996177 -52.805838)
			(xy 41.015372 -52.715054) (xy 41.04391 -52.626761) (xy 41.062148 -52.584096) (xy 41.065954 -52.574152)
			(xy 41.065962 -52.552888) (xy 41.062148 -52.542948) (xy 41.043914 -52.500281) (xy 41.015366 -52.411991)
			(xy 40.99617 -52.321207) (xy 40.986534 -52.228918) (xy 40.985948 -52.182522) (xy 40.986435 -52.139315)
			(xy 40.994822 -52.053307) (xy 41.01151 -51.968519) (xy 41.03634 -51.885748) (xy 41.06908 -51.805775)
			(xy 41.10942 -51.729354) (xy 41.156981 -51.657205) (xy 41.211314 -51.590007) (xy 41.271906 -51.528395)
			(xy 41.304718 -51.500278) (xy 41.313608 -51.492912) (xy 41.322752 -51.473354) (xy 41.32453 -51.37404)
			(xy 41.315894 -51.353974) (xy 41.307512 -51.346608) (xy 41.276898 -51.318519) (xy 41.22043 -51.257566)
			(xy 41.169894 -51.191613) (xy 41.125729 -51.121234) (xy 41.08832 -51.047042) (xy 41.057993 -50.969685)
			(xy 41.035014 -50.889837) (xy 41.019581 -50.808193) (xy 41.01183 -50.725467) (xy 41.011348 -50.683922)
			(xy 41.011934 -50.637526) (xy 41.021577 -50.545238) (xy 41.040772 -50.454454) (xy 41.06931 -50.366161)
			(xy 41.087548 -50.323496) (xy 41.091354 -50.313552) (xy 41.091362 -50.292288) (xy 41.087548 -50.282348)
			(xy 41.069314 -50.239681) (xy 41.040766 -50.151391) (xy 41.02157 -50.060607) (xy 41.011934 -49.968318)
			(xy 41.011348 -49.921922) (xy 41.011899 -49.878262) (xy 41.020444 -49.791361) (xy 41.037465 -49.705715)
			(xy 41.062796 -49.62215) (xy 41.096195 -49.54147) (xy 41.137339 -49.464451) (xy 41.185834 -49.391834)
			(xy 41.241211 -49.32432) (xy 41.302937 -49.262557) (xy 41.37042 -49.207141) (xy 41.443008 -49.158605)
			(xy 41.520003 -49.117415) (xy 41.600664 -49.08397) (xy 41.642284 -49.070768) (xy 41.658032 -49.065942)
			(xy 41.677844 -49.040034) (xy 41.681146 -48.910748) (xy 41.662858 -48.883824) (xy 41.647364 -48.878236)
			(xy 41.608244 -48.863487) (xy 41.532712 -48.82763) (xy 41.460877 -48.784845) (xy 41.393374 -48.735509)
			(xy 41.330797 -48.680057) (xy 41.2737 -48.618979) (xy 41.222584 -48.552812) (xy 41.177902 -48.482142)
			(xy 41.140048 -48.407591) (xy 41.109356 -48.329818) (xy 41.086096 -48.249507) (xy 41.070474 -48.167369)
			(xy 41.062627 -48.084127) (xy 41.062148 -48.042322) (xy 41.062734 -47.995926) (xy 41.072377 -47.903638)
			(xy 41.091572 -47.812854) (xy 41.12011 -47.724561) (xy 41.138348 -47.681896) (xy 41.142154 -47.671952)
			(xy 41.142162 -47.650688) (xy 41.138348 -47.640748) (xy 41.120114 -47.598081) (xy 41.091566 -47.509791)
			(xy 41.07237 -47.419007) (xy 41.062734 -47.326718) (xy 41.062148 -47.280322) (xy 41.062652 -47.237974)
			(xy 41.070703 -47.15366) (xy 41.086732 -47.070494) (xy 41.110593 -46.989227) (xy 41.142072 -46.910597)
			(xy 41.180883 -46.835316) (xy 41.226673 -46.764064) (xy 41.279029 -46.697488) (xy 41.337477 -46.63619)
			(xy 41.401487 -46.580725) (xy 41.470479 -46.531596) (xy 41.543829 -46.489247) (xy 41.620872 -46.454063)
			(xy 41.700911 -46.426361) (xy 41.78322 -46.406393) (xy 41.867055 -46.39434) (xy 41.951656 -46.39031)
			(xy 42.036257 -46.39434) (xy 42.120092 -46.406393) (xy 42.202401 -46.426361) (xy 42.28244 -46.454063)
			(xy 42.359483 -46.489247) (xy 42.432833 -46.531596) (xy 42.501825 -46.580725) (xy 42.565835 -46.63619)
			(xy 42.624283 -46.697488) (xy 42.676639 -46.764064) (xy 42.722429 -46.835316) (xy 42.76124 -46.910597)
			(xy 42.792719 -46.989227) (xy 42.81658 -47.070494) (xy 42.832609 -47.15366) (xy 42.84066 -47.237974)
			(xy 42.841164 -47.280322) (xy 42.840557 -47.326717) (xy 42.83092 -47.419005) (xy 42.811731 -47.509789)
			(xy 42.783199 -47.598083) (xy 42.764964 -47.640748) (xy 42.761132 -47.650684) (xy 42.76114 -47.671956)
			(xy 42.764964 -47.681896) (xy 42.783213 -47.724556) (xy 42.811757 -47.812849) (xy 42.830949 -47.903635)
			(xy 42.84058 -47.995926) (xy 42.840844 -48.016922) (xy 46.599348 -48.016922) (xy 46.599934 -47.970526)
			(xy 46.609577 -47.878238) (xy 46.628772 -47.787454) (xy 46.65731 -47.699161) (xy 46.675548 -47.656496)
			(xy 46.679354 -47.646552) (xy 46.679362 -47.625288) (xy 46.675548 -47.615348) (xy 46.657314 -47.572681)
			(xy 46.628766 -47.484391) (xy 46.60957 -47.393607) (xy 46.599934 -47.301318) (xy 46.599348 -47.254922)
			(xy 46.599852 -47.212574) (xy 46.607903 -47.12826) (xy 46.623932 -47.045094) (xy 46.647793 -46.963827)
			(xy 46.679272 -46.885197) (xy 46.718083 -46.809916) (xy 46.763873 -46.738664) (xy 46.816229 -46.672088)
			(xy 46.874677 -46.61079) (xy 46.938687 -46.555325) (xy 47.007679 -46.506196) (xy 47.081029 -46.463847)
			(xy 47.158072 -46.428663) (xy 47.238111 -46.400961) (xy 47.32042 -46.380993) (xy 47.404255 -46.36894)
			(xy 47.488856 -46.36491) (xy 47.573457 -46.36894) (xy 47.657292 -46.380993) (xy 47.739601 -46.400961)
			(xy 47.81964 -46.428663) (xy 47.896683 -46.463847) (xy 47.970033 -46.506196) (xy 48.039025 -46.555325)
			(xy 48.103035 -46.61079) (xy 48.161483 -46.672088) (xy 48.213839 -46.738664) (xy 48.259629 -46.809916)
			(xy 48.29844 -46.885197) (xy 48.329919 -46.963827) (xy 48.35378 -47.045094) (xy 48.369809 -47.12826)
			(xy 48.37786 -47.212574) (xy 48.378364 -47.254922) (xy 48.377757 -47.301317) (xy 48.36812 -47.393605)
			(xy 48.348931 -47.484389) (xy 48.320399 -47.572683) (xy 48.302164 -47.615348) (xy 48.298332 -47.625284)
			(xy 48.29834 -47.646556) (xy 48.302164 -47.656496) (xy 48.320413 -47.699156) (xy 48.348957 -47.787449)
			(xy 48.368149 -47.878235) (xy 48.37778 -47.970526) (xy 48.378364 -48.016922) (xy 48.37786 -48.05927)
			(xy 48.369809 -48.143584) (xy 48.35378 -48.22675) (xy 48.329919 -48.308017) (xy 48.29844 -48.386647)
			(xy 48.259629 -48.461928) (xy 48.213839 -48.53318) (xy 48.161483 -48.599756) (xy 48.103035 -48.661054)
			(xy 48.039025 -48.716519) (xy 47.970033 -48.765648) (xy 47.896683 -48.807997) (xy 47.81964 -48.843181)
			(xy 47.739601 -48.870883) (xy 47.657292 -48.890851) (xy 47.573457 -48.902904) (xy 47.488856 -48.906935)
			(xy 47.404255 -48.902904) (xy 47.32042 -48.890851) (xy 47.238111 -48.870883) (xy 47.158072 -48.843181)
			(xy 47.081029 -48.807997) (xy 47.007679 -48.765648) (xy 46.938687 -48.716519) (xy 46.874677 -48.661054)
			(xy 46.816229 -48.599756) (xy 46.763873 -48.53318) (xy 46.718083 -48.461928) (xy 46.679272 -48.386647)
			(xy 46.647793 -48.308017) (xy 46.623932 -48.22675) (xy 46.607903 -48.143584) (xy 46.599852 -48.05927)
			(xy 46.599348 -48.016922) (xy 42.840844 -48.016922) (xy 42.841164 -48.042322) (xy 42.840645 -48.085983)
			(xy 42.832095 -48.172885) (xy 42.815071 -48.25853) (xy 42.789736 -48.342096) (xy 42.756334 -48.422776)
			(xy 42.715186 -48.499795) (xy 42.66669 -48.572411) (xy 42.61131 -48.639925) (xy 42.549581 -48.701687)
			(xy 42.482097 -48.757103) (xy 42.409507 -48.805639) (xy 42.332511 -48.846828) (xy 42.251848 -48.880274)
			(xy 42.210228 -48.893476) (xy 42.19448 -48.898302) (xy 42.174668 -48.92421) (xy 42.171366 -49.053496)
			(xy 42.189654 -49.08042) (xy 42.205148 -49.086008) (xy 42.244252 -49.100798) (xy 42.319782 -49.136653)
			(xy 42.391615 -49.179435) (xy 42.459117 -49.228768) (xy 42.521693 -49.284217) (xy 42.578791 -49.345292)
			(xy 42.629907 -49.411455) (xy 42.67459 -49.482121) (xy 42.712447 -49.556668) (xy 42.743142 -49.634438)
			(xy 42.766405 -49.714744) (xy 42.782031 -49.796879) (xy 42.789883 -49.880118) (xy 42.790364 -49.921922)
			(xy 42.789757 -49.968317) (xy 42.78012 -50.060605) (xy 42.760931 -50.151389) (xy 42.732399 -50.239683)
			(xy 42.714164 -50.282348) (xy 42.710332 -50.292284) (xy 42.71034 -50.313556) (xy 42.714164 -50.323496)
			(xy 42.732413 -50.366156) (xy 42.760957 -50.454449) (xy 42.780149 -50.545235) (xy 42.78978 -50.637526)
			(xy 42.790364 -50.683922) (xy 42.789832 -50.727128) (xy 42.781451 -50.813134) (xy 42.764769 -50.897921)
			(xy 42.739944 -50.980691) (xy 42.70721 -51.060664) (xy 42.666875 -51.137086) (xy 42.619319 -51.209236)
			(xy 42.564991 -51.276435) (xy 42.504404 -51.338049) (xy 42.471594 -51.366166) (xy 42.462704 -51.373532)
			(xy 42.45356 -51.39309) (xy 42.451782 -51.492404) (xy 42.460418 -51.51247) (xy 42.4688 -51.519836)
			(xy 42.499438 -51.547899) (xy 42.555904 -51.608856) (xy 42.606439 -51.674813) (xy 42.650602 -51.745196)
			(xy 42.688008 -51.819391) (xy 42.718331 -51.896751) (xy 42.741308 -51.976602) (xy 42.756737 -52.058248)
			(xy 42.764484 -52.140977) (xy 42.764964 -52.182522) (xy 42.764357 -52.228917) (xy 42.75472 -52.321205)
			(xy 42.735531 -52.411989) (xy 42.706999 -52.500283) (xy 42.688764 -52.542948) (xy 42.684932 -52.552884)
			(xy 42.68494 -52.574156) (xy 42.688764 -52.584096) (xy 42.707013 -52.626756) (xy 42.735557 -52.715049)
			(xy 42.754749 -52.805835) (xy 42.76438 -52.898126) (xy 42.764964 -52.944522) (xy 42.764408 -52.989616)
			(xy 42.75528 -53.07934) (xy 42.737121 -53.167679) (xy 42.710115 -53.253728) (xy 42.674541 -53.336603)
			(xy 42.630764 -53.415453) (xy 42.605452 -53.452776) (xy 42.596562 -53.465476) (xy 42.5958 -53.495194)
			(xy 42.659808 -53.600604) (xy 42.686478 -53.613558) (xy 42.701718 -53.61178) (xy 42.729978 -53.608353)
			(xy 42.78679 -53.604666) (xy 42.815256 -53.604414) (xy 42.856359 -53.604894) (xy 42.938215 -53.612475)
			(xy 43.019022 -53.627578) (xy 43.098091 -53.650071) (xy 43.174747 -53.679765) (xy 43.248336 -53.716406)
			(xy 43.31823 -53.75968) (xy 43.383832 -53.809219) (xy 43.444584 -53.8646) (xy 43.499967 -53.925351)
			(xy 43.549508 -53.990952) (xy 43.592784 -54.060845) (xy 43.629426 -54.134433) (xy 43.659122 -54.211088)
			(xy 43.681617 -54.290157) (xy 43.696721 -54.370963) (xy 43.704305 -54.452819) (xy 43.704764 -54.493922)
			(xy 43.704157 -54.540317) (xy 43.69452 -54.632605) (xy 43.675331 -54.723389) (xy 43.646799 -54.811683)
			(xy 43.628564 -54.854348) (xy 43.624732 -54.864284) (xy 43.62474 -54.885556) (xy 43.628564 -54.895496)
			(xy 43.646813 -54.938156) (xy 43.675357 -55.026449) (xy 43.694549 -55.117235) (xy 43.700672 -55.175912)
			(xy 45.74032 -55.175912) (xy 45.740905 -55.129516) (xy 45.750549 -55.037228) (xy 45.769744 -54.946444)
			(xy 45.798282 -54.858151) (xy 45.81652 -54.815486) (xy 45.820333 -54.805544) (xy 45.820337 -54.784278)
			(xy 45.81652 -54.774338) (xy 45.798281 -54.731673) (xy 45.769735 -54.643382) (xy 45.75054 -54.552598)
			(xy 45.740906 -54.460308) (xy 45.74032 -54.413912) (xy 45.740787 -54.372924) (xy 45.748311 -54.291294)
			(xy 45.763316 -54.210703) (xy 45.785673 -54.131835) (xy 45.815193 -54.055359) (xy 45.851626 -53.981924)
			(xy 45.894663 -53.912153) (xy 45.943937 -53.846639) (xy 45.999031 -53.785937) (xy 46.059477 -53.730563)
			(xy 46.124763 -53.680987) (xy 46.194334 -53.637629) (xy 46.2676 -53.600857) (xy 46.343939 -53.570984)
			(xy 46.422703 -53.548263) (xy 46.503224 -53.532886) (xy 46.543976 -53.528468) (xy 46.556422 -53.527452)
			(xy 46.576996 -53.514244) (xy 46.63059 -53.42128) (xy 46.63186 -53.396896) (xy 46.62678 -53.38572)
			(xy 46.608055 -53.342583) (xy 46.578751 -53.253221) (xy 46.559041 -53.161266) (xy 46.549146 -53.067744)
			(xy 46.548548 -53.020722) (xy 46.549134 -52.974326) (xy 46.558777 -52.882038) (xy 46.577972 -52.791254)
			(xy 46.60651 -52.702961) (xy 46.624748 -52.660296) (xy 46.628554 -52.650352) (xy 46.628562 -52.629088)
			(xy 46.624748 -52.619148) (xy 46.606514 -52.576481) (xy 46.577966 -52.488191) (xy 46.55877 -52.397407)
			(xy 46.549134 -52.305118) (xy 46.548548 -52.258722) (xy 46.54903 -52.216411) (xy 46.557056 -52.13217)
			(xy 46.573048 -52.049072) (xy 46.596861 -51.967869) (xy 46.62828 -51.889295) (xy 46.66702 -51.814061)
			(xy 46.712731 -51.742847) (xy 46.765 -51.676297) (xy 46.823355 -51.615013) (xy 46.887266 -51.559548)
			(xy 46.92142 -51.534568) (xy 46.931072 -51.52771) (xy 46.942248 -51.506882) (xy 46.94555 -51.402234)
			(xy 46.935898 -51.380644) (xy 46.9265 -51.373278) (xy 46.892876 -51.345171) (xy 46.830763 -51.283341)
			(xy 46.775028 -51.215705) (xy 46.726212 -51.142918) (xy 46.684787 -51.065684) (xy 46.651154 -50.984753)
			(xy 46.62564 -50.900907) (xy 46.608491 -50.81496) (xy 46.599874 -50.727743) (xy 46.599348 -50.683922)
			(xy 46.599934 -50.637526) (xy 46.609577 -50.545238) (xy 46.628772 -50.454454) (xy 46.65731 -50.366161)
			(xy 46.675548 -50.323496) (xy 46.679354 -50.313552) (xy 46.679362 -50.292288) (xy 46.675548 -50.282348)
			(xy 46.657314 -50.239681) (xy 46.628766 -50.151391) (xy 46.60957 -50.060607) (xy 46.599934 -49.968318)
			(xy 46.599348 -49.921922) (xy 46.599852 -49.879574) (xy 46.607903 -49.79526) (xy 46.623932 -49.712094)
			(xy 46.647793 -49.630827) (xy 46.679272 -49.552197) (xy 46.718083 -49.476916) (xy 46.763873 -49.405664)
			(xy 46.816229 -49.339088) (xy 46.874677 -49.27779) (xy 46.938687 -49.222325) (xy 47.007679 -49.173196)
			(xy 47.081029 -49.130847) (xy 47.158072 -49.095663) (xy 47.238111 -49.067961) (xy 47.32042 -49.047993)
			(xy 47.404255 -49.03594) (xy 47.488856 -49.03191) (xy 47.573457 -49.03594) (xy 47.657292 -49.047993)
			(xy 47.739601 -49.067961) (xy 47.81964 -49.095663) (xy 47.896683 -49.130847) (xy 47.970033 -49.173196)
			(xy 48.039025 -49.222325) (xy 48.103035 -49.27779) (xy 48.161483 -49.339088) (xy 48.213839 -49.405664)
			(xy 48.259629 -49.476916) (xy 48.29844 -49.552197) (xy 48.329919 -49.630827) (xy 48.35378 -49.712094)
			(xy 48.369809 -49.79526) (xy 48.37786 -49.879574) (xy 48.378364 -49.921922) (xy 48.377757 -49.968317)
			(xy 48.36812 -50.060605) (xy 48.348931 -50.151389) (xy 48.320399 -50.239683) (xy 48.302164 -50.282348)
			(xy 48.298332 -50.292284) (xy 48.29834 -50.313556) (xy 48.302164 -50.323496) (xy 48.320413 -50.366156)
			(xy 48.348957 -50.454449) (xy 48.368149 -50.545235) (xy 48.37778 -50.637526) (xy 48.378364 -50.683922)
			(xy 48.377835 -50.726232) (xy 48.369813 -50.810471) (xy 48.353827 -50.893568) (xy 48.330019 -50.97477)
			(xy 48.298606 -51.053343) (xy 48.259871 -51.128578) (xy 48.214164 -51.199792) (xy 48.1619 -51.266343)
			(xy 48.103551 -51.327629) (xy 48.039644 -51.383095) (xy 48.005492 -51.408076) (xy 47.99584 -51.414934)
			(xy 47.984664 -51.435762) (xy 47.981362 -51.54041) (xy 47.991014 -51.562) (xy 48.000412 -51.569366)
			(xy 48.034011 -51.597501) (xy 48.096125 -51.659328) (xy 48.151861 -51.72696) (xy 48.200679 -51.799744)
			(xy 48.242107 -51.876974) (xy 48.275742 -51.957901) (xy 48.30126 -52.041744) (xy 48.318413 -52.127688)
			(xy 48.327035 -52.214902) (xy 48.327564 -52.258722) (xy 48.326957 -52.305117) (xy 48.31732 -52.397405)
			(xy 48.298131 -52.488189) (xy 48.269599 -52.576483) (xy 48.251364 -52.619148) (xy 48.247532 -52.629084)
			(xy 48.24754 -52.650356) (xy 48.251364 -52.660296) (xy 48.269613 -52.702956) (xy 48.298157 -52.791249)
			(xy 48.317349 -52.882035) (xy 48.32698 -52.974326) (xy 48.327564 -53.020722) (xy 48.327054 -53.061708)
			(xy 48.319527 -53.143335) (xy 48.304521 -53.223922) (xy 48.282164 -53.302787) (xy 48.252644 -53.37926)
			(xy 48.216213 -53.452692) (xy 48.173179 -53.52246) (xy 48.123908 -53.587973) (xy 48.068818 -53.648673)
			(xy 48.008376 -53.704047) (xy 47.943094 -53.753624) (xy 47.873528 -53.796984) (xy 47.800267 -53.833758)
			(xy 47.723934 -53.863636) (xy 47.645174 -53.886362) (xy 47.564658 -53.901745) (xy 47.523908 -53.906166)
			(xy 47.511462 -53.907182) (xy 47.490888 -53.92039) (xy 47.437294 -54.013354) (xy 47.436024 -54.037738)
			(xy 47.441104 -54.048914) (xy 47.459839 -54.092047) (xy 47.489141 -54.18141) (xy 47.508848 -54.273367)
			(xy 47.51874 -54.36689) (xy 47.519336 -54.413912) (xy 47.518755 -54.460308) (xy 47.509109 -54.552596)
			(xy 47.489912 -54.64338) (xy 47.461374 -54.731673) (xy 47.443136 -54.774338) (xy 47.439311 -54.784276)
			(xy 47.439316 -54.805546) (xy 47.443136 -54.815486) (xy 47.461386 -54.858146) (xy 47.489929 -54.946439)
			(xy 47.50912 -55.037225) (xy 47.518752 -55.129516) (xy 47.519336 -55.175912) (xy 47.518832 -55.21826)
			(xy 47.510781 -55.302574) (xy 47.494752 -55.38574) (xy 47.470891 -55.467007) (xy 47.439412 -55.545637)
			(xy 47.400601 -55.620918) (xy 47.354811 -55.69217) (xy 47.302455 -55.758746) (xy 47.244007 -55.820044)
			(xy 47.179997 -55.875509) (xy 47.111005 -55.924638) (xy 47.037655 -55.966987) (xy 46.960612 -56.002171)
			(xy 46.880573 -56.029873) (xy 46.798264 -56.049841) (xy 46.714429 -56.061894) (xy 46.629828 -56.065925)
			(xy 46.545227 -56.061894) (xy 46.461392 -56.049841) (xy 46.379083 -56.029873) (xy 46.299044 -56.002171)
			(xy 46.222001 -55.966987) (xy 46.148651 -55.924638) (xy 46.079659 -55.875509) (xy 46.015649 -55.820044)
			(xy 45.957201 -55.758746) (xy 45.904845 -55.69217) (xy 45.859055 -55.620918) (xy 45.820244 -55.545637)
			(xy 45.788765 -55.467007) (xy 45.764904 -55.38574) (xy 45.748875 -55.302574) (xy 45.740824 -55.21826)
			(xy 45.74032 -55.175912) (xy 43.700672 -55.175912) (xy 43.70418 -55.209526) (xy 43.704764 -55.255922)
			(xy 43.70426 -55.29827) (xy 43.696209 -55.382584) (xy 43.68018 -55.46575) (xy 43.656319 -55.547017)
			(xy 43.62484 -55.625647) (xy 43.586029 -55.700928) (xy 43.540239 -55.77218) (xy 43.487883 -55.838756)
			(xy 43.429435 -55.900054) (xy 43.365425 -55.955519) (xy 43.296433 -56.004648) (xy 43.223083 -56.046997)
			(xy 43.14604 -56.082181) (xy 43.066001 -56.109883) (xy 42.983692 -56.129851) (xy 42.899857 -56.141904)
			(xy 42.815256 -56.145935) (xy 42.730655 -56.141904) (xy 42.64682 -56.129851) (xy 42.564511 -56.109883)
			(xy 42.484472 -56.082181) (xy 42.407429 -56.046997) (xy 42.334079 -56.004648) (xy 42.265087 -55.955519)
			(xy 42.201077 -55.900054) (xy 42.142629 -55.838756) (xy 42.090273 -55.77218) (xy 42.044483 -55.700928)
			(xy 42.005672 -55.625647) (xy 41.974193 -55.547017) (xy 41.950332 -55.46575) (xy 41.934303 -55.382584)
			(xy 41.926252 -55.29827) (xy 41.925748 -55.255922) (xy 41.926334 -55.209526) (xy 41.935977 -55.117238)
			(xy 41.955172 -55.026454) (xy 41.98371 -54.938161) (xy 42.001948 -54.895496) (xy 42.005754 -54.885552)
			(xy 42.005762 -54.864288) (xy 42.001948 -54.854348) (xy 41.983714 -54.811681) (xy 41.955166 -54.723391)
			(xy 41.93597 -54.632607) (xy 41.926334 -54.540318) (xy 41.925748 -54.493922) (xy 41.926324 -54.448829)
			(xy 41.935448 -54.359106) (xy 41.953604 -54.270766) (xy 41.980605 -54.184717) (xy 42.016176 -54.101842)
			(xy 42.059949 -54.022992) (xy 42.08526 -53.985668) (xy 42.09415 -53.972968) (xy 42.094912 -53.94325)
			(xy 42.030904 -53.83784) (xy 42.004234 -53.824886) (xy 41.988994 -53.826664) (xy 41.960734 -53.83009)
			(xy 41.903922 -53.833777) (xy 41.875456 -53.83403) (xy 41.834353 -53.833575) (xy 41.752499 -53.825987)
			(xy 41.671694 -53.810878) (xy 41.592628 -53.788379) (xy 41.515975 -53.758681) (xy 41.442389 -53.722036)
			(xy 41.372498 -53.678759) (xy 41.306898 -53.629218) (xy 41.246148 -53.573836) (xy 41.190767 -53.513085)
			(xy 41.141228 -53.447484) (xy 41.097953 -53.377592) (xy 41.061311 -53.304005) (xy 41.031614 -53.227351)
			(xy 41.009117 -53.148284) (xy 40.99401 -53.067479) (xy 40.986424 -52.985625) (xy 40.985948 -52.944522)
			(xy 30.230307 -52.944522) (xy 30.185144 -53.12042) (xy 30.130653 -53.300902) (xy 30.068652 -53.478944)
			(xy 29.99925 -53.654234) (xy 29.922569 -53.826463) (xy 29.838742 -53.995331) (xy 29.747918 -54.16054)
			(xy 29.650255 -54.3218) (xy 29.545925 -54.47883) (xy 29.43511 -54.631353) (xy 29.318006 -54.779102)
			(xy 29.194818 -54.921817) (xy 29.065761 -55.059248) (xy 28.931062 -55.191155) (xy 28.790958 -55.317305)
			(xy 28.645694 -55.437478) (xy 28.495526 -55.551462) (xy 28.340715 -55.659058) (xy 28.181535 -55.760077)
			(xy 28.018265 -55.854341) (xy 27.85119 -55.941686) (xy 27.680604 -56.021957) (xy 27.506807 -56.095015)
			(xy 27.330102 -56.160731) (xy 27.150801 -56.218989) (xy 26.969217 -56.269689) (xy 26.785669 -56.312739)
			(xy 26.60048 -56.348066) (xy 26.413974 -56.375607) (xy 26.226478 -56.395313) (xy 26.038321 -56.407151)
			(xy 25.849834 -56.4111) (xy 25.661347 -56.407151) (xy 25.47319 -56.395313) (xy 25.285694 -56.375607)
			(xy 25.099188 -56.348066) (xy 24.913999 -56.312739) (xy 24.730451 -56.269689) (xy 24.548867 -56.218989)
			(xy 24.369566 -56.160731) (xy 24.192861 -56.095015) (xy 24.019064 -56.021957) (xy 23.848478 -55.941686)
			(xy 23.681403 -55.854341) (xy 23.518133 -55.760077) (xy 23.358953 -55.659058) (xy 23.204142 -55.551462)
			(xy 23.053974 -55.437478) (xy 22.90871 -55.317305) (xy 22.768606 -55.191155) (xy 22.633907 -55.059248)
			(xy 22.50485 -54.921817) (xy 22.381662 -54.779102) (xy 22.264558 -54.631353) (xy 22.153743 -54.47883)
			(xy 22.049413 -54.3218) (xy 21.95175 -54.16054) (xy 21.860926 -53.995331) (xy 21.777099 -53.826463)
			(xy 21.700418 -53.654234) (xy 21.631016 -53.478944) (xy 21.569015 -53.300902) (xy 21.514524 -53.12042)
			(xy 21.467639 -52.937815) (xy 21.428442 -52.753406) (xy 21.397001 -52.567517) (xy 21.373372 -52.380475)
			(xy 21.357596 -52.192608) (xy 21.349702 -52.004244) (xy 21.349208 -51.90998) (xy 9.464029 -51.90998)
			(xy 9.430547 -51.952556) (xy 9.372099 -52.013854) (xy 9.308089 -52.069319) (xy 9.239097 -52.118448)
			(xy 9.165747 -52.160797) (xy 9.088704 -52.195981) (xy 9.008665 -52.223683) (xy 8.926356 -52.243651)
			(xy 8.842521 -52.255704) (xy 8.75792 -52.259735) (xy 8.673319 -52.255704) (xy 8.589484 -52.243651)
			(xy 8.507175 -52.223683) (xy 8.427136 -52.195981) (xy 8.350093 -52.160797) (xy 8.276743 -52.118448)
			(xy 8.207751 -52.069319) (xy 8.143741 -52.013854) (xy 8.085293 -51.952556) (xy 8.032937 -51.88598)
			(xy 7.987147 -51.814728) (xy 7.948336 -51.739447) (xy 7.916857 -51.660817) (xy 7.892996 -51.57955)
			(xy 7.876967 -51.496384) (xy 7.868916 -51.41207) (xy 7.868412 -51.369722) (xy 7.869001 -51.323327)
			(xy 7.878644 -51.231038) (xy 7.897838 -51.140255) (xy 7.926375 -51.051961) (xy 7.944612 -51.009296)
			(xy 7.948419 -50.999352) (xy 7.948428 -50.978087) (xy 7.944612 -50.968148) (xy 7.926376 -50.925482)
			(xy 7.897829 -50.837191) (xy 7.878634 -50.746407) (xy 7.868998 -50.654118) (xy 7.868412 -50.607722)
			(xy 7.868912 -50.565551) (xy 7.876911 -50.481589) (xy 7.89282 -50.398761) (xy 7.916496 -50.31781)
			(xy 7.947728 -50.239464) (xy 7.986233 -50.164424) (xy 8.031668 -50.093366) (xy 8.083624 -50.026926)
			(xy 8.141634 -49.965702) (xy 8.205178 -49.910243) (xy 8.273685 -49.861046) (xy 8.309864 -49.839372)
			(xy 8.321548 -49.832514) (xy 8.334756 -49.809654) (xy 8.336026 -49.6951) (xy 8.323072 -49.671986)
			(xy 8.311388 -49.664874) (xy 8.27629 -49.642915) (xy 8.209891 -49.593454) (xy 8.148376 -49.538037)
			(xy 8.092277 -49.477143) (xy 8.042079 -49.4113) (xy 7.998217 -49.341077) (xy 7.96107 -49.267081)
			(xy 7.93096 -49.189954) (xy 7.908148 -49.110363) (xy 7.89283 -49.028996) (xy 7.88514 -48.946558)
			(xy 7.884668 -48.90516) (xy 7.885274 -48.858765) (xy 7.894913 -48.766477) (xy 7.914102 -48.675694)
			(xy 7.942634 -48.587399) (xy 7.960868 -48.544734) (xy 7.964709 -48.534801) (xy 7.964694 -48.513527)
			(xy 7.960868 -48.503586) (xy 7.942609 -48.46093) (xy 7.914069 -48.372635) (xy 7.89488 -48.281848)
			(xy 7.885251 -48.189557) (xy 7.884668 -48.14316) (xy 7.88524 -48.10027) (xy 7.893501 -48.014888)
			(xy 7.909943 -47.930699) (xy 7.934412 -47.848482) (xy 7.966682 -47.769003) (xy 8.006452 -47.693)
			(xy 8.053354 -47.621177) (xy 8.106952 -47.554203) (xy 8.166748 -47.492699) (xy 8.232187 -47.437237)
			(xy 8.30266 -47.388332) (xy 8.339836 -47.366936) (xy 8.352282 -47.359824) (xy 8.366252 -47.335694)
			(xy 8.363204 -47.21733) (xy 8.348472 -47.193708) (xy 8.335518 -47.187358) (xy 8.298973 -47.16859)
			(xy 8.229148 -47.125295) (xy 8.163612 -47.075745) (xy 8.102925 -47.020364) (xy 8.047602 -46.959622)
			(xy 7.998116 -46.894038) (xy 7.954889 -46.824171) (xy 7.918287 -46.750615) (xy 7.888625 -46.673998)
			(xy 7.866153 -46.594972) (xy 7.851064 -46.51421) (xy 7.843487 -46.432401) (xy 7.843012 -46.391322)
			(xy 4.208092 -46.391322) (xy 4.203273 -46.441784) (xy 4.187244 -46.52495) (xy 4.163383 -46.606217)
			(xy 4.131904 -46.684847) (xy 4.093093 -46.760128) (xy 4.047303 -46.83138) (xy 3.994947 -46.897956)
			(xy 3.936499 -46.959254) (xy 3.872489 -47.014719) (xy 3.803497 -47.063848) (xy 3.730147 -47.106197)
			(xy 3.653104 -47.141381) (xy 3.573065 -47.169083) (xy 3.490756 -47.189051) (xy 3.406921 -47.201104)
			(xy 3.32232 -47.205135) (xy 3.237719 -47.201104) (xy 3.153884 -47.189051) (xy 3.071575 -47.169083)
			(xy 2.991536 -47.141381) (xy 2.914493 -47.106197) (xy 2.841143 -47.063848) (xy 2.772151 -47.014719)
			(xy 2.708141 -46.959254) (xy 2.649693 -46.897956) (xy 2.597337 -46.83138) (xy 2.551547 -46.760128)
			(xy 2.512736 -46.684847) (xy 2.481257 -46.606217) (xy 2.457396 -46.52495) (xy 2.441367 -46.441784)
			(xy 2.433316 -46.35747) (xy 2.432812 -46.315122) (xy 2.433401 -46.268727) (xy 2.443044 -46.176438)
			(xy 2.462238 -46.085655) (xy 2.490775 -45.997361) (xy 2.509012 -45.954696) (xy 2.512819 -45.944752)
			(xy 2.512828 -45.923487) (xy 2.509012 -45.913548) (xy 2.490768 -45.870885) (xy 2.462224 -45.782593)
			(xy 2.443031 -45.691808) (xy 2.433397 -45.599518) (xy 2.432812 -45.553122) (xy 2.43334 -45.509703)
			(xy 2.441823 -45.42328) (xy 2.458681 -45.338094) (xy 2.483753 -45.254954) (xy 2.516803 -45.17465)
			(xy 2.536698 -45.136054) (xy 2.541778 -45.126656) (xy 2.543302 -45.105574) (xy 2.511806 -45.01515)
			(xy 2.497836 -44.999656) (xy 2.48793 -44.995338) (xy 2.448944 -44.977593) (xy 2.374243 -44.935663)
			(xy 2.303921 -44.886744) (xy 2.238628 -44.83129) (xy 2.17897 -44.769815) (xy 2.1255 -44.702888) (xy 2.078714 -44.631129)
			(xy 2.039044 -44.555204) (xy 2.006859 -44.475817) (xy 1.982457 -44.393702) (xy 1.966064 -44.309621)
			(xy 1.957833 -44.224354) (xy 1.957324 -44.181522) (xy 1.651254 -44.181522) (xy 1.651254 -48.380904)
			(xy 1.652778 -48.43145) (xy 1.651254 -48.481996) (xy 1.651254 -48.982122) (xy 2.432812 -48.982122)
			(xy 2.433401 -48.935727) (xy 2.443044 -48.843438) (xy 2.462238 -48.752655) (xy 2.490775 -48.664361)
			(xy 2.509012 -48.621696) (xy 2.512819 -48.611752) (xy 2.512828 -48.590487) (xy 2.509012 -48.580548)
			(xy 2.490768 -48.537885) (xy 2.462224 -48.449593) (xy 2.443031 -48.358808) (xy 2.433397 -48.266518)
			(xy 2.432812 -48.220122) (xy 2.433316 -48.177774) (xy 2.441367 -48.09346) (xy 2.457396 -48.010294)
			(xy 2.481257 -47.929027) (xy 2.512736 -47.850397) (xy 2.551547 -47.775116) (xy 2.597337 -47.703864)
			(xy 2.649693 -47.637288) (xy 2.708141 -47.57599) (xy 2.772151 -47.520525) (xy 2.841143 -47.471396)
			(xy 2.914493 -47.429047) (xy 2.991536 -47.393863) (xy 3.071575 -47.366161) (xy 3.153884 -47.346193)
			(xy 3.237719 -47.33414) (xy 3.32232 -47.33011) (xy 3.406921 -47.33414) (xy 3.490756 -47.346193) (xy 3.573065 -47.366161)
			(xy 3.653104 -47.393863) (xy 3.730147 -47.429047) (xy 3.803497 -47.471396) (xy 3.872489 -47.520525)
			(xy 3.936499 -47.57599) (xy 3.994947 -47.637288) (xy 4.047303 -47.703864) (xy 4.093093 -47.775116)
			(xy 4.131904 -47.850397) (xy 4.163383 -47.929027) (xy 4.187244 -48.010294) (xy 4.203273 -48.09346)
			(xy 4.211324 -48.177774) (xy 4.211828 -48.220122) (xy 4.211216 -48.266517) (xy 4.201579 -48.358804)
			(xy 4.182392 -48.449588) (xy 4.153862 -48.537882) (xy 4.135628 -48.580548) (xy 4.131798 -48.590484)
			(xy 4.131806 -48.611756) (xy 4.135628 -48.621696) (xy 4.153873 -48.664358) (xy 4.182417 -48.752651)
			(xy 4.20161 -48.843436) (xy 4.211243 -48.935726) (xy 4.211828 -48.982122) (xy 4.211326 -49.024153)
			(xy 4.203391 -49.107839) (xy 4.187595 -49.190403) (xy 4.164078 -49.271108) (xy 4.133051 -49.349234)
			(xy 4.094789 -49.424083) (xy 4.049635 -49.494988) (xy 3.997992 -49.561315) (xy 3.969512 -49.59223)
			(xy 3.961892 -49.600358) (xy 3.955034 -49.620424) (xy 3.963416 -49.71796) (xy 3.973576 -49.736756)
			(xy 3.982466 -49.74336) (xy 4.015233 -49.768475) (xy 4.076459 -49.823867) (xy 4.132287 -49.884696)
			(xy 4.182236 -49.950438) (xy 4.225877 -50.020526) (xy 4.262832 -50.094359) (xy 4.292785 -50.171298)
			(xy 4.315477 -50.250683) (xy 4.330713 -50.33183) (xy 4.338361 -50.41404) (xy 4.338828 -50.455322)
			(xy 4.338216 -50.501717) (xy 4.328579 -50.594004) (xy 4.309392 -50.684788) (xy 4.280862 -50.773082)
			(xy 4.262628 -50.815748) (xy 4.258798 -50.825684) (xy 4.258806 -50.846956) (xy 4.262628 -50.856896)
			(xy 4.280873 -50.899558) (xy 4.309417 -50.987851) (xy 4.32861 -51.078636) (xy 4.338243 -51.170926)
			(xy 4.338828 -51.217322) (xy 4.338334 -51.25916) (xy 4.330474 -51.342467) (xy 4.314827 -51.424667)
			(xy 4.29153 -51.505035) (xy 4.260789 -51.58286) (xy 4.222876 -51.657455) (xy 4.200906 -51.693064)
			(xy 4.195572 -51.7017) (xy 4.192016 -51.721512) (xy 4.212082 -51.811428) (xy 4.223766 -51.827938)
			(xy 4.232402 -51.833272) (xy 4.266569 -51.855428) (xy 4.331126 -51.905072) (xy 4.390875 -51.960409)
			(xy 4.445316 -52.020975) (xy 4.493993 -52.086264) (xy 4.536499 -52.155729) (xy 4.572478 -52.228788)
			(xy 4.601628 -52.30483) (xy 4.623706 -52.383218) (xy 4.638527 -52.463296) (xy 4.645967 -52.544393)
			(xy 4.646422 -52.585112) (xy 4.645842 -52.631508) (xy 4.636196 -52.723796) (xy 4.616999 -52.81458)
			(xy 4.58846 -52.902873) (xy 4.570222 -52.945538) (xy 4.566309 -52.955458) (xy 4.566314 -52.976764)
			(xy 4.570222 -52.986686) (xy 4.588472 -53.029346) (xy 4.617014 -53.117639) (xy 4.636206 -53.208425)
			(xy 4.645838 -53.300716) (xy 4.646422 -53.347112) (xy 4.645918 -53.38946) (xy 4.64026 -53.448712)
			(xy 6.525006 -53.448712) (xy 6.525592 -53.402316) (xy 6.535236 -53.310028) (xy 6.554431 -53.219244)
			(xy 6.582968 -53.130951) (xy 6.601206 -53.088286) (xy 6.605103 -53.078362) (xy 6.605108 -53.05706)
			(xy 6.601206 -53.047138) (xy 6.582966 -53.004474) (xy 6.554421 -52.916182) (xy 6.535226 -52.825398)
			(xy 6.525592 -52.733108) (xy 6.525006 -52.686712) (xy 6.52551 -52.644364) (xy 6.533561 -52.56005)
			(xy 6.54959 -52.476884) (xy 6.573451 -52.395617) (xy 6.60493 -52.316987) (xy 6.643741 -52.241706)
			(xy 6.689531 -52.170454) (xy 6.741887 -52.103878) (xy 6.800335 -52.04258) (xy 6.864345 -51.987115)
			(xy 6.933337 -51.937986) (xy 7.006687 -51.895637) (xy 7.08373 -51.860453) (xy 7.163769 -51.832751)
			(xy 7.246078 -51.812783) (xy 7.329913 -51.80073) (xy 7.414514 -51.7967) (xy 7.499115 -51.80073) (xy 7.58295 -51.812783)
			(xy 7.665259 -51.832751) (xy 7.745298 -51.860453) (xy 7.822341 -51.895637) (xy 7.895691 -51.937986)
			(xy 7.964683 -51.987115) (xy 8.028693 -52.04258) (xy 8.087141 -52.103878) (xy 8.139497 -52.170454)
			(xy 8.185287 -52.241706) (xy 8.224098 -52.316987) (xy 8.255577 -52.395617) (xy 8.279438 -52.476884)
			(xy 8.295467 -52.56005) (xy 8.303518 -52.644364) (xy 8.304022 -52.686712) (xy 8.303442 -52.733108)
			(xy 8.293796 -52.825396) (xy 8.274599 -52.91618) (xy 8.24606 -53.004473) (xy 8.227822 -53.047138)
			(xy 8.223909 -53.057058) (xy 8.223914 -53.078364) (xy 8.227822 -53.088286) (xy 8.246072 -53.130946)
			(xy 8.274614 -53.219239) (xy 8.293806 -53.310025) (xy 8.303438 -53.402316) (xy 8.304022 -53.448712)
			(xy 8.303518 -53.49106) (xy 8.295467 -53.575374) (xy 8.279438 -53.65854) (xy 8.255577 -53.739807)
			(xy 8.224098 -53.818437) (xy 8.185287 -53.893718) (xy 8.139497 -53.96497) (xy 8.087141 -54.031546)
			(xy 8.028693 -54.092844) (xy 7.964683 -54.148309) (xy 7.895691 -54.197438) (xy 7.822341 -54.239787)
			(xy 7.745298 -54.274971) (xy 7.665259 -54.302673) (xy 7.58295 -54.322641) (xy 7.499115 -54.334694)
			(xy 7.414514 -54.338725) (xy 7.329913 -54.334694) (xy 7.246078 -54.322641) (xy 7.163769 -54.302673)
			(xy 7.08373 -54.274971) (xy 7.006687 -54.239787) (xy 6.933337 -54.197438) (xy 6.864345 -54.148309)
			(xy 6.800335 -54.092844) (xy 6.741887 -54.031546) (xy 6.689531 -53.96497) (xy 6.643741 -53.893718)
			(xy 6.60493 -53.818437) (xy 6.573451 -53.739807) (xy 6.54959 -53.65854) (xy 6.533561 -53.575374)
			(xy 6.52551 -53.49106) (xy 6.525006 -53.448712) (xy 4.64026 -53.448712) (xy 4.637867 -53.473774)
			(xy 4.621838 -53.55694) (xy 4.597977 -53.638207) (xy 4.566498 -53.716837) (xy 4.527687 -53.792118)
			(xy 4.481897 -53.86337) (xy 4.429541 -53.929946) (xy 4.371093 -53.991244) (xy 4.307083 -54.046709)
			(xy 4.238091 -54.095838) (xy 4.164741 -54.138187) (xy 4.087698 -54.173371) (xy 4.007659 -54.201073)
			(xy 3.92535 -54.221041) (xy 3.841515 -54.233094) (xy 3.756914 -54.237125) (xy 3.672313 -54.233094)
			(xy 3.588478 -54.221041) (xy 3.506169 -54.201073) (xy 3.42613 -54.173371) (xy 3.349087 -54.138187)
			(xy 3.275737 -54.095838) (xy 3.206745 -54.046709) (xy 3.142735 -53.991244) (xy 3.084287 -53.929946)
			(xy 3.031931 -53.86337) (xy 2.986141 -53.792118) (xy 2.94733 -53.716837) (xy 2.915851 -53.638207)
			(xy 2.89199 -53.55694) (xy 2.875961 -53.473774) (xy 2.86791 -53.38946) (xy 2.867406 -53.347112) (xy 2.867992 -53.300716)
			(xy 2.877636 -53.208428) (xy 2.896831 -53.117644) (xy 2.925368 -53.029351) (xy 2.943606 -52.986686)
			(xy 2.947503 -52.976762) (xy 2.947508 -52.95546) (xy 2.943606 -52.945538) (xy 2.925366 -52.902874)
			(xy 2.896821 -52.814582) (xy 2.877626 -52.723798) (xy 2.867992 -52.631508) (xy 2.867406 -52.585112)
			(xy 2.867886 -52.543273) (xy 2.875747 -52.459966) (xy 2.891397 -52.377765) (xy 2.914696 -52.297397)
			(xy 2.94544 -52.219572) (xy 2.983356 -52.144978) (xy 3.005328 -52.10937) (xy 3.010662 -52.100734)
			(xy 3.014218 -52.080922) (xy 2.994152 -51.991006) (xy 2.982468 -51.974496) (xy 2.973832 -51.969162)
			(xy 2.939663 -51.947009) (xy 2.875107 -51.897365) (xy 2.815357 -51.842028) (xy 2.760916 -51.781461)
			(xy 2.712239 -51.716172) (xy 2.669733 -51.646707) (xy 2.633755 -51.573647) (xy 2.604604 -51.497605)
			(xy 2.582527 -51.419217) (xy 2.567706 -51.339139) (xy 2.560267 -51.258041) (xy 2.559812 -51.217322)
			(xy 2.560401 -51.170927) (xy 2.570044 -51.078638) (xy 2.589238 -50.987855) (xy 2.617775 -50.899561)
			(xy 2.636012 -50.856896) (xy 2.639819 -50.846952) (xy 2.639828 -50.825687) (xy 2.636012 -50.815748)
			(xy 2.617768 -50.773085) (xy 2.589224 -50.684793) (xy 2.570031 -50.594008) (xy 2.560397 -50.501718)
			(xy 2.559812 -50.455322) (xy 2.560302 -50.413291) (xy 2.568238 -50.329604) (xy 2.584035 -50.247039)
			(xy 2.607553 -50.166334) (xy 2.638582 -50.088208) (xy 2.676846 -50.013359) (xy 2.722001 -49.942455)
			(xy 2.773647 -49.876128) (xy 2.802128 -49.845214) (xy 2.809748 -49.837086) (xy 2.816606 -49.81702)
			(xy 2.808224 -49.719484) (xy 2.798064 -49.700688) (xy 2.789174 -49.694084) (xy 2.756404 -49.668973)
			(xy 2.695178 -49.61358) (xy 2.63935 -49.552751) (xy 2.589401 -49.487009) (xy 2.545761 -49.41692)
			(xy 2.508806 -49.343087) (xy 2.478853 -49.266147) (xy 2.456162 -49.186761) (xy 2.440926 -49.105614)
			(xy 2.433279 -49.023404) (xy 2.432812 -48.982122) (xy 1.651254 -48.982122) (xy 1.651254 -53.460904)
			(xy 1.652778 -53.51145) (xy 1.651254 -53.561996) (xy 1.651254 -58.540904) (xy 1.652778 -58.59145)
			(xy 1.651254 -58.641996) (xy 1.651254 -58.913776) (xy 2.81559 -58.913776) (xy 2.816029 -58.875488)
			(xy 2.822649 -58.799198) (xy 2.835796 -58.723758) (xy 2.855371 -58.649726) (xy 2.867914 -58.613548)
			(xy 2.870567 -58.605113) (xy 2.870559 -58.587442) (xy 2.867914 -58.579004) (xy 2.855351 -58.542832)
			(xy 2.835756 -58.468802) (xy 2.822607 -58.39336) (xy 2.816 -58.317066) (xy 2.81559 -58.278776) (xy 2.816044 -58.237673)
			(xy 2.823631 -58.155818) (xy 2.838738 -58.075013) (xy 2.861236 -57.995946) (xy 2.890934 -57.919292)
			(xy 2.927578 -57.845705) (xy 2.970854 -57.775813) (xy 3.020395 -57.710212) (xy 3.075778 -57.649462)
			(xy 3.136529 -57.594081) (xy 3.202131 -57.544542) (xy 3.272024 -57.501267) (xy 3.345612 -57.464625)
			(xy 3.422267 -57.434929) (xy 3.501334 -57.412433) (xy 3.58214 -57.397328) (xy 3.663995 -57.389743)
			(xy 3.705098 -57.389268) (xy 3.74403 -57.389697) (xy 3.821594 -57.396535) (xy 3.898262 -57.410133)
			(xy 3.973446 -57.430385) (xy 4.010152 -57.44337) (xy 4.018701 -57.446134) (xy 4.036655 -57.446134)
			(xy 4.045204 -57.44337) (xy 4.081909 -57.430385) (xy 4.157097 -57.410148) (xy 4.233764 -57.396554)
			(xy 4.311326 -57.389707) (xy 4.350258 -57.389268) (xy 4.38919 -57.389709) (xy 4.466753 -57.396543)
			(xy 4.543421 -57.410138) (xy 4.618606 -57.430387) (xy 4.655312 -57.44337) (xy 4.663861 -57.446134)
			(xy 4.681815 -57.446134) (xy 4.690364 -57.44337) (xy 4.727073 -57.430397) (xy 4.802259 -57.410156)
			(xy 4.878926 -57.396559) (xy 4.956487 -57.389709) (xy 4.995418 -57.389268) (xy 5.03652 -57.389749)
			(xy 5.118374 -57.397333) (xy 5.199179 -57.412438) (xy 5.278246 -57.434934) (xy 5.3549 -57.46463)
			(xy 5.428486 -57.501271) (xy 5.498378 -57.544546) (xy 5.563979 -57.594086) (xy 5.624729 -57.649466)
			(xy 5.680111 -57.710216) (xy 5.72965 -57.775817) (xy 5.772926 -57.845708) (xy 5.809568 -57.919295)
			(xy 5.839264 -57.995948) (xy 5.861761 -58.075015) (xy 5.876866 -58.15582) (xy 5.884451 -58.237674)
			(xy 5.884926 -58.278776) (xy 5.884501 -58.317064) (xy 5.877877 -58.393355) (xy 5.864726 -58.468794)
			(xy 5.845147 -58.542827) (xy 5.832602 -58.579004) (xy 5.829972 -58.587445) (xy 5.829964 -58.60511)
			(xy 5.832602 -58.613548) (xy 5.845169 -58.649719) (xy 5.864763 -58.72375) (xy 5.877911 -58.799192)
			(xy 5.884517 -58.875486) (xy 5.884926 -58.913776) (xy 34.212784 -58.913776) (xy 34.21322 -58.873695)
			(xy 34.220435 -58.79386) (xy 34.234805 -58.714997) (xy 34.256212 -58.637747) (xy 34.269934 -58.600086)
			(xy 34.27267 -58.591745) (xy 34.272943 -58.574209) (xy 34.270442 -58.565796) (xy 34.255367 -58.519464)
			(xy 34.234216 -58.42435) (xy 34.22359 -58.327495) (xy 34.222944 -58.278776) (xy 34.223444 -58.237675)
			(xy 34.23103 -58.155822) (xy 34.246136 -58.075019) (xy 34.268633 -57.995955) (xy 34.298329 -57.919303)
			(xy 34.33497 -57.845718) (xy 34.378244 -57.775828) (xy 34.427782 -57.710228) (xy 34.483162 -57.649479)
			(xy 34.543909 -57.594098) (xy 34.609508 -57.544558) (xy 34.679397 -57.501282) (xy 34.752981 -57.464639)
			(xy 34.829632 -57.434941) (xy 34.908696 -57.412442) (xy 34.989499 -57.397334) (xy 35.071351 -57.389745)
			(xy 35.112452 -57.389268) (xy 35.152022 -57.38968) (xy 35.23085 -57.396689) (xy 35.308744 -57.410674)
			(xy 35.385087 -57.431524) (xy 35.422332 -57.444894) (xy 35.430999 -57.447734) (xy 35.449225 -57.447734)
			(xy 35.457892 -57.444894) (xy 35.495135 -57.43152) (xy 35.57148 -57.410675) (xy 35.649374 -57.396694)
			(xy 35.728202 -57.389687) (xy 35.767772 -57.389268) (xy 35.806704 -57.389705) (xy 35.884267 -57.396541)
			(xy 35.960936 -57.410136) (xy 36.03612 -57.430387) (xy 36.072826 -57.44337) (xy 36.081375 -57.446134)
			(xy 36.099329 -57.446134) (xy 36.107878 -57.44337) (xy 36.144585 -57.430393) (xy 36.219772 -57.410153)
			(xy 36.296439 -57.396557) (xy 36.374001 -57.389708) (xy 36.412932 -57.389268) (xy 36.454034 -57.389736)
			(xy 36.535888 -57.397324) (xy 36.616693 -57.412431) (xy 36.695759 -57.434929) (xy 36.772411 -57.464627)
			(xy 36.845997 -57.50127) (xy 36.915889 -57.544546) (xy 36.981489 -57.594086) (xy 37.042238 -57.649467)
			(xy 37.097619 -57.710217) (xy 37.147159 -57.775818) (xy 37.190434 -57.84571) (xy 37.227077 -57.919296)
			(xy 37.256773 -57.995949) (xy 37.279271 -58.075015) (xy 37.294378 -58.15582) (xy 37.301964 -58.237674)
			(xy 37.30244 -58.278776) (xy 37.302014 -58.317064) (xy 37.29539 -58.393355) (xy 37.28224 -58.468794)
			(xy 37.262661 -58.542827) (xy 37.250116 -58.579004) (xy 37.247485 -58.587445) (xy 37.247478 -58.60511)
			(xy 37.250116 -58.613548) (xy 37.262695 -58.649715) (xy 37.282285 -58.723747) (xy 37.29543 -58.799191)
			(xy 37.302033 -58.875486) (xy 37.30244 -58.913776) (xy 37.301911 -58.954877) (xy 37.294328 -59.036729)
			(xy 37.279226 -59.117532) (xy 37.256732 -59.196597) (xy 37.22704 -59.273249) (xy 37.190401 -59.346835)
			(xy 37.147129 -59.416726) (xy 37.097593 -59.482326) (xy 37.042216 -59.543076) (xy 36.981469 -59.598457)
			(xy 36.915872 -59.647998) (xy 36.845984 -59.691274) (xy 36.7724 -59.727917) (xy 36.69575 -59.757614)
			(xy 36.616687 -59.780113) (xy 36.535885 -59.79522) (xy 36.454033 -59.802808) (xy 36.412932 -59.803284)
			(xy 36.373362 -59.802873) (xy 36.294534 -59.795863) (xy 36.21664 -59.781878) (xy 36.140297 -59.761028)
			(xy 36.103052 -59.747658) (xy 36.094385 -59.744818) (xy 36.076159 -59.744818) (xy 36.067492 -59.747658)
			(xy 36.030251 -59.761039) (xy 35.953906 -59.781882) (xy 35.876011 -59.795861) (xy 35.797182 -59.802865)
			(xy 35.757612 -59.803284) (xy 35.718043 -59.802849) (xy 35.639215 -59.795846) (xy 35.561321 -59.781868)
			(xy 35.484977 -59.761025) (xy 35.447732 -59.747658) (xy 35.439065 -59.744818) (xy 35.420839 -59.744818)
			(xy 35.412172 -59.747658) (xy 35.374923 -59.761016) (xy 35.298581 -59.781865) (xy 35.220688 -59.79585)
			(xy 35.141861 -59.802862) (xy 35.102292 -59.803284) (xy 35.061188 -59.802855) (xy 34.979331 -59.795269)
			(xy 34.898523 -59.780163) (xy 34.819453 -59.757665) (xy 34.742797 -59.727967) (xy 34.669208 -59.691322)
			(xy 34.599314 -59.648044) (xy 34.533711 -59.598502) (xy 34.47296 -59.543118) (xy 34.417578 -59.482364)
			(xy 34.368038 -59.41676) (xy 34.324762 -59.346864) (xy 34.28812 -59.273274) (xy 34.258425 -59.196616)
			(xy 34.23593 -59.117546) (xy 34.220826 -59.036738) (xy 34.213243 -58.95488) (xy 34.212784 -58.913776)
			(xy 5.884926 -58.913776) (xy 5.884425 -58.954878) (xy 5.876842 -59.036732) (xy 5.861739 -59.117537)
			(xy 5.839245 -59.196604) (xy 5.809551 -59.273258) (xy 5.772912 -59.346846) (xy 5.729638 -59.416739)
			(xy 5.6801 -59.48234) (xy 5.624721 -59.543091) (xy 5.563973 -59.598474) (xy 5.498373 -59.648014)
			(xy 5.428483 -59.691291) (xy 5.354897 -59.727934) (xy 5.278244 -59.757632) (xy 5.199178 -59.78013)
			(xy 5.118374 -59.795236) (xy 5.03652 -59.802823) (xy 4.995418 -59.803284) (xy 4.955849 -59.802847)
			(xy 4.877021 -59.795845) (xy 4.799127 -59.781867) (xy 4.722783 -59.761025) (xy 4.685538 -59.747658)
			(xy 4.676871 -59.744818) (xy 4.658645 -59.744818) (xy 4.649978 -59.747658) (xy 4.612728 -59.761014)
			(xy 4.536386 -59.781864) (xy 4.458494 -59.79585) (xy 4.379667 -59.802861) (xy 4.340098 -59.803284)
			(xy 4.30181 -59.80284) (xy 4.22552 -59.796221) (xy 4.15008 -59.783077) (xy 4.076048 -59.763503) (xy 4.03987 -59.75096)
			(xy 4.031432 -59.748318) (xy 4.013764 -59.748318) (xy 4.005326 -59.75096) (xy 3.969151 -59.763516)
			(xy 3.895122 -59.783113) (xy 3.819681 -59.796264) (xy 3.743387 -59.802873) (xy 3.705098 -59.803284)
			(xy 3.663995 -59.80283) (xy 3.582139 -59.795244) (xy 3.501332 -59.780139) (xy 3.422264 -59.757642)
			(xy 3.345608 -59.727945) (xy 3.27202 -59.691302) (xy 3.202127 -59.648026) (xy 3.136524 -59.598485)
			(xy 3.075773 -59.543103) (xy 3.020391 -59.482351) (xy 2.970851 -59.416748) (xy 2.927575 -59.346855)
			(xy 2.890933 -59.273266) (xy 2.861236 -59.196611) (xy 2.83874 -59.117542) (xy 2.823635 -59.036735)
			(xy 2.81605 -58.954879) (xy 2.81559 -58.913776) (xy 1.651254 -58.913776) (xy 1.651254 -60.583826)
			(xy 1.651672 -60.59344) (xy 1.658768 -60.611311) (xy 1.671951 -60.625308) (xy 1.680464 -60.6298)
			(xy 1.777492 -60.675266) (xy 1.806448 -60.671456) (xy 1.817878 -60.661804) (xy 1.852158 -60.633943)
			(xy 1.925295 -60.584391) (xy 2.002983 -60.54233) (xy 2.084455 -60.508174) (xy 2.168912 -60.482261)
			(xy 2.25552 -60.464843) (xy 2.343429 -60.456094) (xy 2.3876 -60.455556) (xy 2.429948 -60.45606) (xy 2.514262 -60.464111)
			(xy 2.597428 -60.48014) (xy 2.678695 -60.504001) (xy 2.757325 -60.53548) (xy 2.832606 -60.574291)
			(xy 2.903858 -60.620081) (xy 2.970434 -60.672437) (xy 3.031732 -60.730885) (xy 3.087197 -60.794895)
			(xy 3.136326 -60.863887) (xy 3.178675 -60.937237) (xy 3.213859 -61.01428) (xy 3.241561 -61.094319)
			(xy 3.261529 -61.176628) (xy 3.273582 -61.260463) (xy 3.277613 -61.345064) (xy 3.273582 -61.429665)
			(xy 3.261529 -61.5135) (xy 3.241561 -61.595809) (xy 3.213859 -61.675848) (xy 3.178675 -61.752891)
			(xy 3.136326 -61.826241) (xy 3.087197 -61.895233) (xy 3.031732 -61.959243) (xy 2.970434 -62.017691)
			(xy 2.903858 -62.070047) (xy 2.832606 -62.115837) (xy 2.757325 -62.154648) (xy 2.678695 -62.186127)
			(xy 2.597428 -62.209988) (xy 2.514262 -62.226017) (xy 2.429948 -62.234068) (xy 2.3876 -62.234572)
			(xy 2.343427 -62.234044) (xy 2.255514 -62.225314) (xy 2.1689 -62.207907) (xy 2.08444 -62.181996)
			(xy 2.002966 -62.147835) (xy 1.925282 -62.105763) (xy 1.852154 -62.056193) (xy 1.817878 -62.028324)
			(xy 1.806448 -62.018672) (xy 1.777492 -62.014862) (xy 1.680464 -62.060328) (xy 1.671941 -62.064794)
			(xy 1.658779 -62.078811) (xy 1.651702 -62.096688) (xy 1.651254 -62.106302) (xy 1.651254 -62.91961)
			(xy 2.866902 -62.91961) (xy 2.870932 -62.835009) (xy 2.882985 -62.751174) (xy 2.902953 -62.668865)
			(xy 2.930655 -62.588826) (xy 2.965839 -62.511783) (xy 3.008188 -62.438433) (xy 3.057317 -62.369441)
			(xy 3.112782 -62.305431) (xy 3.17408 -62.246983) (xy 3.240656 -62.194627) (xy 3.311908 -62.148837)
			(xy 3.387189 -62.110026) (xy 3.465819 -62.078547) (xy 3.547086 -62.054686) (xy 3.630252 -62.038657)
			(xy 3.714566 -62.030606) (xy 3.756914 -62.030102) (xy 3.798801 -62.030589) (xy 3.882204 -62.038457)
			(xy 3.964499 -62.054131) (xy 4.044955 -62.077473) (xy 4.12286 -62.108275) (xy 4.197525 -62.146264)
			(xy 4.233164 -62.168278) (xy 4.242443 -62.173643) (xy 4.26362 -62.176807) (xy 4.274058 -62.174374)
			(xy 4.313587 -62.163648) (xy 4.39411 -62.148627) (xy 4.475672 -62.141072) (xy 4.516628 -62.140592)
			(xy 4.558376 -62.141088) (xy 4.641502 -62.148931) (xy 4.72353 -62.164517) (xy 4.76377 -62.175644)
			(xy 4.772547 -62.177806) (xy 4.790563 -62.176464) (xy 4.807 -62.168969) (xy 4.819827 -62.156248)
			(xy 4.823968 -62.148212) (xy 4.842139 -62.110175) (xy 4.884656 -62.037378) (xy 4.933869 -61.96893)
			(xy 4.989337 -61.905446) (xy 5.050563 -61.847493) (xy 5.116997 -61.795593) (xy 5.188043 -61.750211)
			(xy 5.263063 -61.711754) (xy 5.341386 -61.680567) (xy 5.422308 -61.65693) (xy 5.505103 -61.641055)
			(xy 5.589028 -61.633084) (xy 5.63118 -61.632592) (xy 5.679455 -61.633216) (xy 5.775436 -61.643683)
			(xy 5.86972 -61.664483) (xy 5.91566 -61.679328) (xy 5.92496 -61.681958) (xy 5.944239 -61.680892)
			(xy 5.961778 -61.672815) (xy 5.968746 -61.66612) (xy 5.996693 -61.637322) (xy 6.056944 -61.58431)
			(xy 6.121726 -61.536939) (xy 6.19051 -61.495596) (xy 6.262739 -61.460616) (xy 6.337824 -61.432285)
			(xy 6.415157 -61.410831) (xy 6.494107 -61.396429) (xy 6.574033 -61.389197) (xy 6.61416 -61.388752)
			(xy 6.655541 -61.389217) (xy 6.737944 -61.396909) (xy 6.819276 -61.412223) (xy 6.898834 -61.435025)
			(xy 6.97593 -61.465118) (xy 7.049898 -61.502242) (xy 7.120098 -61.546075) (xy 7.185923 -61.59624)
			(xy 7.246804 -61.652302) (xy 7.302214 -61.713777) (xy 7.351674 -61.780133) (xy 7.37362 -61.815218)
			(xy 7.378663 -61.822848) (xy 7.393028 -61.83415) (xy 7.410447 -61.839687) (xy 7.419594 -61.839602)
			(xy 7.46506 -61.838332) (xy 7.507408 -61.838836) (xy 7.591722 -61.846887) (xy 7.674888 -61.862916)
			(xy 7.756155 -61.886777) (xy 7.834785 -61.918256) (xy 7.910066 -61.957067) (xy 7.981318 -62.002857)
			(xy 8.047894 -62.055213) (xy 8.109192 -62.113661) (xy 8.164657 -62.177671) (xy 8.213786 -62.246663)
			(xy 8.256135 -62.320013) (xy 8.291319 -62.397056) (xy 8.319021 -62.477095) (xy 8.338989 -62.559404)
			(xy 8.351042 -62.643239) (xy 8.355073 -62.72784) (xy 8.351042 -62.812441) (xy 8.338989 -62.896276)
			(xy 8.319021 -62.978585) (xy 8.291319 -63.058624) (xy 8.256135 -63.135667) (xy 8.213786 -63.209017)
			(xy 8.164657 -63.278009) (xy 8.144633 -63.301118) (xy 8.478012 -63.301118) (xy 8.478479 -63.260118)
			(xy 8.48604 -63.178469) (xy 8.50108 -63.09786) (xy 8.523472 -63.018978) (xy 8.553026 -62.94249) (xy 8.589491 -62.869045)
			(xy 8.632559 -62.799266) (xy 8.681863 -62.733746) (xy 8.736986 -62.673039) (xy 8.79746 -62.61766)
			(xy 8.862772 -62.56808) (xy 8.932369 -62.524719) (xy 9.005659 -62.487945) (xy 9.04367 -62.47257)
			(xy 9.052103 -62.468823) (xy 9.065784 -62.456464) (xy 9.07034 -62.44844) (xy 9.084056 -62.42177)
			(xy 9.087894 -62.413359) (xy 9.089841 -62.394988) (xy 9.087866 -62.385956) (xy 9.078643 -62.349166)
			(xy 9.065764 -62.274415) (xy 9.059304 -62.198838) (xy 9.05891 -62.160912) (xy 9.059364 -62.119809)
			(xy 9.066948 -62.037952) (xy 9.082053 -61.957145) (xy 9.104549 -61.878076) (xy 9.134245 -61.80142)
			(xy 9.170888 -61.727831) (xy 9.214164 -61.657937) (xy 9.263705 -61.592335) (xy 9.319087 -61.531583)
			(xy 9.379839 -61.476201) (xy 9.445442 -61.426661) (xy 9.515336 -61.383385) (xy 9.588925 -61.346743)
			(xy 9.665581 -61.317047) (xy 9.744651 -61.294551) (xy 9.825458 -61.279447) (xy 9.907315 -61.271863)
			(xy 9.948418 -61.271404) (xy 9.994814 -61.271979) (xy 10.087102 -61.281627) (xy 10.177886 -61.300825)
			(xy 10.266179 -61.329365) (xy 10.308844 -61.347604) (xy 10.318784 -61.351424) (xy 10.340052 -61.351424)
			(xy 10.349992 -61.347604) (xy 10.392652 -61.329354) (xy 10.480945 -61.300811) (xy 10.571731 -61.28162)
			(xy 10.664022 -61.271988) (xy 10.710418 -61.271404) (xy 10.751521 -61.271849) (xy 10.833377 -61.279436)
			(xy 10.914183 -61.294543) (xy 10.993251 -61.317041) (xy 11.069905 -61.346739) (xy 11.143493 -61.383383)
			(xy 11.213385 -61.42666) (xy 11.278986 -61.476202) (xy 11.339736 -61.531585) (xy 11.395117 -61.592337)
			(xy 11.444657 -61.65794) (xy 11.487932 -61.727834) (xy 11.524573 -61.801422) (xy 11.554268 -61.878078)
			(xy 11.576764 -61.957146) (xy 11.591868 -62.037953) (xy 11.599452 -62.119809) (xy 11.599926 -62.160912)
			(xy 11.599412 -62.20418) (xy 11.591007 -62.290308) (xy 11.574279 -62.375212) (xy 11.549384 -62.45809)
			(xy 11.516558 -62.53816) (xy 11.476112 -62.614663) (xy 11.428428 -62.686876) (xy 11.373957 -62.754118)
			(xy 11.313213 -62.815753) (xy 11.246772 -62.871197) (xy 11.211306 -62.895988) (xy 11.200384 -62.903354)
			(xy 11.1887 -62.92596) (xy 11.19124 -63.037466) (xy 11.203686 -63.059564) (xy 11.214862 -63.066422)
			(xy 11.249558 -63.088451) (xy 11.315146 -63.137985) (xy 11.375884 -63.193359) (xy 11.431253 -63.254102)
			(xy 11.480782 -63.319694) (xy 11.524047 -63.389577) (xy 11.56068 -63.463153) (xy 11.590368 -63.539796)
			(xy 11.612857 -63.61885) (xy 11.627956 -63.699643) (xy 11.635536 -63.781484) (xy 11.635702 -63.796348)
			(xy 31.622996 -63.796348) (xy 31.622996 -63.711652) (xy 31.631047 -63.627338) (xy 31.647076 -63.544172)
			(xy 31.670937 -63.462905) (xy 31.702416 -63.384275) (xy 31.741227 -63.308994) (xy 31.787017 -63.237742)
			(xy 31.839373 -63.171166) (xy 31.897821 -63.109868) (xy 31.961831 -63.054403) (xy 32.030823 -63.005274)
			(xy 32.104173 -62.962925) (xy 32.181216 -62.927741) (xy 32.261255 -62.900039) (xy 32.343564 -62.880071)
			(xy 32.427399 -62.868018) (xy 32.512 -62.863988) (xy 32.596601 -62.868018) (xy 32.680436 -62.880071)
			(xy 32.762745 -62.900039) (xy 32.842784 -62.927741) (xy 32.919827 -62.962925) (xy 32.993177 -63.005274)
			(xy 33.062169 -63.054403) (xy 33.126179 -63.109868) (xy 33.184627 -63.171166) (xy 33.218509 -63.21425)
			(xy 34.033718 -63.21425) (xy 34.037748 -63.129649) (xy 34.049801 -63.045814) (xy 34.069769 -62.963505)
			(xy 34.097471 -62.883466) (xy 34.132655 -62.806423) (xy 34.175004 -62.733073) (xy 34.224133 -62.664081)
			(xy 34.279598 -62.600071) (xy 34.340896 -62.541623) (xy 34.407472 -62.489267) (xy 34.478724 -62.443477)
			(xy 34.554005 -62.404666) (xy 34.632635 -62.373187) (xy 34.713902 -62.349326) (xy 34.797068 -62.333297)
			(xy 34.881382 -62.325246) (xy 34.92373 -62.324742) (xy 34.972583 -62.32541) (xy 35.069704 -62.336099)
			(xy 35.117532 -62.346078) (xy 35.126604 -62.347689) (xy 35.14483 -62.345078) (xy 35.153092 -62.340998)
			(xy 35.179254 -62.32652) (xy 35.187103 -62.321709) (xy 35.198952 -62.307637) (xy 35.202368 -62.299088)
			(xy 35.216984 -62.259706) (xy 35.252601 -62.183621) (xy 35.295233 -62.111234) (xy 35.344499 -62.043188)
			(xy 35.399961 -61.980091) (xy 35.461125 -61.922503) (xy 35.527445 -61.870938) (xy 35.598332 -61.825856)
			(xy 35.673154 -61.787657) (xy 35.751244 -61.756683) (xy 35.831906 -61.733209) (xy 35.914421 -61.717445)
			(xy 35.998056 -61.70953) (xy 36.04006 -61.709046) (xy 36.082409 -61.709542) (xy 36.166723 -61.717593)
			(xy 36.249889 -61.733622) (xy 36.331156 -61.757484) (xy 36.409786 -61.788963) (xy 36.485068 -61.827773)
			(xy 36.55632 -61.873564) (xy 36.622897 -61.92592) (xy 36.684195 -61.984368) (xy 36.73966 -62.048378)
			(xy 36.78879 -62.117371) (xy 36.831138 -62.190721) (xy 36.866323 -62.267764) (xy 36.894025 -62.347803)
			(xy 36.913993 -62.430113) (xy 36.926046 -62.513949) (xy 36.930077 -62.59855) (xy 36.926046 -62.683151)
			(xy 36.913993 -62.766987) (xy 36.894025 -62.849297) (xy 36.866323 -62.929336) (xy 36.831138 -63.006379)
			(xy 36.78879 -63.079729) (xy 36.73966 -63.148722) (xy 36.684195 -63.212732) (xy 36.622897 -63.27118)
			(xy 36.55632 -63.323536) (xy 36.485068 -63.369327) (xy 36.409786 -63.408137) (xy 36.331156 -63.439616)
			(xy 36.249889 -63.463478) (xy 36.166723 -63.479507) (xy 36.082409 -63.487558) (xy 36.04006 -63.488062)
			(xy 35.991207 -63.487396) (xy 35.894086 -63.476705) (xy 35.846258 -63.466726) (xy 35.837187 -63.46511)
			(xy 35.81896 -63.467724) (xy 35.810698 -63.471806) (xy 35.784536 -63.486284) (xy 35.776685 -63.491091)
			(xy 35.769186 -63.5) (xy 36.956492 -63.5) (xy 36.956969 -63.458464) (xy 36.964723 -63.375756) (xy 36.980153 -63.29413)
			(xy 37.003126 -63.214299) (xy 37.033441 -63.136957) (xy 37.070835 -63.062777) (xy 37.114981 -62.992407)
			(xy 37.165495 -62.926459) (xy 37.221937 -62.865508) (xy 37.283816 -62.810083) (xy 37.316918 -62.78499)
			(xy 37.326134 -62.777283) (xy 37.336883 -62.755838) (xy 37.337492 -62.743842) (xy 37.337492 -62.738)
			(xy 37.337967 -62.696898) (xy 37.345552 -62.615043) (xy 37.360657 -62.534238) (xy 37.383153 -62.455171)
			(xy 37.412849 -62.378517) (xy 37.449491 -62.30493) (xy 37.492766 -62.235038) (xy 37.542306 -62.169437)
			(xy 37.597687 -62.108687) (xy 37.658437 -62.053306) (xy 37.724038 -62.003766) (xy 37.79393 -61.960491)
			(xy 37.867517 -61.923849) (xy 37.944171 -61.894153) (xy 38.023238 -61.871657) (xy 38.104043 -61.856552)
			(xy 38.185898 -61.848967) (xy 38.227 -61.848492) (xy 38.269691 -61.848987) (xy 38.35468 -61.857168)
			(xy 38.438494 -61.873456) (xy 38.520362 -61.897699) (xy 38.59953 -61.929676) (xy 38.67527 -61.969091)
			(xy 38.746885 -62.015583) (xy 38.813715 -62.068723) (xy 38.875146 -62.128022) (xy 38.925388 -62.18682)
			(xy 39.605712 -62.18682) (xy 39.606171 -62.145717) (xy 39.613755 -62.06386) (xy 39.628859 -61.983053)
			(xy 39.651355 -61.903984) (xy 39.68105 -61.827328) (xy 39.717692 -61.753739) (xy 39.760968 -61.683845)
			(xy 39.810509 -61.618243) (xy 39.865891 -61.557491) (xy 39.926643 -61.502109) (xy 39.992245 -61.452568)
			(xy 40.062139 -61.409292) (xy 40.135728 -61.37265) (xy 40.212384 -61.342955) (xy 40.291453 -61.320459)
			(xy 40.37226 -61.305355) (xy 40.454117 -61.297771) (xy 40.49522 -61.297312) (xy 40.535415 -61.297761)
			(xy 40.615477 -61.304997) (xy 40.69456 -61.319425) (xy 40.77202 -61.340929) (xy 40.847224 -61.369332)
			(xy 40.883586 -61.386466) (xy 40.894955 -61.391141) (xy 40.919488 -61.390498) (xy 40.930576 -61.385196)
			(xy 40.970538 -61.363428) (xy 41.054035 -61.32723) (xy 41.140791 -61.299746) (xy 41.229899 -61.281264)
			(xy 41.320429 -61.271976) (xy 41.365932 -61.271404) (xy 41.412327 -61.27201) (xy 41.504615 -61.281648)
			(xy 41.595399 -61.300837) (xy 41.683693 -61.329369) (xy 41.726358 -61.347604) (xy 41.736298 -61.351424)
			(xy 41.757566 -61.351424) (xy 41.767506 -61.347604) (xy 41.810164 -61.329349) (xy 41.898458 -61.300808)
			(xy 41.989244 -61.281617) (xy 42.081536 -61.271987) (xy 42.127932 -61.271404) (xy 42.17028 -61.271885)
			(xy 42.254593 -61.279939) (xy 42.337758 -61.29597) (xy 42.419022 -61.319834) (xy 42.497651 -61.351315)
			(xy 42.572931 -61.390127) (xy 42.644181 -61.435919) (xy 42.710755 -61.488276) (xy 42.772052 -61.546724)
			(xy 42.827515 -61.610734) (xy 42.876643 -61.679726) (xy 42.91899 -61.753076) (xy 42.954173 -61.830119)
			(xy 42.981874 -61.910157) (xy 43.001841 -61.992466) (xy 43.013895 -62.0763) (xy 43.017925 -62.1609)
			(xy 43.013895 -62.2455) (xy 43.001841 -62.329334) (xy 42.981874 -62.411643) (xy 42.954173 -62.491681)
			(xy 42.91899 -62.568724) (xy 42.876643 -62.642074) (xy 42.827515 -62.711066) (xy 42.772052 -62.775076)
			(xy 42.710755 -62.833524) (xy 42.644181 -62.885881) (xy 42.572931 -62.931673) (xy 42.497651 -62.970485)
			(xy 42.419022 -63.001966) (xy 42.337758 -63.02583) (xy 42.254593 -63.041861) (xy 42.17028 -63.049915)
			(xy 42.127932 -63.05042) (xy 42.081537 -63.049825) (xy 41.989249 -63.040183) (xy 41.898465 -63.020991)
			(xy 41.810171 -62.992456) (xy 41.767506 -62.97422) (xy 41.757566 -62.9704) (xy 41.736298 -62.9704)
			(xy 41.726358 -62.97422) (xy 41.700867 -62.985226) (xy 41.648758 -63.004417) (xy 41.622218 -63.012574)
			(xy 41.609518 -63.016638) (xy 41.590976 -63.035688) (xy 41.562782 -63.145924) (xy 41.56964 -63.171578)
			(xy 41.579038 -63.18123) (xy 41.608974 -63.21238) (xy 41.663298 -63.279566) (xy 41.71085 -63.351704)
			(xy 41.751182 -63.428113) (xy 41.783914 -63.508073) (xy 41.808736 -63.590831) (xy 41.825416 -63.675607)
			(xy 41.833795 -63.7616) (xy 41.834308 -63.8048) (xy 41.833804 -63.847148) (xy 41.825753 -63.931462)
			(xy 41.809724 -64.014628) (xy 41.785863 -64.095895) (xy 41.754384 -64.174525) (xy 41.715573 -64.249806)
			(xy 41.669783 -64.321058) (xy 41.617427 -64.387634) (xy 41.560905 -64.446912) (xy 44.31411 -64.446912)
			(xy 44.314564 -64.405809) (xy 44.322148 -64.323952) (xy 44.337253 -64.243145) (xy 44.359749 -64.164076)
			(xy 44.389445 -64.08742) (xy 44.426088 -64.013831) (xy 44.469364 -63.943937) (xy 44.518905 -63.878335)
			(xy 44.574287 -63.817583) (xy 44.635039 -63.762201) (xy 44.700642 -63.712661) (xy 44.770536 -63.669385)
			(xy 44.844125 -63.632743) (xy 44.920781 -63.603047) (xy 44.999851 -63.580551) (xy 45.080658 -63.565447)
			(xy 45.162515 -63.557863) (xy 45.203618 -63.557404) (xy 45.250014 -63.557979) (xy 45.342302 -63.567627)
			(xy 45.433086 -63.586825) (xy 45.521379 -63.615365) (xy 45.564044 -63.633604) (xy 45.573984 -63.637424)
			(xy 45.595252 -63.637424) (xy 45.605192 -63.633604) (xy 45.647852 -63.615354) (xy 45.736145 -63.586811)
			(xy 45.826931 -63.56762) (xy 45.919222 -63.557988) (xy 45.965618 -63.557404) (xy 46.012014 -63.557979)
			(xy 46.104302 -63.567627) (xy 46.195086 -63.586825) (xy 46.283379 -63.615365) (xy 46.326044 -63.633604)
			(xy 46.335984 -63.637424) (xy 46.357252 -63.637424) (xy 46.367192 -63.633604) (xy 46.409852 -63.615354)
			(xy 46.498145 -63.586811) (xy 46.588931 -63.56762) (xy 46.681222 -63.557988) (xy 46.727618 -63.557404)
			(xy 46.774014 -63.557979) (xy 46.866302 -63.567627) (xy 46.957086 -63.586825) (xy 47.045379 -63.615365)
			(xy 47.088044 -63.633604) (xy 47.097984 -63.637424) (xy 47.119252 -63.637424) (xy 47.129192 -63.633604)
			(xy 47.171852 -63.615354) (xy 47.260145 -63.586811) (xy 47.350931 -63.56762) (xy 47.443222 -63.557988)
			(xy 47.489618 -63.557404) (xy 47.530721 -63.557849) (xy 47.612577 -63.565436) (xy 47.693383 -63.580543)
			(xy 47.772451 -63.603041) (xy 47.849105 -63.632739) (xy 47.922693 -63.669383) (xy 47.992585 -63.71266)
			(xy 48.058186 -63.762202) (xy 48.118936 -63.817585) (xy 48.174317 -63.878337) (xy 48.223857 -63.94394)
			(xy 48.267132 -64.013834) (xy 48.303773 -64.087422) (xy 48.333468 -64.164078) (xy 48.355964 -64.243146)
			(xy 48.371068 -64.323953) (xy 48.378652 -64.405809) (xy 48.379126 -64.446912) (xy 48.378721 -64.486109)
			(xy 48.371833 -64.564201) (xy 48.358103 -64.641384) (xy 48.337637 -64.717059) (xy 48.324516 -64.753998)
			(xy 48.321491 -64.763411) (xy 48.322155 -64.783154) (xy 48.325786 -64.792352) (xy 48.344597 -64.835569)
			(xy 48.374056 -64.925107) (xy 48.393895 -65.017255) (xy 48.40389 -65.110983) (xy 48.404526 -65.158112)
			(xy 48.404045 -65.199214) (xy 48.396459 -65.281068) (xy 48.381353 -65.361872) (xy 48.358856 -65.440938)
			(xy 48.32916 -65.517591) (xy 48.292518 -65.591178) (xy 48.249243 -65.661069) (xy 48.199704 -65.72667)
			(xy 48.144324 -65.787419) (xy 48.083574 -65.8428) (xy 48.017974 -65.89234) (xy 47.948083 -65.935616)
			(xy 47.874497 -65.972258) (xy 47.797844 -66.001954) (xy 47.718778 -66.024452) (xy 47.637974 -66.039558)
			(xy 47.55612 -66.047145) (xy 47.515018 -66.04762) (xy 47.468623 -66.04703) (xy 47.376334 -66.037387)
			(xy 47.285551 -66.018193) (xy 47.197257 -65.989657) (xy 47.154592 -65.97142) (xy 47.144652 -65.9676)
			(xy 47.123384 -65.9676) (xy 47.113444 -65.97142) (xy 47.07078 -65.98966) (xy 46.982488 -66.018205)
			(xy 46.891704 -66.037399) (xy 46.799414 -66.047034) (xy 46.753018 -66.04762) (xy 46.706623 -66.04703)
			(xy 46.614334 -66.037387) (xy 46.523551 -66.018193) (xy 46.435257 -65.989657) (xy 46.392592 -65.97142)
			(xy 46.382652 -65.9676) (xy 46.361384 -65.9676) (xy 46.351444 -65.97142) (xy 46.30878 -65.98966)
			(xy 46.220488 -66.018205) (xy 46.129704 -66.037399) (xy 46.037414 -66.047034) (xy 45.991018 -66.04762)
			(xy 45.944623 -66.04703) (xy 45.852334 -66.037387) (xy 45.761551 -66.018193) (xy 45.673257 -65.989657)
			(xy 45.630592 -65.97142) (xy 45.620652 -65.9676) (xy 45.599384 -65.9676) (xy 45.589444 -65.97142)
			(xy 45.54678 -65.98966) (xy 45.458488 -66.018205) (xy 45.367704 -66.037399) (xy 45.275414 -66.047034)
			(xy 45.229018 -66.04762) (xy 45.187915 -66.047131) (xy 45.106061 -66.039547) (xy 45.025255 -66.024444)
			(xy 44.946188 -66.001949) (xy 44.869534 -65.972254) (xy 44.795946 -65.935614) (xy 44.726053 -65.89234)
			(xy 44.660451 -65.842801) (xy 44.5997 -65.787421) (xy 44.544318 -65.726672) (xy 44.494777 -65.661072)
			(xy 44.451501 -65.59118) (xy 44.414858 -65.517594) (xy 44.385161 -65.44094) (xy 44.362663 -65.361874)
			(xy 44.347557 -65.281069) (xy 44.339971 -65.199215) (xy 44.33951 -65.158112) (xy 44.339926 -65.118915)
			(xy 44.346812 -65.040824) (xy 44.360539 -64.963641) (xy 44.381001 -64.887965) (xy 44.39412 -64.851026)
			(xy 44.397129 -64.841609) (xy 44.396474 -64.82187) (xy 44.39285 -64.812672) (xy 44.37405 -64.76945)
			(xy 44.344587 -64.679915) (xy 44.324745 -64.587768) (xy 44.314747 -64.494041) (xy 44.31411 -64.446912)
			(xy 41.560905 -64.446912) (xy 41.558979 -64.448932) (xy 41.494969 -64.504397) (xy 41.425977 -64.553526)
			(xy 41.352627 -64.595875) (xy 41.275584 -64.631059) (xy 41.195545 -64.658761) (xy 41.113236 -64.678729)
			(xy 41.029401 -64.690782) (xy 40.9448 -64.694813) (xy 40.860199 -64.690782) (xy 40.776364 -64.678729)
			(xy 40.694055 -64.658761) (xy 40.614016 -64.631059) (xy 40.536973 -64.595875) (xy 40.463623 -64.553526)
			(xy 40.394631 -64.504397) (xy 40.330621 -64.448932) (xy 40.272173 -64.387634) (xy 40.219817 -64.321058)
			(xy 40.174027 -64.249806) (xy 40.135216 -64.174525) (xy 40.103737 -64.095895) (xy 40.079876 -64.014628)
			(xy 40.063847 -63.931462) (xy 40.055796 -63.847148) (xy 40.055292 -63.8048) (xy 40.055742 -63.763678)
			(xy 40.063336 -63.681786) (xy 40.07846 -63.600946) (xy 40.100984 -63.521847) (xy 40.130716 -63.445166)
			(xy 40.167401 -63.371558) (xy 40.210727 -63.301651) (xy 40.260322 -63.236045) (xy 40.287702 -63.20536)
			(xy 40.296592 -63.195454) (xy 40.302688 -63.170054) (xy 40.272462 -63.06185) (xy 40.254174 -63.043054)
			(xy 40.241728 -63.039498) (xy 40.202803 -63.0275) (xy 40.127174 -62.997232) (xy 40.054629 -62.960177)
			(xy 39.985776 -62.916645) (xy 39.92119 -62.867001) (xy 39.861413 -62.81166) (xy 39.806945 -62.751087)
			(xy 39.758243 -62.685788) (xy 39.715714 -62.61631) (xy 39.679714 -62.543236) (xy 39.650545 -62.467176)
			(xy 39.628452 -62.388769) (xy 39.613619 -62.30867) (xy 39.60617 -62.22755) (xy 39.605712 -62.18682)
			(xy 38.925388 -62.18682) (xy 38.930612 -62.192934) (xy 38.979603 -62.262862) (xy 39.021668 -62.337163)
			(xy 39.056419 -62.415153) (xy 39.083538 -62.496114) (xy 39.093648 -62.537594) (xy 39.096849 -62.548553)
			(xy 39.111089 -62.566359) (xy 39.12108 -62.571884) (xy 39.158334 -62.590371) (xy 39.229563 -62.633312)
			(xy 39.296474 -62.682714) (xy 39.358481 -62.738146) (xy 39.415043 -62.799123) (xy 39.465667 -62.865114)
			(xy 39.509911 -62.935542) (xy 39.547387 -63.009792) (xy 39.57777 -63.087216) (xy 39.600793 -63.167138)
			(xy 39.616256 -63.24886) (xy 39.624023 -63.331668) (xy 39.624508 -63.373254) (xy 39.624004 -63.414356)
			(xy 39.616423 -63.496211) (xy 39.601322 -63.577017) (xy 39.578829 -63.656084) (xy 39.549136 -63.732739)
			(xy 39.512497 -63.806327) (xy 39.469224 -63.876221) (xy 39.419686 -63.941823) (xy 39.364307 -64.002574)
			(xy 39.303558 -64.057957) (xy 39.237959 -64.107498) (xy 39.168067 -64.150774) (xy 39.094481 -64.187417)
			(xy 39.017828 -64.217114) (xy 38.938761 -64.239611) (xy 38.857956 -64.254717) (xy 38.776102 -64.262302)
			(xy 38.735 -64.262762) (xy 38.695393 -64.262327) (xy 38.616493 -64.255276) (xy 38.538533 -64.241229)
			(xy 38.462134 -64.220299) (xy 38.424866 -64.206882) (xy 38.412697 -64.203102) (xy 38.387501 -64.206724)
			(xy 38.37686 -64.21374) (xy 38.343987 -64.237638) (xy 38.274613 -64.279989) (xy 38.201666 -64.315835)
			(xy 38.125752 -64.344877) (xy 38.047506 -64.366873) (xy 37.96758 -64.38164) (xy 37.88664 -64.389055)
			(xy 37.846 -64.389508) (xy 37.804898 -64.389033) (xy 37.723043 -64.381448) (xy 37.642238 -64.366343)
			(xy 37.563171 -64.343847) (xy 37.486517 -64.314151) (xy 37.41293 -64.277509) (xy 37.343038 -64.234234)
			(xy 37.277437 -64.184694) (xy 37.216687 -64.129313) (xy 37.161306 -64.068563) (xy 37.111766 -64.002962)
			(xy 37.068491 -63.93307) (xy 37.031849 -63.859483) (xy 37.002153 -63.782829) (xy 36.979657 -63.703762)
			(xy 36.964552 -63.622957) (xy 36.956967 -63.541102) (xy 36.956492 -63.5) (xy 35.769186 -63.5) (xy 35.764837 -63.505166)
			(xy 35.761422 -63.513716) (xy 35.746817 -63.553102) (xy 35.711199 -63.629187) (xy 35.668567 -63.701575)
			(xy 35.619299 -63.76962) (xy 35.563836 -63.832718) (xy 35.502672 -63.890306) (xy 35.43635 -63.94187)
			(xy 35.365462 -63.986952) (xy 35.290639 -64.02515) (xy 35.212549 -64.056124) (xy 35.131886 -64.079597)
			(xy 35.04937 -64.09536) (xy 34.965734 -64.103274) (xy 34.92373 -64.103758) (xy 34.881382 -64.103254)
			(xy 34.797068 -64.095203) (xy 34.713902 -64.079174) (xy 34.632635 -64.055313) (xy 34.554005 -64.023834)
			(xy 34.478724 -63.985023) (xy 34.407472 -63.939233) (xy 34.340896 -63.886877) (xy 34.279598 -63.828429)
			(xy 34.224133 -63.764419) (xy 34.175004 -63.695427) (xy 34.132655 -63.622077) (xy 34.097471 -63.545034)
			(xy 34.069769 -63.464995) (xy 34.049801 -63.382686) (xy 34.037748 -63.298851) (xy 34.033718 -63.21425)
			(xy 33.218509 -63.21425) (xy 33.236983 -63.237742) (xy 33.282773 -63.308994) (xy 33.321584 -63.384275)
			(xy 33.353063 -63.462905) (xy 33.376924 -63.544172) (xy 33.392953 -63.627338) (xy 33.401004 -63.711652)
			(xy 33.401508 -63.754) (xy 33.401004 -63.796348) (xy 33.392953 -63.880662) (xy 33.376924 -63.963828)
			(xy 33.353063 -64.045095) (xy 33.321584 -64.123725) (xy 33.282773 -64.199006) (xy 33.236983 -64.270258)
			(xy 33.184627 -64.336834) (xy 33.126179 -64.398132) (xy 33.062169 -64.453597) (xy 32.993177 -64.502726)
			(xy 32.919827 -64.545075) (xy 32.842784 -64.580259) (xy 32.762745 -64.607961) (xy 32.680436 -64.627929)
			(xy 32.596601 -64.639982) (xy 32.512 -64.644013) (xy 32.427399 -64.639982) (xy 32.343564 -64.627929)
			(xy 32.261255 -64.607961) (xy 32.181216 -64.580259) (xy 32.104173 -64.545075) (xy 32.030823 -64.502726)
			(xy 31.961831 -64.453597) (xy 31.897821 -64.398132) (xy 31.839373 -64.336834) (xy 31.787017 -64.270258)
			(xy 31.741227 -64.199006) (xy 31.702416 -64.123725) (xy 31.670937 -64.045095) (xy 31.647076 -63.963828)
			(xy 31.631047 -63.880662) (xy 31.622996 -63.796348) (xy 11.635702 -63.796348) (xy 11.635994 -63.82258)
			(xy 11.635529 -63.863683) (xy 11.627945 -63.945539) (xy 11.612841 -64.026346) (xy 11.590346 -64.105415)
			(xy 11.56065 -64.182071) (xy 11.524009 -64.255659) (xy 11.480733 -64.325553) (xy 11.431193 -64.391155)
			(xy 11.375811 -64.451907) (xy 11.31506 -64.507289) (xy 11.249458 -64.55683) (xy 11.179564 -64.600106)
			(xy 11.105976 -64.636748) (xy 11.029321 -64.666444) (xy 10.950252 -64.68894) (xy 10.869445 -64.704045)
			(xy 10.787589 -64.711628) (xy 10.746486 -64.712088) (xy 10.705415 -64.711626) (xy 10.623623 -64.704065)
			(xy 10.542876 -64.688992) (xy 10.463864 -64.666535) (xy 10.38726 -64.636886) (xy 10.313718 -64.600298)
			(xy 10.243864 -64.557082) (xy 10.178293 -64.507607) (xy 10.117566 -64.452296) (xy 10.062199 -64.391619)
			(xy 10.012665 -64.326093) (xy 9.969386 -64.256278) (xy 9.932731 -64.182769) (xy 9.91743 -64.144652)
			(xy 9.913366 -64.134492) (xy 9.898126 -64.119506) (xy 9.80694 -64.084962) (xy 9.785858 -64.086232)
			(xy 9.775952 -64.091312) (xy 9.738019 -64.110358) (xy 9.65924 -64.141974) (xy 9.577808 -64.165942)
			(xy 9.494463 -64.182044) (xy 9.409963 -64.190132) (xy 9.36752 -64.190626) (xy 9.326417 -64.190168)
			(xy 9.244561 -64.182583) (xy 9.163754 -64.167477) (xy 9.084686 -64.14498) (xy 9.008031 -64.115284)
			(xy 8.934443 -64.078641) (xy 8.864549 -64.035365) (xy 8.798947 -63.985825) (xy 8.738196 -63.930443)
			(xy 8.682814 -63.869691) (xy 8.633274 -63.804089) (xy 8.589998 -63.734196) (xy 8.553355 -63.660607)
			(xy 8.523659 -63.583952) (xy 8.501162 -63.504884) (xy 8.486057 -63.424077) (xy 8.478472 -63.342221)
			(xy 8.478012 -63.301118) (xy 8.144633 -63.301118) (xy 8.109192 -63.342019) (xy 8.047894 -63.400467)
			(xy 7.981318 -63.452823) (xy 7.910066 -63.498613) (xy 7.834785 -63.537424) (xy 7.756155 -63.568903)
			(xy 7.674888 -63.592764) (xy 7.591722 -63.608793) (xy 7.507408 -63.616844) (xy 7.46506 -63.617348)
			(xy 7.420557 -63.616805) (xy 7.331997 -63.607896) (xy 7.288276 -63.599568) (xy 7.278207 -63.597948)
			(xy 7.258222 -63.601917) (xy 7.241362 -63.61336) (xy 7.235444 -63.621666) (xy 7.213183 -63.655283)
			(xy 7.163466 -63.718765) (xy 7.108207 -63.777486) (xy 7.04786 -63.830964) (xy 6.982919 -63.87876)
			(xy 6.913919 -63.920482) (xy 6.841425 -63.955786) (xy 6.766033 -63.984383) (xy 6.688362 -64.006038)
			(xy 6.609049 -64.020573) (xy 6.528747 -64.027869) (xy 6.48843 -64.02832) (xy 6.446687 -64.027835)
			(xy 6.363569 -64.020004) (xy 6.281549 -64.004423) (xy 6.20135 -63.981227) (xy 6.123675 -63.950622)
			(xy 6.049209 -63.912876) (xy 5.978605 -63.868321) (xy 5.912486 -63.817349) (xy 5.851431 -63.760408)
			(xy 5.795977 -63.697999) (xy 5.746613 -63.63067) (xy 5.703773 -63.559013) (xy 5.667832 -63.483659)
			(xy 5.653024 -63.444628) (xy 5.649098 -63.435293) (xy 5.635318 -63.420475) (xy 5.616895 -63.412104)
			(xy 5.606796 -63.411354) (xy 5.569138 -63.409905) (xy 5.494247 -63.401443) (xy 5.420343 -63.386666)
			(xy 5.384038 -63.376556) (xy 5.375259 -63.374402) (xy 5.357245 -63.375741) (xy 5.340808 -63.383234)
			(xy 5.327981 -63.395953) (xy 5.32384 -63.403988) (xy 5.305701 -63.442041) (xy 5.26318 -63.514837)
			(xy 5.213964 -63.583285) (xy 5.158492 -63.646769) (xy 5.097263 -63.70472) (xy 5.030826 -63.756619)
			(xy 4.959777 -63.801999) (xy 4.884754 -63.840454) (xy 4.806429 -63.87164) (xy 4.725505 -63.895275)
			(xy 4.642708 -63.911148) (xy 4.558781 -63.919117) (xy 4.516628 -63.919608) (xy 4.47474 -63.919147)
			(xy 4.391336 -63.911274) (xy 4.309042 -63.895595) (xy 4.228585 -63.872249) (xy 4.15068 -63.841442)
			(xy 4.076016 -63.803448) (xy 4.040378 -63.781432) (xy 4.031115 -63.776034) (xy 4.009924 -63.77289)
			(xy 3.999484 -63.775336) (xy 3.959958 -63.786075) (xy 3.879434 -63.801091) (xy 3.79787 -63.80864)
			(xy 3.756914 -63.809118) (xy 3.714566 -63.808614) (xy 3.630252 -63.800563) (xy 3.547086 -63.784534)
			(xy 3.465819 -63.760673) (xy 3.387189 -63.729194) (xy 3.311908 -63.690383) (xy 3.240656 -63.644593)
			(xy 3.17408 -63.592237) (xy 3.112782 -63.533789) (xy 3.057317 -63.469779) (xy 3.008188 -63.400787)
			(xy 2.965839 -63.327437) (xy 2.930655 -63.250394) (xy 2.902953 -63.170355) (xy 2.882985 -63.088046)
			(xy 2.870932 -63.004211) (xy 2.866902 -62.91961) (xy 1.651254 -62.91961) (xy 1.651254 -63.620904)
			(xy 1.652778 -63.67145) (xy 1.651254 -63.721996) (xy 1.651254 -67.292728) (xy 1.651782 -67.303295)
			(xy 1.660319 -67.322626) (xy 1.675958 -67.336838) (xy 1.685798 -67.340734) (xy 1.792478 -67.377056)
			(xy 1.823466 -67.367404) (xy 1.833626 -67.35445) (xy 1.859431 -67.321517) (xy 1.916296 -67.260137)
			(xy 1.978672 -67.204368) (xy 2.04601 -67.154702) (xy 2.117714 -67.111579) (xy 2.19315 -67.075379)
			(xy 2.271652 -67.046422) (xy 2.352526 -67.024965) (xy 2.435058 -67.011196) (xy 2.476754 -67.00774)
			(xy 2.490978 -67.006724) (xy 2.513838 -66.990722) (xy 2.561844 -66.882518) (xy 2.558288 -66.854832)
			(xy 2.549398 -66.843656) (xy 2.523652 -66.810058) (xy 2.477928 -66.738817) (xy 2.439178 -66.663555)
			(xy 2.407751 -66.584953) (xy 2.383931 -66.503722) (xy 2.367933 -66.420596) (xy 2.359903 -66.336326)
			(xy 2.359406 -66.294) (xy 2.35991 -66.251652) (xy 2.367961 -66.167338) (xy 2.38399 -66.084172) (xy 2.407851 -66.002905)
			(xy 2.43933 -65.924275) (xy 2.478141 -65.848994) (xy 2.523931 -65.777742) (xy 2.576287 -65.711166)
			(xy 2.634735 -65.649868) (xy 2.698745 -65.594403) (xy 2.767737 -65.545274) (xy 2.841087 -65.502925)
			(xy 2.91813 -65.467741) (xy 2.998169 -65.440039) (xy 3.080478 -65.420071) (xy 3.164313 -65.408018)
			(xy 3.248914 -65.403988) (xy 3.333515 -65.408018) (xy 3.41735 -65.420071) (xy 3.499659 -65.440039)
			(xy 3.579698 -65.467741) (xy 3.656741 -65.502925) (xy 3.730091 -65.545274) (xy 3.799083 -65.594403)
			(xy 3.863093 -65.649868) (xy 3.921541 -65.711166) (xy 3.973897 -65.777742) (xy 4.019687 -65.848994)
			(xy 4.058498 -65.924275) (xy 4.089977 -66.002905) (xy 4.113838 -66.084172) (xy 4.129867 -66.167338)
			(xy 4.137918 -66.251652) (xy 4.138422 -66.294) (xy 7.237988 -66.294) (xy 7.242018 -66.209399) (xy 7.254071 -66.125564)
			(xy 7.274039 -66.043255) (xy 7.301741 -65.963216) (xy 7.336925 -65.886173) (xy 7.379274 -65.812823)
			(xy 7.428403 -65.743831) (xy 7.483868 -65.679821) (xy 7.545166 -65.621373) (xy 7.611742 -65.569017)
			(xy 7.682994 -65.523227) (xy 7.758275 -65.484416) (xy 7.836905 -65.452937) (xy 7.918172 -65.429076)
			(xy 8.001338 -65.413047) (xy 8.085652 -65.404996) (xy 8.128 -65.404492) (xy 8.169279 -65.404971)
			(xy 8.251481 -65.412621) (xy 8.332621 -65.427855) (xy 8.412001 -65.450542) (xy 8.488936 -65.480488)
			(xy 8.562766 -65.517433) (xy 8.632854 -65.561061) (xy 8.698598 -65.610996) (xy 8.759433 -65.666808)
			(xy 8.814833 -65.728017) (xy 8.864324 -65.794096) (xy 8.894869 -65.843912) (xy 12.36091 -65.843912)
			(xy 12.361483 -65.799142) (xy 12.370472 -65.710054) (xy 12.388371 -65.622321) (xy 12.414998 -65.536832)
			(xy 12.43203 -65.495424) (xy 12.435588 -65.485831) (xy 12.435593 -65.46539) (xy 12.43203 -65.4558)
			(xy 12.415 -65.414391) (xy 12.38837 -65.328902) (xy 12.370465 -65.24117) (xy 12.361466 -65.152082)
			(xy 12.36091 -65.107312) (xy 12.361364 -65.066209) (xy 12.368948 -64.984352) (xy 12.384053 -64.903545)
			(xy 12.406549 -64.824476) (xy 12.436245 -64.74782) (xy 12.472888 -64.674231) (xy 12.516164 -64.604337)
			(xy 12.565705 -64.538735) (xy 12.621087 -64.477983) (xy 12.681839 -64.422601) (xy 12.747442 -64.373061)
			(xy 12.817336 -64.329785) (xy 12.890925 -64.293143) (xy 12.967581 -64.263447) (xy 13.046651 -64.240951)
			(xy 13.127458 -64.225847) (xy 13.209315 -64.218263) (xy 13.250418 -64.217804) (xy 13.296814 -64.218379)
			(xy 13.389102 -64.228027) (xy 13.479886 -64.247225) (xy 13.568179 -64.275765) (xy 13.610844 -64.294004)
			(xy 13.620784 -64.297824) (xy 13.642052 -64.297824) (xy 13.651992 -64.294004) (xy 13.694652 -64.275754)
			(xy 13.782945 -64.247211) (xy 13.873731 -64.22802) (xy 13.966022 -64.218388) (xy 14.012418 -64.217804)
			(xy 14.058814 -64.218379) (xy 14.151102 -64.228027) (xy 14.241886 -64.247225) (xy 14.330179 -64.275765)
			(xy 14.372844 -64.294004) (xy 14.382784 -64.297824) (xy 14.404052 -64.297824) (xy 14.413992 -64.294004)
			(xy 14.456652 -64.275754) (xy 14.544945 -64.247211) (xy 14.635731 -64.22802) (xy 14.728022 -64.218388)
			(xy 14.774418 -64.217804) (xy 14.820814 -64.218379) (xy 14.913102 -64.228027) (xy 15.003886 -64.247225)
			(xy 15.092179 -64.275765) (xy 15.134844 -64.294004) (xy 15.144784 -64.297824) (xy 15.166052 -64.297824)
			(xy 15.175992 -64.294004) (xy 15.218652 -64.275754) (xy 15.306945 -64.247211) (xy 15.397731 -64.22802)
			(xy 15.490022 -64.218388) (xy 15.536418 -64.217804) (xy 15.577521 -64.218249) (xy 15.659377 -64.225836)
			(xy 15.740183 -64.240943) (xy 15.819251 -64.263441) (xy 15.895905 -64.293139) (xy 15.969493 -64.329783)
			(xy 16.039385 -64.37306) (xy 16.104986 -64.422602) (xy 16.165736 -64.477985) (xy 16.221117 -64.538737)
			(xy 16.270657 -64.60434) (xy 16.313932 -64.674234) (xy 16.350573 -64.747822) (xy 16.380268 -64.824478)
			(xy 16.402764 -64.903546) (xy 16.417868 -64.984353) (xy 16.425452 -65.066209) (xy 16.425926 -65.107312)
			(xy 16.425367 -65.152083) (xy 16.416374 -65.241171) (xy 16.398471 -65.328904) (xy 16.37184 -65.414393)
			(xy 16.354806 -65.4558) (xy 16.351232 -65.465388) (xy 16.351237 -65.485834) (xy 16.354806 -65.495424)
			(xy 16.371846 -65.536829) (xy 16.398473 -65.622319) (xy 16.416375 -65.710053) (xy 16.425371 -65.799141)
			(xy 16.425926 -65.843912) (xy 16.425445 -65.885014) (xy 16.417859 -65.966868) (xy 16.402753 -66.047672)
			(xy 16.380256 -66.126738) (xy 16.35056 -66.203391) (xy 16.313918 -66.276978) (xy 16.270643 -66.346869)
			(xy 16.221104 -66.41247) (xy 16.165724 -66.473219) (xy 16.104974 -66.5286) (xy 16.039374 -66.57814)
			(xy 15.969483 -66.621416) (xy 15.895897 -66.658058) (xy 15.819244 -66.687754) (xy 15.740178 -66.710252)
			(xy 15.659374 -66.725358) (xy 15.57752 -66.732945) (xy 15.536418 -66.73342) (xy 15.490023 -66.73283)
			(xy 15.397734 -66.723187) (xy 15.306951 -66.703993) (xy 15.218657 -66.675457) (xy 15.175992 -66.65722)
			(xy 15.166052 -66.6534) (xy 15.144784 -66.6534) (xy 15.134844 -66.65722) (xy 15.09218 -66.67546)
			(xy 15.003888 -66.704005) (xy 14.913104 -66.723199) (xy 14.820814 -66.732834) (xy 14.774418 -66.73342)
			(xy 14.728023 -66.73283) (xy 14.635734 -66.723187) (xy 14.544951 -66.703993) (xy 14.456657 -66.675457)
			(xy 14.413992 -66.65722) (xy 14.404052 -66.6534) (xy 14.382784 -66.6534) (xy 14.372844 -66.65722)
			(xy 14.33018 -66.67546) (xy 14.241888 -66.704005) (xy 14.151104 -66.723199) (xy 14.058814 -66.732834)
			(xy 14.012418 -66.73342) (xy 13.966023 -66.73283) (xy 13.873734 -66.723187) (xy 13.782951 -66.703993)
			(xy 13.694657 -66.675457) (xy 13.651992 -66.65722) (xy 13.642052 -66.6534) (xy 13.620784 -66.6534)
			(xy 13.610844 -66.65722) (xy 13.56818 -66.67546) (xy 13.479888 -66.704005) (xy 13.389104 -66.723199)
			(xy 13.296814 -66.732834) (xy 13.250418 -66.73342) (xy 13.209315 -66.732931) (xy 13.127461 -66.725347)
			(xy 13.046655 -66.710244) (xy 12.967588 -66.687749) (xy 12.890934 -66.658054) (xy 12.817346 -66.621414)
			(xy 12.747453 -66.57814) (xy 12.681851 -66.528601) (xy 12.6211 -66.473221) (xy 12.565718 -66.412472)
			(xy 12.516177 -66.346872) (xy 12.472901 -66.27698) (xy 12.436258 -66.203394) (xy 12.406561 -66.12674)
			(xy 12.384063 -66.047674) (xy 12.368957 -65.966869) (xy 12.361371 -65.885015) (xy 12.36091 -65.843912)
			(xy 8.894869 -65.843912) (xy 8.907479 -65.864477) (xy 8.943926 -65.938554) (xy 8.973352 -66.015689)
			(xy 8.995504 -66.095219) (xy 9.010191 -66.17646) (xy 9.014206 -66.217546) (xy 9.015476 -66.23304)
			(xy 9.03478 -66.25717) (xy 9.153906 -66.294508) (xy 9.18337 -66.285872) (xy 9.193276 -66.274188)
			(xy 9.221377 -66.241363) (xy 9.282991 -66.180772) (xy 9.350191 -66.126441) (xy 9.422342 -66.078884)
			(xy 9.498766 -66.038547) (xy 9.578741 -66.005813) (xy 9.661514 -65.980989) (xy 9.746304 -65.964308)
			(xy 9.832312 -65.95593) (xy 9.87552 -65.955418) (xy 9.917983 -65.955918) (xy 10.002521 -65.964027)
			(xy 10.085901 -65.980156) (xy 10.167365 -66.004157) (xy 10.246171 -66.035812) (xy 10.321601 -66.074834)
			(xy 10.39297 -66.120865) (xy 10.459627 -66.173489) (xy 10.520965 -66.232225) (xy 10.576428 -66.29654)
			(xy 10.625509 -66.365847) (xy 10.667761 -66.439516) (xy 10.702801 -66.516876) (xy 10.717022 -66.55689)
			(xy 10.720488 -66.565626) (xy 10.732539 -66.580026) (xy 10.748937 -66.589172) (xy 10.75817 -66.590926)
			(xy 10.800093 -66.597358) (xy 10.882567 -66.617176) (xy 10.96278 -66.644756) (xy 11.040002 -66.679849)
			(xy 11.113531 -66.722136) (xy 11.1827 -66.771231) (xy 11.24688 -66.826689) (xy 11.305488 -66.888007)
			(xy 11.357992 -66.954626) (xy 11.403913 -67.025942) (xy 11.442835 -67.101307) (xy 11.474404 -67.180035)
			(xy 11.498334 -67.261411) (xy 11.514407 -67.344696) (xy 11.520436 -67.40779) (xy 33.026858 -67.40779)
			(xy 33.027351 -67.365169) (xy 33.035525 -67.280318) (xy 33.051776 -67.196639) (xy 33.075958 -67.114898)
			(xy 33.107847 -67.035844) (xy 33.147151 -66.960203) (xy 33.19351 -66.888668) (xy 33.246498 -66.821896)
			(xy 33.305631 -66.760498) (xy 33.370365 -66.705037) (xy 33.440107 -66.656023) (xy 33.514217 -66.613904)
			(xy 33.592016 -66.579066) (xy 33.672791 -66.55183) (xy 33.714182 -66.54165) (xy 33.72358 -66.539364)
			(xy 33.739328 -66.528696) (xy 33.788858 -66.455544) (xy 33.792922 -66.437002) (xy 33.791652 -66.42735)
			(xy 33.786917 -66.394216) (xy 33.781832 -66.327469) (xy 33.781492 -66.294) (xy 33.781996 -66.251652)
			(xy 33.790047 -66.167338) (xy 33.806076 -66.084172) (xy 33.829937 -66.002905) (xy 33.861416 -65.924275)
			(xy 33.900227 -65.848994) (xy 33.946017 -65.777742) (xy 33.998373 -65.711166) (xy 34.056821 -65.649868)
			(xy 34.120831 -65.594403) (xy 34.189823 -65.545274) (xy 34.263173 -65.502925) (xy 34.340216 -65.467741)
			(xy 34.420255 -65.440039) (xy 34.502564 -65.420071) (xy 34.586399 -65.408018) (xy 34.671 -65.403988)
			(xy 34.755601 -65.408018) (xy 34.839436 -65.420071) (xy 34.921745 -65.440039) (xy 35.001784 -65.467741)
			(xy 35.078827 -65.502925) (xy 35.152177 -65.545274) (xy 35.221169 -65.594403) (xy 35.285179 -65.649868)
			(xy 35.343627 -65.711166) (xy 35.395983 -65.777742) (xy 35.441773 -65.848994) (xy 35.480584 -65.924275)
			(xy 35.512063 -66.002905) (xy 35.535924 -66.084172) (xy 35.551953 -66.167338) (xy 35.560004 -66.251652)
			(xy 35.560508 -66.294) (xy 35.559968 -66.338139) (xy 35.551246 -66.425983) (xy 35.533859 -66.512531)
			(xy 35.507976 -66.596928) (xy 35.473855 -66.678344) (xy 35.45332 -66.717418) (xy 35.447224 -66.728848)
			(xy 35.44697 -66.753486) (xy 35.496754 -66.850768) (xy 35.517074 -66.864992) (xy 35.52952 -66.866516)
			(xy 35.576124 -66.873129) (xy 35.667697 -66.894933) (xy 35.756454 -66.926289) (xy 35.841402 -66.966847)
			(xy 35.881818 -66.990976) (xy 35.890173 -66.995594) (xy 35.90897 -66.998849) (xy 35.918394 -66.997326)
			(xy 35.947858 -66.991484) (xy 35.957102 -66.989251) (xy 35.973158 -66.979094) (xy 35.9791 -66.971672)
			(xy 36.004119 -66.938057) (xy 36.05957 -66.875225) (xy 36.120685 -66.817887) (xy 36.186923 -66.766551)
			(xy 36.257695 -66.721673) (xy 36.332374 -66.68365) (xy 36.410298 -66.65282) (xy 36.490777 -66.629456)
			(xy 36.573097 -66.613764) (xy 36.656527 -66.605885) (xy 36.698428 -66.605404) (xy 36.74337 -66.605962)
			(xy 36.832796 -66.615027) (xy 36.920852 -66.633062) (xy 37.006641 -66.659883) (xy 37.048186 -66.677032)
			(xy 37.057841 -66.680604) (xy 37.078409 -66.680604) (xy 37.088064 -66.677032) (xy 37.129608 -66.659879)
			(xy 37.215397 -66.63306) (xy 37.303454 -66.615028) (xy 37.39288 -66.605966) (xy 37.437822 -66.605404)
			(xy 37.478925 -66.605846) (xy 37.560781 -66.613433) (xy 37.641587 -66.62854) (xy 37.720655 -66.651039)
			(xy 37.797309 -66.680737) (xy 37.870897 -66.717381) (xy 37.940789 -66.760658) (xy 38.00639 -66.8102)
			(xy 38.067141 -66.865583) (xy 38.122522 -66.926336) (xy 38.172061 -66.991939) (xy 38.215336 -67.061833)
			(xy 38.251977 -67.135422) (xy 38.281672 -67.212077) (xy 38.304168 -67.291146) (xy 38.319272 -67.371953)
			(xy 38.326856 -67.453809) (xy 38.32733 -67.494912) (xy 38.326885 -67.535378) (xy 38.319538 -67.615977)
			(xy 38.318448 -67.6219) (xy 38.602384 -67.6219) (xy 38.606414 -67.537297) (xy 38.618468 -67.45346)
			(xy 38.638437 -67.371149) (xy 38.66614 -67.291108) (xy 38.701326 -67.214064) (xy 38.743676 -67.140712)
			(xy 38.792808 -67.071719) (xy 38.848275 -67.007709) (xy 38.909575 -66.949261) (xy 38.976154 -66.896905)
			(xy 39.047408 -66.851114) (xy 39.122693 -66.812305) (xy 39.201325 -66.780827) (xy 39.282594 -66.756967)
			(xy 39.365763 -66.740939) (xy 39.450078 -66.732891) (xy 39.492428 -66.732404) (xy 39.535733 -66.732898)
			(xy 39.621934 -66.741308) (xy 39.706909 -66.758055) (xy 39.789854 -66.782982) (xy 39.869985 -66.815851)
			(xy 39.946542 -66.856351) (xy 40.0188 -66.9041) (xy 40.086076 -66.958646) (xy 40.117268 -66.98869)
			(xy 40.124634 -66.996056) (xy 40.143684 -67.003676) (xy 40.237918 -67.001136) (xy 40.256714 -66.992754)
			(xy 40.263572 -66.98488) (xy 40.291612 -66.954859) (xy 40.352368 -66.89956) (xy 40.417961 -66.850097)
			(xy 40.487834 -66.806889) (xy 40.561393 -66.770305) (xy 40.638009 -66.740657) (xy 40.717033 -66.718196)
			(xy 40.79779 -66.703114) (xy 40.879593 -66.69554) (xy 40.92067 -66.695066) (xy 40.963865 -66.695594)
			(xy 41.049848 -66.703958) (xy 41.134615 -66.720619) (xy 41.217367 -66.74542) (xy 41.297325 -66.778127)
			(xy 41.373735 -66.818433) (xy 41.445876 -66.865958) (xy 41.513071 -66.920254) (xy 41.574684 -66.980808)
			(xy 41.630135 -67.047051) (xy 41.678903 -67.118359) (xy 41.720527 -67.194059) (xy 41.738042 -67.233546)
			(xy 41.74292 -67.243493) (xy 41.759432 -67.258234) (xy 41.780596 -67.264717) (xy 41.791636 -67.263772)
			(xy 41.821962 -67.259841) (xy 41.882977 -67.25565) (xy 41.913556 -67.25539) (xy 41.955905 -67.255882)
			(xy 42.04022 -67.263933) (xy 42.123388 -67.279962) (xy 42.204656 -67.303824) (xy 42.283288 -67.335303)
			(xy 42.358571 -67.374114) (xy 42.429824 -67.419905) (xy 42.496401 -67.472262) (xy 42.557701 -67.53071)
			(xy 42.613167 -67.594721) (xy 42.662297 -67.663714) (xy 42.704646 -67.737065) (xy 42.739831 -67.81411)
			(xy 42.767533 -67.89415) (xy 42.787502 -67.976461) (xy 42.799556 -68.060297) (xy 42.803586 -68.1449)
			(xy 42.799556 -68.229503) (xy 42.787502 -68.313339) (xy 42.767533 -68.39565) (xy 42.739831 -68.47569)
			(xy 42.704646 -68.552735) (xy 42.662297 -68.626086) (xy 42.613167 -68.695079) (xy 42.557701 -68.75909)
			(xy 42.496401 -68.817538) (xy 42.429824 -68.869895) (xy 42.358571 -68.915686) (xy 42.283288 -68.954497)
			(xy 42.204656 -68.985976) (xy 42.123388 -69.009838) (xy 42.04022 -69.025867) (xy 41.955905 -69.033918)
			(xy 41.913556 -69.034406) (xy 41.870361 -69.033872) (xy 41.784378 -69.025511) (xy 41.699611 -69.008852)
			(xy 41.616858 -68.984052) (xy 41.536899 -68.951345) (xy 41.460489 -68.91104) (xy 41.388347 -68.863516)
			(xy 41.321153 -68.80922) (xy 41.25954 -68.748666) (xy 41.204088 -68.682422) (xy 41.155321 -68.611114)
			(xy 41.113698 -68.535414) (xy 41.096184 -68.495926) (xy 41.091296 -68.485986) (xy 41.074787 -68.471248)
			(xy 41.053629 -68.46476) (xy 41.04259 -68.4657) (xy 41.012263 -68.469628) (xy 40.951249 -68.473822)
			(xy 40.92067 -68.474082) (xy 40.877365 -68.473593) (xy 40.791164 -68.465183) (xy 40.706189 -68.448435)
			(xy 40.623243 -68.423508) (xy 40.543112 -68.390639) (xy 40.466556 -68.350137) (xy 40.394297 -68.302387)
			(xy 40.327022 -68.247841) (xy 40.29583 -68.217796) (xy 40.288464 -68.21043) (xy 40.269414 -68.20281)
			(xy 40.17518 -68.20535) (xy 40.156384 -68.213732) (xy 40.149526 -68.221606) (xy 40.121484 -68.251625)
			(xy 40.060729 -68.306924) (xy 39.995136 -68.356388) (xy 39.925263 -68.399596) (xy 39.851705 -68.43618)
			(xy 39.775088 -68.465829) (xy 39.696065 -68.48829) (xy 39.615308 -68.503372) (xy 39.533505 -68.510946)
			(xy 39.492428 -68.51142) (xy 39.450078 -68.510909) (xy 39.365763 -68.502861) (xy 39.282594 -68.486833)
			(xy 39.201325 -68.462973) (xy 39.122693 -68.431495) (xy 39.047408 -68.392686) (xy 38.976154 -68.346895)
			(xy 38.909575 -68.294539) (xy 38.848274 -68.236091) (xy 38.792808 -68.172081) (xy 38.743676 -68.103088)
			(xy 38.701326 -68.029736) (xy 38.66614 -67.952692) (xy 38.638437 -67.872651) (xy 38.618468 -67.79034)
			(xy 38.606414 -67.706503) (xy 38.602384 -67.6219) (xy 38.318448 -67.6219) (xy 38.304896 -67.695574)
			(xy 38.283081 -67.773511) (xy 38.254272 -67.849143) (xy 38.21871 -67.921844) (xy 38.176688 -67.991012)
			(xy 38.128553 -68.056075) (xy 38.074704 -68.116493) (xy 38.015588 -68.171768) (xy 37.983922 -68.196968)
			(xy 37.976091 -68.203711) (xy 37.966131 -68.221797) (xy 37.964618 -68.23202) (xy 37.960167 -68.272724)
			(xy 37.944697 -68.353139) (xy 37.921901 -68.431791) (xy 37.891971 -68.508014) (xy 37.855161 -68.581163)
			(xy 37.811782 -68.650619) (xy 37.762203 -68.715793) (xy 37.706842 -68.776134) (xy 37.646169 -68.83113)
			(xy 37.580697 -68.880316) (xy 37.510981 -68.923275) (xy 37.437612 -68.959644) (xy 37.361209 -68.989114)
			(xy 37.282422 -69.011436) (xy 37.201915 -69.026421) (xy 37.120373 -69.033942) (xy 37.079428 -69.034406)
			(xy 37.045318 -69.034079) (xy 36.977299 -69.028868) (xy 36.943538 -69.023992) (xy 36.934209 -69.02304)
			(xy 36.915918 -69.027095) (xy 36.900296 -69.037436) (xy 36.894516 -69.04482) (xy 36.869522 -69.079042)
			(xy 36.81405 -69.143113) (xy 36.752736 -69.201618) (xy 36.686136 -69.254026) (xy 36.614854 -69.299864)
			(xy 36.539536 -69.338714) (xy 36.460865 -69.370226) (xy 36.379553 -69.394113) (xy 36.296338 -69.410159)
			(xy 36.211974 -69.418219) (xy 36.1696 -69.418708) (xy 36.128183 -69.418225) (xy 36.045711 -69.410489)
			(xy 35.964314 -69.395122) (xy 35.884698 -69.372257) (xy 35.807552 -69.342091) (xy 35.733543 -69.304885)
			(xy 35.698176 -69.283326) (xy 35.687 -69.276468) (xy 35.662108 -69.274944) (xy 35.56127 -69.32041)
			(xy 35.54603 -69.340222) (xy 35.543998 -69.352922) (xy 35.536694 -69.393998) (xy 35.515416 -69.474673)
			(xy 35.486677 -69.553002) (xy 35.450729 -69.628295) (xy 35.407889 -69.699891) (xy 35.358532 -69.767161)
			(xy 35.303094 -69.829514) (xy 35.24206 -69.886401) (xy 35.175968 -69.937324) (xy 35.105397 -69.981833)
			(xy 35.030969 -70.019539) (xy 34.953337 -70.05011) (xy 34.873183 -70.073277) (xy 34.791213 -70.088837)
			(xy 34.708145 -70.096652) (xy 34.666428 -70.097142) (xy 34.625327 -70.096607) (xy 34.543475 -70.089025)
			(xy 34.462672 -70.073923) (xy 34.383608 -70.05143) (xy 34.306956 -70.021737) (xy 34.23337 -69.985099)
			(xy 34.163479 -69.941828) (xy 34.097879 -69.892292) (xy 34.037129 -69.836915) (xy 33.981747 -69.776169)
			(xy 33.932207 -69.710572) (xy 33.888931 -69.640684) (xy 33.852288 -69.567101) (xy 33.82259 -69.490451)
			(xy 33.800092 -69.411388) (xy 33.784984 -69.330586) (xy 33.777396 -69.248735) (xy 33.77692 -69.207634)
			(xy 33.777436 -69.164645) (xy 33.785747 -69.079069) (xy 33.802276 -68.994695) (xy 33.826868 -68.912308)
			(xy 33.859294 -68.832679) (xy 33.899251 -68.75655) (xy 33.946367 -68.684631) (xy 34.000202 -68.617593)
			(xy 34.060254 -68.556062) (xy 34.125962 -68.500612) (xy 34.196713 -68.451759) (xy 34.271847 -68.409961)
			(xy 34.350664 -68.375607) (xy 34.432427 -68.349018) (xy 34.516375 -68.33044) (xy 34.558986 -68.32473)
			(xy 34.571432 -68.323206) (xy 34.592006 -68.308728) (xy 34.642044 -68.211446) (xy 34.64179 -68.1863)
			(xy 34.635694 -68.175124) (xy 34.61893 -68.142866) (xy 34.61385 -68.132452) (xy 34.595816 -68.118228)
			(xy 34.496502 -68.095622) (xy 34.47415 -68.100702) (xy 34.46526 -68.107814) (xy 34.431709 -68.133513)
			(xy 34.360542 -68.179106) (xy 34.285372 -68.217746) (xy 34.206877 -68.249083) (xy 34.125764 -68.272835)
			(xy 34.042764 -68.288789) (xy 33.958626 -68.296801) (xy 33.916366 -68.297298) (xy 33.875263 -68.296866)
			(xy 33.793407 -68.289278) (xy 33.7126 -68.274169) (xy 33.633533 -68.25167) (xy 33.556878 -68.221971)
			(xy 33.483291 -68.185326) (xy 33.413398 -68.142048) (xy 33.347797 -68.092505) (xy 33.287047 -68.037121)
			(xy 33.231667 -67.976369) (xy 33.182127 -67.910765) (xy 33.138853 -67.840871) (xy 33.102211 -67.767282)
			(xy 33.072516 -67.690626) (xy 33.05002 -67.611557) (xy 33.034916 -67.530749) (xy 33.027332 -67.448893)
			(xy 33.026858 -67.40779) (xy 11.520436 -67.40779) (xy 11.522476 -67.429133) (xy 11.522964 -67.471544)
			(xy 11.522497 -67.512647) (xy 11.514912 -67.594501) (xy 11.499806 -67.675307) (xy 11.477309 -67.754374)
			(xy 11.447613 -67.831028) (xy 11.410971 -67.904615) (xy 11.367695 -67.974507) (xy 11.318155 -68.040108)
			(xy 11.262773 -68.100859) (xy 11.202022 -68.15624) (xy 11.136421 -68.205779) (xy 11.066528 -68.249055)
			(xy 10.992941 -68.285696) (xy 10.916286 -68.315392) (xy 10.837219 -68.337888) (xy 10.756413 -68.352993)
			(xy 10.674559 -68.360578) (xy 10.633456 -68.361052) (xy 10.590994 -68.360515) (xy 10.506458 -68.352409)
			(xy 10.423079 -68.336283) (xy 10.341616 -68.312284) (xy 10.262811 -68.280632) (xy 10.187381 -68.241614)
			(xy 10.116013 -68.195585) (xy 10.049355 -68.142965) (xy 9.988016 -68.084232) (xy 9.932553 -68.01992)
			(xy 9.883471 -67.950616) (xy 9.841217 -67.87695) (xy 9.806176 -67.799593) (xy 9.791954 -67.75958)
			(xy 9.788518 -67.75083) (xy 9.776453 -67.736433) (xy 9.760043 -67.727294) (xy 9.750806 -67.725544)
			(xy 9.708592 -67.719062) (xy 9.625559 -67.699051) (xy 9.544827 -67.671171) (xy 9.46714 -67.635679)
			(xy 9.393213 -67.592902) (xy 9.323729 -67.543234) (xy 9.259326 -67.487133) (xy 9.2006 -67.425116)
			(xy 9.14809 -67.357753) (xy 9.10228 -67.285667) (xy 9.063593 -67.20952) (xy 9.032385 -67.130015)
			(xy 9.008943 -67.047884) (xy 8.993485 -66.963884) (xy 8.989314 -66.92138) (xy 8.988044 -66.905886)
			(xy 8.96874 -66.881756) (xy 8.849614 -66.844418) (xy 8.82015 -66.853054) (xy 8.810244 -66.864738)
			(xy 8.782114 -66.897537) (xy 8.720505 -66.958132) (xy 8.653311 -67.012466) (xy 8.581163 -67.060027)
			(xy 8.504743 -67.100367) (xy 8.424771 -67.133104) (xy 8.342001 -67.157931) (xy 8.257213 -67.174614)
			(xy 8.171207 -67.182995) (xy 8.128 -67.183508) (xy 8.085652 -67.183004) (xy 8.001338 -67.174953)
			(xy 7.918172 -67.158924) (xy 7.836905 -67.135063) (xy 7.758275 -67.103584) (xy 7.682994 -67.064773)
			(xy 7.611742 -67.018983) (xy 7.545166 -66.966627) (xy 7.483868 -66.908179) (xy 7.428403 -66.844169)
			(xy 7.379274 -66.775177) (xy 7.336925 -66.701827) (xy 7.301741 -66.624784) (xy 7.274039 -66.544745)
			(xy 7.254071 -66.462436) (xy 7.242018 -66.378601) (xy 7.237988 -66.294) (xy 4.138422 -66.294) (xy 4.137936 -66.335693)
			(xy 4.130134 -66.418713) (xy 4.114596 -66.500639) (xy 4.091458 -66.58075) (xy 4.060924 -66.658344)
			(xy 4.023261 -66.73274) (xy 3.978801 -66.803284) (xy 3.927933 -66.869357) (xy 3.871104 -66.930379)
			(xy 3.808813 -66.985814) (xy 3.741607 -67.035176) (xy 3.670076 -67.07803) (xy 3.594848 -67.114002)
			(xy 3.516583 -67.142774) (xy 3.435969 -67.164095) (xy 3.353713 -67.177777) (xy 3.31216 -67.181222)
			(xy 3.297936 -67.182238) (xy 3.275076 -67.19824) (xy 3.22707 -67.306444) (xy 3.230626 -67.33413)
			(xy 3.239516 -67.345306) (xy 3.265262 -67.378904) (xy 3.310986 -67.450145) (xy 3.349736 -67.525407)
			(xy 3.381164 -67.604009) (xy 3.404984 -67.68524) (xy 3.420981 -67.768366) (xy 3.429011 -67.852636)
			(xy 3.429508 -67.894962) (xy 3.429042 -67.936121) (xy 3.428218 -67.945) (xy 3.670032 -67.945) (xy 3.674062 -67.860397)
			(xy 3.686116 -67.776561) (xy 3.706084 -67.69425) (xy 3.733787 -67.61421) (xy 3.768972 -67.537165)
			(xy 3.811321 -67.463814) (xy 3.860451 -67.394821) (xy 3.915917 -67.33081) (xy 3.977216 -67.272361)
			(xy 4.043794 -67.220004) (xy 4.115047 -67.174212) (xy 4.19033 -67.135401) (xy 4.268962 -67.103922)
			(xy 4.35023 -67.08006) (xy 4.433398 -67.064031) (xy 4.517713 -67.05598) (xy 4.560062 -67.055492)
			(xy 4.604519 -67.056018) (xy 4.69299 -67.064884) (xy 4.780135 -67.082531) (xy 4.865085 -67.108784)
			(xy 4.946992 -67.14338) (xy 4.986274 -67.164204) (xy 4.997805 -67.169631) (xy 5.023257 -67.169631)
			(xy 5.034788 -67.164204) (xy 5.074069 -67.143378) (xy 5.155978 -67.10879) (xy 5.240929 -67.082542)
			(xy 5.328074 -67.064897) (xy 5.416543 -67.05603) (xy 5.461 -67.055492) (xy 5.502102 -67.055967) (xy 5.583957 -67.063552)
			(xy 5.664762 -67.078657) (xy 5.743829 -67.101153) (xy 5.820483 -67.130849) (xy 5.89407 -67.167491)
			(xy 5.963962 -67.210766) (xy 6.029563 -67.260306) (xy 6.090313 -67.315687) (xy 6.145694 -67.376437)
			(xy 6.195234 -67.442038) (xy 6.238509 -67.51193) (xy 6.275151 -67.585517) (xy 6.304847 -67.662171)
			(xy 6.327343 -67.741238) (xy 6.342448 -67.822043) (xy 6.350033 -67.903898) (xy 6.350508 -67.945)
			(xy 6.349492 -67.988942) (xy 6.34873 -68.004182) (xy 6.36397 -68.03009) (xy 6.474714 -68.084954)
			(xy 6.504686 -68.081398) (xy 6.51637 -68.071492) (xy 6.550771 -68.043251) (xy 6.624227 -67.992984)
			(xy 6.702336 -67.950303) (xy 6.784315 -67.915633) (xy 6.869346 -67.889322) (xy 6.95658 -67.871632)
			(xy 7.045144 -67.86274) (xy 7.089648 -67.862196) (xy 7.131803 -67.862695) (xy 7.215733 -67.870686)
			(xy 7.298531 -67.886581) (xy 7.379454 -67.910239) (xy 7.457775 -67.941448) (xy 7.532793 -67.979926)
			(xy 7.603833 -68.02533) (xy 7.670259 -68.077251) (xy 7.731474 -68.135224) (xy 7.78693 -68.198728)
			(xy 7.836129 -68.267194) (xy 7.87863 -68.340009) (xy 7.91405 -68.416517) (xy 7.942073 -68.496034)
			(xy 7.95274 -68.53682) (xy 7.95528 -68.54698) (xy 7.967472 -68.562982) (xy 8.047736 -68.610226) (xy 8.067802 -68.61302)
			(xy 8.077962 -68.610226) (xy 8.115833 -68.600458) (xy 8.192844 -68.586788) (xy 8.270757 -68.57992)
			(xy 8.309864 -68.579492) (xy 8.352212 -68.579996) (xy 8.436526 -68.588047) (xy 8.519692 -68.604076)
			(xy 8.600958 -68.627938) (xy 8.679587 -68.659417) (xy 8.754869 -68.698228) (xy 8.82612 -68.744019)
			(xy 8.892696 -68.796375) (xy 8.953994 -68.854822) (xy 9.009458 -68.918832) (xy 9.058587 -68.987824)
			(xy 9.100935 -69.061174) (xy 9.136119 -69.138217) (xy 9.163821 -69.218255) (xy 9.183789 -69.300565)
			(xy 9.187326 -69.325166) (xy 10.413996 -69.325166) (xy 10.413996 -69.24047) (xy 10.422047 -69.156156)
			(xy 10.438076 -69.07299) (xy 10.461937 -68.991723) (xy 10.493416 -68.913093) (xy 10.532227 -68.837812)
			(xy 10.578017 -68.76656) (xy 10.630373 -68.699984) (xy 10.688821 -68.638686) (xy 10.752831 -68.583221)
			(xy 10.821823 -68.534092) (xy 10.895173 -68.491743) (xy 10.972216 -68.456559) (xy 11.052255 -68.428857)
			(xy 11.134564 -68.408889) (xy 11.218399 -68.396836) (xy 11.303 -68.392806) (xy 11.387601 -68.396836)
			(xy 11.471436 -68.408889) (xy 11.553745 -68.428857) (xy 11.633784 -68.456559) (xy 11.710827 -68.491743)
			(xy 11.784177 -68.534092) (xy 11.853169 -68.583221) (xy 11.917179 -68.638686) (xy 11.975627 -68.699984)
			(xy 12.027983 -68.76656) (xy 12.073773 -68.837812) (xy 12.112584 -68.913093) (xy 12.144063 -68.991723)
			(xy 12.167924 -69.07299) (xy 12.181979 -69.145912) (xy 13.12291 -69.145912) (xy 13.123364 -69.104809)
			(xy 13.130948 -69.022952) (xy 13.146053 -68.942145) (xy 13.168549 -68.863076) (xy 13.198245 -68.78642)
			(xy 13.234888 -68.712831) (xy 13.278164 -68.642937) (xy 13.327705 -68.577335) (xy 13.383087 -68.516583)
			(xy 13.443839 -68.461201) (xy 13.509442 -68.411661) (xy 13.579336 -68.368385) (xy 13.652925 -68.331743)
			(xy 13.729581 -68.302047) (xy 13.808651 -68.279551) (xy 13.889458 -68.264447) (xy 13.971315 -68.256863)
			(xy 14.012418 -68.256404) (xy 14.058814 -68.256979) (xy 14.151102 -68.266627) (xy 14.241886 -68.285825)
			(xy 14.330179 -68.314365) (xy 14.372844 -68.332604) (xy 14.382784 -68.336424) (xy 14.404052 -68.336424)
			(xy 14.413992 -68.332604) (xy 14.456652 -68.314354) (xy 14.544945 -68.285811) (xy 14.635731 -68.26662)
			(xy 14.728022 -68.256988) (xy 14.774418 -68.256404) (xy 14.820814 -68.256979) (xy 14.913102 -68.266627)
			(xy 15.003886 -68.285825) (xy 15.092179 -68.314365) (xy 15.134844 -68.332604) (xy 15.144784 -68.336424)
			(xy 15.166052 -68.336424) (xy 15.175992 -68.332604) (xy 15.218652 -68.314354) (xy 15.306945 -68.285811)
			(xy 15.397731 -68.26662) (xy 15.490022 -68.256988) (xy 15.536418 -68.256404) (xy 15.582814 -68.256979)
			(xy 15.675102 -68.266627) (xy 15.765886 -68.285825) (xy 15.854179 -68.314365) (xy 15.896844 -68.332604)
			(xy 15.906784 -68.336424) (xy 15.928052 -68.336424) (xy 15.937992 -68.332604) (xy 15.980652 -68.314354)
			(xy 16.068945 -68.285811) (xy 16.159731 -68.26662) (xy 16.252022 -68.256988) (xy 16.298418 -68.256404)
			(xy 16.340708 -68.256929) (xy 16.424907 -68.264953) (xy 16.507964 -68.280936) (xy 16.589127 -68.304735)
			(xy 16.667664 -68.336133) (xy 16.742864 -68.374848) (xy 16.814048 -68.420528) (xy 16.880572 -68.472762)
			(xy 16.941835 -68.531077) (xy 16.997284 -68.594947) (xy 17.046417 -68.663793) (xy 17.068038 -68.700142)
			(xy 17.073806 -68.709011) (xy 17.090853 -68.721492) (xy 17.101058 -68.724272) (xy 17.142811 -68.734157)
			(xy 17.224346 -68.760894) (xy 17.302927 -68.795359) (xy 17.377823 -68.837232) (xy 17.448339 -68.886124)
			(xy 17.513818 -68.94158) (xy 17.573652 -69.003084) (xy 17.627284 -69.070065) (xy 17.674216 -69.1419)
			(xy 17.714011 -69.217921) (xy 17.746299 -69.297421) (xy 17.770781 -69.379662) (xy 17.787229 -69.463878)
			(xy 17.795489 -69.549286) (xy 17.796002 -69.59219) (xy 17.795538 -69.633293) (xy 17.787954 -69.715149)
			(xy 17.772849 -69.795956) (xy 17.750353 -69.875024) (xy 17.720657 -69.951679) (xy 17.684015 -70.025268)
			(xy 17.64074 -70.095161) (xy 17.591199 -70.160763) (xy 17.535818 -70.221515) (xy 17.475066 -70.276897)
			(xy 17.409464 -70.326437) (xy 17.339571 -70.369713) (xy 17.265983 -70.406356) (xy 17.189328 -70.436052)
			(xy 17.11026 -70.458549) (xy 17.029453 -70.473654) (xy 16.947597 -70.481238) (xy 16.906494 -70.481698)
			(xy 16.864202 -70.481244) (xy 16.780001 -70.473212) (xy 16.696943 -70.45722) (xy 16.615778 -70.433414)
			(xy 16.537241 -70.402008) (xy 16.462041 -70.363286) (xy 16.390858 -70.317599) (xy 16.324335 -70.265359)
			(xy 16.263073 -70.207038) (xy 16.207625 -70.143163) (xy 16.158494 -70.074311) (xy 16.136874 -70.03796)
			(xy 16.1311 -70.029095) (xy 16.114058 -70.016612) (xy 16.103854 -70.01383) (xy 16.06129 -70.003765)
			(xy 15.97821 -69.97641) (xy 15.937992 -69.95922) (xy 15.928052 -69.9554) (xy 15.906784 -69.9554)
			(xy 15.896844 -69.95922) (xy 15.85418 -69.97746) (xy 15.765888 -70.006005) (xy 15.675104 -70.025199)
			(xy 15.582814 -70.034834) (xy 15.536418 -70.03542) (xy 15.490023 -70.03483) (xy 15.397734 -70.025187)
			(xy 15.306951 -70.005993) (xy 15.218657 -69.977457) (xy 15.175992 -69.95922) (xy 15.166052 -69.9554)
			(xy 15.144784 -69.9554) (xy 15.134844 -69.95922) (xy 15.113508 -69.968364) (xy 15.102668 -69.973511)
			(xy 15.087041 -69.991684) (xy 15.083536 -70.003162) (xy 15.07617 -70.033642) (xy 15.07399 -70.045451)
			(xy 15.079576 -70.068779) (xy 15.086838 -70.078346) (xy 15.111646 -70.10816) (xy 15.156579 -70.171385)
			(xy 15.195833 -70.238284) (xy 15.229111 -70.308349) (xy 15.256159 -70.381046) (xy 15.276771 -70.455822)
			(xy 15.284196 -70.49389) (xy 15.286791 -70.504794) (xy 15.299851 -70.522978) (xy 15.309342 -70.528942)
			(xy 15.346491 -70.550338) (xy 15.416903 -70.599252) (xy 15.482281 -70.654714) (xy 15.497045 -70.669912)
			(xy 36.575492 -70.669912) (xy 36.575996 -70.627564) (xy 36.584047 -70.54325) (xy 36.600076 -70.460084)
			(xy 36.623937 -70.378817) (xy 36.655416 -70.300187) (xy 36.694227 -70.224906) (xy 36.740017 -70.153654)
			(xy 36.792373 -70.087078) (xy 36.850821 -70.02578) (xy 36.914831 -69.970315) (xy 36.983823 -69.921186)
			(xy 37.057173 -69.878837) (xy 37.134216 -69.843653) (xy 37.214255 -69.815951) (xy 37.296564 -69.795983)
			(xy 37.380399 -69.78393) (xy 37.465 -69.7799) (xy 37.549601 -69.78393) (xy 37.633436 -69.795983)
			(xy 37.715745 -69.815951) (xy 37.795784 -69.843653) (xy 37.872827 -69.878837) (xy 37.946177 -69.921186)
			(xy 38.015169 -69.970315) (xy 38.079179 -70.02578) (xy 38.137627 -70.087078) (xy 38.189983 -70.153654)
			(xy 38.235773 -70.224906) (xy 38.274584 -70.300187) (xy 38.306063 -70.378817) (xy 38.329924 -70.460084)
			(xy 38.345953 -70.54325) (xy 38.354004 -70.627564) (xy 38.354508 -70.669912) (xy 38.354041 -70.710908)
			(xy 38.346509 -70.792553) (xy 38.331499 -70.87316) (xy 38.30914 -70.952044) (xy 38.294818 -70.99046)
			(xy 38.291008 -70.999858) (xy 38.291516 -71.020178) (xy 38.329616 -71.10476) (xy 38.344348 -71.118476)
			(xy 38.353746 -71.122032) (xy 38.392402 -71.137056) (xy 38.447664 -71.163895) (xy 38.95201 -71.163895)
			(xy 38.957277 -71.080211) (xy 38.970397 -70.997394) (xy 38.991252 -70.916179) (xy 39.019657 -70.837287)
			(xy 39.055361 -70.761418) (xy 39.098046 -70.689246) (xy 39.147334 -70.621412) (xy 39.202787 -70.558517)
			(xy 39.263913 -70.501119) (xy 39.330169 -70.449729) (xy 39.400967 -70.404803) (xy 39.47568 -70.366738)
			(xy 39.553642 -70.335874) (xy 39.634164 -70.312483) (xy 39.716529 -70.296774) (xy 39.800007 -70.288886)
			(xy 39.841932 -70.288404) (xy 39.857934 -70.288658) (xy 39.86911 -70.288658) (xy 39.889684 -70.279514)
			(xy 39.955724 -70.203314) (xy 39.96182 -70.18147) (xy 39.959788 -70.170294) (xy 39.954183 -70.13417)
			(xy 39.948209 -70.061306) (xy 39.94785 -70.024752) (xy 39.948321 -69.98365) (xy 39.95591 -69.901797)
			(xy 39.971018 -69.820993) (xy 39.993517 -69.741928) (xy 40.023215 -69.665276) (xy 40.059858 -69.59169)
			(xy 40.103134 -69.5218) (xy 40.152674 -69.4562) (xy 40.208055 -69.395451) (xy 40.268805 -69.34007)
			(xy 40.334405 -69.290531) (xy 40.404296 -69.247255) (xy 40.477881 -69.210612) (xy 40.554534 -69.180915)
			(xy 40.633599 -69.158417) (xy 40.714403 -69.143309) (xy 40.796256 -69.135721) (xy 40.837358 -69.135244)
			(xy 40.880581 -69.135757) (xy 40.96662 -69.14414) (xy 41.051439 -69.16083) (xy 41.134239 -69.185671)
			(xy 41.214239 -69.218427) (xy 41.290683 -69.25879) (xy 41.362851 -69.306379) (xy 41.430061 -69.360745)
			(xy 41.49168 -69.421375) (xy 41.547127 -69.487697) (xy 41.571926 -69.523102) (xy 41.578022 -69.531992)
			(xy 41.596056 -69.543168) (xy 41.692068 -69.55663) (xy 41.712642 -69.550534) (xy 41.72077 -69.543676)
			(xy 41.75507 -69.5158) (xy 41.828227 -69.466192) (xy 41.905942 -69.424082) (xy 41.987448 -69.389883)
			(xy 42.071944 -69.363933) (xy 42.158596 -69.346488) (xy 42.246551 -69.33772) (xy 42.290746 -69.337174)
			(xy 42.334129 -69.337616) (xy 42.420483 -69.346059) (xy 42.505604 -69.36287) (xy 42.588685 -69.38789)
			(xy 42.668934 -69.42088) (xy 42.74559 -69.461527) (xy 42.817923 -69.509445) (xy 42.885248 -69.564179)
			(xy 42.946923 -69.625207) (xy 43.002362 -69.691951) (xy 43.05104 -69.763776) (xy 43.092492 -69.84)
			(xy 43.126326 -69.919897) (xy 43.152219 -70.002709) (xy 43.169926 -70.087649) (xy 43.179278 -70.173909)
			(xy 43.180254 -70.217284) (xy 43.180965 -70.228378) (xy 43.190589 -70.248393) (xy 43.198796 -70.255892)
			(xy 43.220902 -70.274249) (xy 43.262971 -70.313396) (xy 43.28287 -70.334124) (xy 43.289554 -70.340642)
			(xy 43.306371 -70.348715) (xy 43.315636 -70.349872) (xy 43.345354 -70.352412) (xy 43.354654 -70.352739)
			(xy 43.372502 -70.347547) (xy 43.380152 -70.342252) (xy 43.41159 -70.318926) (xy 43.477894 -70.277297)
			(xy 43.547598 -70.241653) (xy 43.620165 -70.212271) (xy 43.695032 -70.189377) (xy 43.77162 -70.173149)
			(xy 43.810428 -70.168008) (xy 43.822874 -70.166484) (xy 43.843448 -70.152006) (xy 43.893486 -70.054724)
			(xy 43.893232 -70.029578) (xy 43.887136 -70.018402) (xy 43.866301 -69.979127) (xy 43.831715 -69.897215)
			(xy 43.80547 -69.812263) (xy 43.787827 -69.725117) (xy 43.778962 -69.636647) (xy 43.778424 -69.59219)
			(xy 43.778957 -69.550264) (xy 43.78685 -69.466784) (xy 43.802563 -69.384418) (xy 43.825957 -69.303895)
			(xy 43.856826 -69.225932) (xy 43.894895 -69.15122) (xy 43.939826 -69.080421) (xy 43.99122 -69.014166)
			(xy 44.048621 -68.953041) (xy 44.111519 -68.897589) (xy 44.179357 -68.848302) (xy 44.251533 -68.805619)
			(xy 44.327404 -68.769917) (xy 44.366688 -68.75526) (xy 44.375289 -68.751741) (xy 44.389354 -68.739617)
			(xy 44.39412 -68.731638) (xy 44.408344 -68.705222) (xy 44.412459 -68.696831) (xy 44.414813 -68.678305)
			(xy 44.412916 -68.669154) (xy 44.40129 -68.617676) (xy 44.388809 -68.51288) (xy 44.388024 -68.460112)
			(xy 44.388464 -68.419008) (xy 44.396048 -68.337151) (xy 44.411153 -68.256343) (xy 44.43365 -68.177273)
			(xy 44.463347 -68.100616) (xy 44.49999 -68.027027) (xy 44.543267 -67.957133) (xy 44.592809 -67.89153)
			(xy 44.648192 -67.830778) (xy 44.708945 -67.775396) (xy 44.774549 -67.725856) (xy 44.844445 -67.68258)
			(xy 44.918035 -67.645938) (xy 44.994692 -67.616243) (xy 45.073762 -67.593748) (xy 45.154571 -67.578645)
			(xy 45.236428 -67.571063) (xy 45.277532 -67.570604) (xy 45.323927 -67.57121) (xy 45.416215 -67.580848)
			(xy 45.506999 -67.600037) (xy 45.595293 -67.628569) (xy 45.637958 -67.646804) (xy 45.647898 -67.650624)
			(xy 45.669166 -67.650624) (xy 45.679106 -67.646804) (xy 45.721764 -67.628549) (xy 45.810058 -67.600008)
			(xy 45.900844 -67.580817) (xy 45.993136 -67.571187) (xy 46.039532 -67.570604) (xy 46.085927 -67.57121)
			(xy 46.178215 -67.580848) (xy 46.268999 -67.600037) (xy 46.357293 -67.628569) (xy 46.399958 -67.646804)
			(xy 46.409898 -67.650624) (xy 46.431166 -67.650624) (xy 46.441106 -67.646804) (xy 46.483764 -67.628549)
			(xy 46.572058 -67.600008) (xy 46.662844 -67.580817) (xy 46.755136 -67.571187) (xy 46.801532 -67.570604)
			(xy 46.847927 -67.57121) (xy 46.940215 -67.580848) (xy 47.030999 -67.600037) (xy 47.119293 -67.628569)
			(xy 47.161958 -67.646804) (xy 47.171898 -67.650624) (xy 47.193166 -67.650624) (xy 47.203106 -67.646804)
			(xy 47.245764 -67.628549) (xy 47.334058 -67.600008) (xy 47.424844 -67.580817) (xy 47.517136 -67.571187)
			(xy 47.563532 -67.570604) (xy 47.60588 -67.571085) (xy 47.690193 -67.579139) (xy 47.773358 -67.59517)
			(xy 47.854622 -67.619034) (xy 47.933251 -67.650515) (xy 48.008531 -67.689327) (xy 48.079781 -67.735119)
			(xy 48.146355 -67.787476) (xy 48.207652 -67.845924) (xy 48.263115 -67.909934) (xy 48.312243 -67.978926)
			(xy 48.35459 -68.052276) (xy 48.389773 -68.129319) (xy 48.417474 -68.209357) (xy 48.437441 -68.291666)
			(xy 48.449495 -68.3755) (xy 48.453525 -68.4601) (xy 48.449495 -68.5447) (xy 48.437441 -68.628534)
			(xy 48.417474 -68.710843) (xy 48.389773 -68.790881) (xy 48.35459 -68.867924) (xy 48.312243 -68.941274)
			(xy 48.263115 -69.010266) (xy 48.207652 -69.074276) (xy 48.146355 -69.132724) (xy 48.079781 -69.185081)
			(xy 48.008531 -69.230873) (xy 47.933251 -69.269685) (xy 47.854622 -69.301166) (xy 47.773358 -69.32503)
			(xy 47.690193 -69.341061) (xy 47.60588 -69.349115) (xy 47.563532 -69.34962) (xy 47.517137 -69.349025)
			(xy 47.424849 -69.339383) (xy 47.334065 -69.320191) (xy 47.245771 -69.291656) (xy 47.203106 -69.27342)
			(xy 47.193166 -69.2696) (xy 47.171898 -69.2696) (xy 47.161958 -69.27342) (xy 47.119292 -69.291655)
			(xy 47.031001 -69.320201) (xy 46.940217 -69.339397) (xy 46.847928 -69.349033) (xy 46.801532 -69.34962)
			(xy 46.755137 -69.349025) (xy 46.662849 -69.339383) (xy 46.572065 -69.320191) (xy 46.483771 -69.291656)
			(xy 46.441106 -69.27342) (xy 46.431166 -69.2696) (xy 46.409898 -69.2696) (xy 46.399958 -69.27342)
			(xy 46.357292 -69.291655) (xy 46.269001 -69.320201) (xy 46.178217 -69.339397) (xy 46.085928 -69.349033)
			(xy 46.039532 -69.34962) (xy 45.993137 -69.349025) (xy 45.900849 -69.339383) (xy 45.810065 -69.320191)
			(xy 45.721771 -69.291656) (xy 45.679106 -69.27342) (xy 45.669166 -69.2696) (xy 45.647898 -69.2696)
			(xy 45.637958 -69.27342) (xy 45.623351 -69.279787) (xy 45.593753 -69.291601) (xy 45.578776 -69.297042)
			(xy 45.570185 -69.300583) (xy 45.556114 -69.312691) (xy 45.551344 -69.320664) (xy 45.53712 -69.34708)
			(xy 45.533004 -69.35547) (xy 45.530652 -69.373997) (xy 45.532548 -69.383148) (xy 45.544173 -69.434626)
			(xy 45.556654 -69.539422) (xy 45.55744 -69.59219) (xy 45.556894 -69.635178) (xy 45.548581 -69.720751)
			(xy 45.532052 -69.805123) (xy 45.50746 -69.887507) (xy 45.475034 -69.967134) (xy 45.435078 -70.043261)
			(xy 45.387964 -70.115179) (xy 45.334132 -70.182215) (xy 45.274083 -70.243746) (xy 45.208379 -70.299197)
			(xy 45.137631 -70.34805) (xy 45.0625 -70.38985) (xy 44.983688 -70.424207) (xy 44.901928 -70.4508)
			(xy 44.817984 -70.469381) (xy 44.775374 -70.475094) (xy 44.762928 -70.476618) (xy 44.742354 -70.491096)
			(xy 44.692316 -70.588378) (xy 44.69257 -70.613524) (xy 44.698666 -70.6247) (xy 44.71543 -70.656958)
			(xy 44.72051 -70.667372) (xy 44.738544 -70.681596) (xy 44.837858 -70.704202) (xy 44.86021 -70.699122)
			(xy 44.8691 -70.69201) (xy 44.902667 -70.666333) (xy 44.973831 -70.620737) (xy 45.048998 -70.582094)
			(xy 45.12749 -70.550754) (xy 45.2086 -70.526998) (xy 45.291598 -70.51104) (xy 45.375735 -70.503025)
			(xy 45.417994 -70.502526) (xy 45.460345 -70.502946) (xy 45.544664 -70.510997) (xy 45.627835 -70.527026)
			(xy 45.709106 -70.550889) (xy 45.787741 -70.582369) (xy 45.863028 -70.621182) (xy 45.934284 -70.666975)
			(xy 46.000864 -70.719334) (xy 46.062166 -70.777785) (xy 46.117634 -70.841798) (xy 46.166767 -70.910794)
			(xy 46.209118 -70.984148) (xy 46.244304 -71.061196) (xy 46.272008 -71.14124) (xy 46.291977 -71.223554)
			(xy 46.304032 -71.307394) (xy 46.308062 -71.392) (xy 46.304032 -71.476606) (xy 46.291977 -71.560446)
			(xy 46.272008 -71.64276) (xy 46.244304 -71.722804) (xy 46.209118 -71.799852) (xy 46.166767 -71.873206)
			(xy 46.117634 -71.942202) (xy 46.062166 -72.006215) (xy 46.000864 -72.064666) (xy 45.934284 -72.117025)
			(xy 45.863028 -72.162818) (xy 45.787741 -72.201631) (xy 45.709106 -72.233111) (xy 45.627835 -72.256974)
			(xy 45.544664 -72.273003) (xy 45.460345 -72.281054) (xy 45.417994 -72.281542) (xy 45.376771 -72.281076)
			(xy 45.294677 -72.273455) (xy 45.213641 -72.258269) (xy 45.134359 -72.235649) (xy 45.05751 -72.205789)
			(xy 44.983754 -72.168945) (xy 44.913724 -72.125433) (xy 44.848022 -72.075627) (xy 44.78721 -72.019955)
			(xy 44.731812 -71.958893) (xy 44.682303 -71.892967) (xy 44.639107 -71.822742) (xy 44.620434 -71.785988)
			(xy 44.615354 -71.775574) (xy 44.59732 -71.76135) (xy 44.498006 -71.738744) (xy 44.475654 -71.743824)
			(xy 44.466764 -71.750936) (xy 44.433203 -71.776622) (xy 44.362039 -71.822218) (xy 44.286871 -71.86086)
			(xy 44.208378 -71.8922) (xy 44.127266 -71.915955) (xy 44.044267 -71.93191) (xy 43.960129 -71.939922)
			(xy 43.91787 -71.94042) (xy 43.877623 -71.939945) (xy 43.797457 -71.93268) (xy 43.718276 -71.918202)
			(xy 43.640726 -71.896632) (xy 43.565441 -71.868143) (xy 43.493038 -71.832971) (xy 43.424108 -71.791402)
			(xy 43.359216 -71.743776) (xy 43.29889 -71.690482) (xy 43.270932 -71.661528) (xy 43.264241 -71.655018)
			(xy 43.247429 -71.64694) (xy 43.238166 -71.64578) (xy 43.208448 -71.64324) (xy 43.199148 -71.642904)
			(xy 43.181299 -71.648101) (xy 43.17365 -71.6534) (xy 43.172888 -71.653908) (xy 43.16095 -71.662798)
			(xy 43.15079 -71.690738) (xy 43.176444 -71.809864) (xy 43.197272 -71.830692) (xy 43.212004 -71.833994)
			(xy 43.253722 -71.843948) (xy 43.335204 -71.870734) (xy 43.413729 -71.905236) (xy 43.488569 -71.947137)
			(xy 43.55903 -71.996045) (xy 43.624456 -72.051508) (xy 43.68424 -72.113011) (xy 43.737828 -72.179981)
			(xy 43.784721 -72.251798) (xy 43.824485 -72.327795) (xy 43.85675 -72.407266) (xy 43.881217 -72.489474)
			(xy 43.897659 -72.573654) (xy 43.905922 -72.659026) (xy 43.90644 -72.701912) (xy 43.905936 -72.74426)
			(xy 43.897885 -72.828574) (xy 43.881856 -72.91174) (xy 43.857995 -72.993007) (xy 43.826516 -73.071637)
			(xy 43.787705 -73.146918) (xy 43.741915 -73.21817) (xy 43.689559 -73.284746) (xy 43.631111 -73.346044)
			(xy 43.567101 -73.401509) (xy 43.498109 -73.450638) (xy 43.424759 -73.492987) (xy 43.347716 -73.528171)
			(xy 43.267677 -73.555873) (xy 43.185368 -73.575841) (xy 43.101533 -73.587894) (xy 43.016932 -73.591925)
			(xy 42.932331 -73.587894) (xy 42.848496 -73.575841) (xy 42.766187 -73.555873) (xy 42.686148 -73.528171)
			(xy 42.609105 -73.492987) (xy 42.535755 -73.450638) (xy 42.466763 -73.401509) (xy 42.402753 -73.346044)
			(xy 42.344305 -73.284746) (xy 42.291949 -73.21817) (xy 42.246159 -73.146918) (xy 42.207348 -73.071637)
			(xy 42.175869 -72.993007) (xy 42.152008 -72.91174) (xy 42.135979 -72.828574) (xy 42.127928 -72.74426)
			(xy 42.127424 -72.701912) (xy 42.127845 -72.661717) (xy 42.135087 -72.581653) (xy 42.149522 -72.50257)
			(xy 42.171031 -72.425111) (xy 42.199441 -72.349908) (xy 42.216578 -72.313546) (xy 42.223182 -72.300338)
			(xy 42.21988 -72.271128) (xy 42.143934 -72.176386) (xy 42.116248 -72.166988) (xy 42.10177 -72.17029)
			(xy 42.051214 -72.181573) (xy 41.948333 -72.193667) (xy 41.896538 -72.19442) (xy 41.855436 -72.193912)
			(xy 41.773582 -72.18633) (xy 41.692777 -72.171228) (xy 41.613709 -72.148735) (xy 41.537055 -72.119042)
			(xy 41.463468 -72.082403) (xy 41.393575 -72.03913) (xy 41.327973 -71.989593) (xy 41.267221 -71.934214)
			(xy 41.211839 -71.873466) (xy 41.162298 -71.807867) (xy 41.119021 -71.737976) (xy 41.082378 -71.664391)
			(xy 41.052681 -71.587738) (xy 41.030183 -71.508672) (xy 41.015077 -71.427868) (xy 41.007491 -71.346014)
			(xy 41.00703 -71.304912) (xy 41.007595 -71.260026) (xy 41.016618 -71.170709) (xy 41.034586 -71.082753)
			(xy 41.047416 -71.039736) (xy 41.05148 -71.02729) (xy 41.0464 -71.002144) (xy 40.975534 -70.916546)
			(xy 40.951912 -70.906894) (xy 40.938958 -70.908418) (xy 40.913646 -70.911144) (xy 40.862815 -70.914069)
			(xy 40.837358 -70.91426) (xy 40.821356 -70.914006) (xy 40.81018 -70.914006) (xy 40.789606 -70.92315)
			(xy 40.723566 -70.99935) (xy 40.71747 -71.021194) (xy 40.719502 -71.03237) (xy 40.725103 -71.068494)
			(xy 40.731079 -71.141358) (xy 40.73144 -71.177912) (xy 40.730912 -71.219837) (xy 40.72302 -71.303315)
			(xy 40.707307 -71.385679) (xy 40.683912 -71.466199) (xy 40.653044 -71.544161) (xy 40.614975 -71.618871)
			(xy 40.570045 -71.689667) (xy 40.518652 -71.755921) (xy 40.461252 -71.817043) (xy 40.398354 -71.872493)
			(xy 40.330517 -71.921778) (xy 40.258343 -71.96446) (xy 40.182473 -72.00016) (xy 40.103579 -72.028561)
			(xy 40.022363 -72.049412) (xy 39.939545 -72.062528) (xy 39.855861 -72.067791) (xy 39.772052 -72.065155)
			(xy 39.688864 -72.054644) (xy 39.607034 -72.036351) (xy 39.527288 -72.010439) (xy 39.450335 -71.977136)
			(xy 39.376858 -71.936739) (xy 39.307509 -71.889607) (xy 39.242902 -71.836157) (xy 39.183613 -71.776865)
			(xy 39.130167 -71.712256) (xy 39.083038 -71.642904) (xy 39.042645 -71.569425) (xy 39.009346 -71.492471)
			(xy 38.983437 -71.412724) (xy 38.965148 -71.330893) (xy 38.954641 -71.247704) (xy 38.95201 -71.163895)
			(xy 38.447664 -71.163895) (xy 38.467009 -71.17329) (xy 38.537919 -71.216313) (xy 38.604516 -71.265749)
			(xy 38.666222 -71.32117) (xy 38.722501 -71.382094) (xy 38.772865 -71.447993) (xy 38.816875 -71.518294)
			(xy 38.85415 -71.592386) (xy 38.884366 -71.669627) (xy 38.907261 -71.749344) (xy 38.922636 -71.830847)
			(xy 38.930357 -71.913428) (xy 38.930834 -71.954898) (xy 38.93033 -71.997246) (xy 38.922279 -72.08156)
			(xy 38.90625 -72.164726) (xy 38.882389 -72.245993) (xy 38.85091 -72.324623) (xy 38.812099 -72.399904)
			(xy 38.766309 -72.471156) (xy 38.713953 -72.537732) (xy 38.655505 -72.59903) (xy 38.591495 -72.654495)
			(xy 38.522503 -72.703624) (xy 38.449153 -72.745973) (xy 38.37211 -72.781157) (xy 38.292071 -72.808859)
			(xy 38.209762 -72.828827) (xy 38.125927 -72.84088) (xy 38.041326 -72.844911) (xy 37.956725 -72.84088)
			(xy 37.87289 -72.828827) (xy 37.790581 -72.808859) (xy 37.710542 -72.781157) (xy 37.633499 -72.745973)
			(xy 37.560149 -72.703624) (xy 37.491157 -72.654495) (xy 37.427147 -72.59903) (xy 37.368699 -72.537732)
			(xy 37.316343 -72.471156) (xy 37.270553 -72.399904) (xy 37.231742 -72.324623) (xy 37.200263 -72.245993)
			(xy 37.176402 -72.164726) (xy 37.160373 -72.08156) (xy 37.152322 -71.997246) (xy 37.151818 -71.954898)
			(xy 37.152293 -71.913902) (xy 37.159824 -71.832257) (xy 37.174831 -71.751651) (xy 37.197187 -71.672766)
			(xy 37.211508 -71.63435) (xy 37.215318 -71.624952) (xy 37.21481 -71.604632) (xy 37.17671 -71.52005)
			(xy 37.161978 -71.506334) (xy 37.15258 -71.502778) (xy 37.113911 -71.487787) (xy 37.039305 -71.451547)
			(xy 36.968397 -71.40852) (xy 36.901802 -71.35908) (xy 36.840098 -71.303655) (xy 36.78382 -71.242728)
			(xy 36.733459 -71.176826) (xy 36.68945 -71.106523) (xy 36.652176 -71.032429) (xy 36.62196 -70.955187)
			(xy 36.599066 -70.875468) (xy 36.583691 -70.793964) (xy 36.57597 -70.711383) (xy 36.575492 -70.669912)
			(xy 15.497045 -70.669912) (xy 15.54202 -70.71621) (xy 15.595565 -70.783167) (xy 15.642418 -70.854966)
			(xy 15.682147 -70.93094) (xy 15.714381 -71.010384) (xy 15.738821 -71.092561) (xy 15.755242 -71.176708)
			(xy 15.76349 -71.262045) (xy 15.764002 -71.304912) (xy 15.763545 -71.346015) (xy 15.755959 -71.42787)
			(xy 15.740852 -71.508676) (xy 15.718355 -71.587743) (xy 15.688658 -71.664397) (xy 15.652015 -71.737984)
			(xy 15.608738 -71.807877) (xy 15.559197 -71.873478) (xy 15.503815 -71.934228) (xy 15.443064 -71.989609)
			(xy 15.377462 -72.039148) (xy 15.307569 -72.082423) (xy 15.233981 -72.119065) (xy 15.157326 -72.148761)
			(xy 15.078258 -72.171257) (xy 14.997452 -72.186361) (xy 14.915597 -72.193946) (xy 14.874494 -72.19442)
			(xy 14.829552 -72.193853) (xy 14.740127 -72.18479) (xy 14.652071 -72.166758) (xy 14.566281 -72.13994)
			(xy 14.524736 -72.122792) (xy 14.515091 -72.119159) (xy 14.494503 -72.119159) (xy 14.484858 -72.122792)
			(xy 14.443312 -72.139939) (xy 14.357523 -72.16676) (xy 14.269467 -72.184793) (xy 14.180042 -72.193856)
			(xy 14.1351 -72.19442) (xy 14.093998 -72.193933) (xy 14.012144 -72.186349) (xy 13.93134 -72.171244)
			(xy 13.852273 -72.148748) (xy 13.77562 -72.119052) (xy 13.702034 -72.082411) (xy 13.632142 -72.039136)
			(xy 13.566541 -71.989598) (xy 13.505791 -71.934217) (xy 13.45041 -71.873468) (xy 13.40087 -71.807868)
			(xy 13.357595 -71.737977) (xy 13.320953 -71.664391) (xy 13.291256 -71.587738) (xy 13.268759 -71.508672)
			(xy 13.253653 -71.427868) (xy 13.246067 -71.346014) (xy 13.245592 -71.304912) (xy 13.246113 -71.261316)
			(xy 13.254641 -71.174543) (xy 13.271616 -71.089021) (xy 13.296876 -71.005569) (xy 13.330179 -70.924988)
			(xy 13.371204 -70.848051) (xy 13.419558 -70.775497) (xy 13.474779 -70.708021) (xy 13.50518 -70.67677)
			(xy 13.51173 -70.6695) (xy 13.519316 -70.651484) (xy 13.519912 -70.641718) (xy 13.520957 -70.601421)
			(xy 13.529456 -70.521253) (xy 13.54517 -70.442182) (xy 13.567973 -70.364857) (xy 13.597676 -70.289912)
			(xy 13.634036 -70.21796) (xy 13.676756 -70.149593) (xy 13.70076 -70.117208) (xy 13.707872 -70.108064)
			(xy 13.712444 -70.085204) (xy 13.686028 -69.984874) (xy 13.670788 -69.967348) (xy 13.66012 -69.962776)
			(xy 13.620695 -69.945258) (xy 13.545156 -69.903572) (xy 13.474008 -69.854767) (xy 13.407918 -69.799304)
			(xy 13.347509 -69.737703) (xy 13.293348 -69.670543) (xy 13.245943 -69.598455) (xy 13.20574 -69.522116)
			(xy 13.173116 -69.442243) (xy 13.148379 -69.359587) (xy 13.13176 -69.274925) (xy 13.123415 -69.189051)
			(xy 13.12291 -69.145912) (xy 12.181979 -69.145912) (xy 12.183953 -69.156156) (xy 12.192004 -69.24047)
			(xy 12.192508 -69.282818) (xy 12.192004 -69.325166) (xy 12.183953 -69.40948) (xy 12.167924 -69.492646)
			(xy 12.144063 -69.573913) (xy 12.112584 -69.652543) (xy 12.073773 -69.727824) (xy 12.027983 -69.799076)
			(xy 11.975627 -69.865652) (xy 11.917179 -69.92695) (xy 11.853169 -69.982415) (xy 11.784177 -70.031544)
			(xy 11.710827 -70.073893) (xy 11.633784 -70.109077) (xy 11.553745 -70.136779) (xy 11.471436 -70.156747)
			(xy 11.387601 -70.1688) (xy 11.303 -70.172831) (xy 11.218399 -70.1688) (xy 11.134564 -70.156747)
			(xy 11.052255 -70.136779) (xy 10.972216 -70.109077) (xy 10.895173 -70.073893) (xy 10.821823 -70.031544)
			(xy 10.752831 -69.982415) (xy 10.688821 -69.92695) (xy 10.630373 -69.865652) (xy 10.578017 -69.799076)
			(xy 10.532227 -69.727824) (xy 10.493416 -69.652543) (xy 10.461937 -69.573913) (xy 10.438076 -69.492646)
			(xy 10.422047 -69.40948) (xy 10.413996 -69.325166) (xy 9.187326 -69.325166) (xy 9.195842 -69.384399)
			(xy 9.199873 -69.469) (xy 9.195842 -69.553601) (xy 9.183789 -69.637435) (xy 9.163821 -69.719745)
			(xy 9.136119 -69.799783) (xy 9.100935 -69.876826) (xy 9.058587 -69.950176) (xy 9.009458 -70.019168)
			(xy 8.953994 -70.083178) (xy 8.892696 -70.141625) (xy 8.82612 -70.193981) (xy 8.754869 -70.239772)
			(xy 8.679587 -70.278583) (xy 8.600958 -70.310062) (xy 8.519692 -70.333924) (xy 8.436526 -70.349953)
			(xy 8.352212 -70.358004) (xy 8.309864 -70.358508) (xy 8.267709 -70.357995) (xy 8.183779 -70.350006)
			(xy 8.100982 -70.334111) (xy 8.020059 -70.310454) (xy 7.941738 -70.279247) (xy 7.866721 -70.240769)
			(xy 7.795681 -70.195367) (xy 7.729255 -70.143447) (xy 7.66804 -70.085475) (xy 7.612583 -70.021972)
			(xy 7.563384 -69.953506) (xy 7.520883 -69.880693) (xy 7.485462 -69.804186) (xy 7.457439 -69.72467)
			(xy 7.446772 -69.683884) (xy 7.444232 -69.673724) (xy 7.43204 -69.657722) (xy 7.351776 -69.610478)
			(xy 7.33171 -69.607684) (xy 7.32155 -69.610478) (xy 7.283684 -69.620264) (xy 7.206671 -69.633928)
			(xy 7.128756 -69.640788) (xy 7.089648 -69.641212) (xy 7.073568 -69.641152) (xy 7.041429 -69.640008)
			(xy 7.025386 -69.638926) (xy 7.011924 -69.63791) (xy 6.988556 -69.648832) (xy 6.921754 -69.73951)
			(xy 6.918452 -69.765164) (xy 6.923532 -69.77761) (xy 6.938408 -69.816657) (xy 6.961637 -69.896926)
			(xy 6.977228 -69.979022) (xy 6.985044 -70.062218) (xy 6.985508 -70.104) (xy 6.985024 -70.145925)
			(xy 6.977133 -70.229404) (xy 6.961421 -70.311769) (xy 6.938028 -70.392291) (xy 6.90716 -70.470253)
			(xy 6.869093 -70.544964) (xy 6.824163 -70.615762) (xy 6.772771 -70.682017) (xy 6.715371 -70.743141)
			(xy 6.652474 -70.798593) (xy 6.584637 -70.847879) (xy 6.512463 -70.890562) (xy 6.436593 -70.926264)
			(xy 6.3577 -70.954668) (xy 6.276483 -70.975521) (xy 6.193665 -70.988638) (xy 6.10998 -70.993903)
			(xy 6.02617 -70.991269) (xy 5.942981 -70.98076) (xy 5.86115 -70.962468) (xy 5.781403 -70.936557)
			(xy 5.704449 -70.903256) (xy 5.63097 -70.86286) (xy 5.561618 -70.815729) (xy 5.49701 -70.762281)
			(xy 5.437719 -70.70299) (xy 5.384271 -70.638382) (xy 5.33714 -70.56903) (xy 5.296744 -70.495551)
			(xy 5.263443 -70.418597) (xy 5.237532 -70.33885) (xy 5.21924 -70.257019) (xy 5.208731 -70.17383)
			(xy 5.206097 -70.09002) (xy 5.211362 -70.006335) (xy 5.224479 -69.923517) (xy 5.245332 -69.8423)
			(xy 5.273736 -69.763407) (xy 5.309438 -69.687537) (xy 5.352121 -69.615363) (xy 5.401407 -69.547526)
			(xy 5.456859 -69.484629) (xy 5.517983 -69.427229) (xy 5.584238 -69.375837) (xy 5.655036 -69.330907)
			(xy 5.729747 -69.29284) (xy 5.807709 -69.261972) (xy 5.888231 -69.238579) (xy 5.970596 -69.222867)
			(xy 6.054075 -69.214976) (xy 6.096 -69.214492) (xy 6.11208 -69.214555) (xy 6.144219 -69.215697) (xy 6.160262 -69.216778)
			(xy 6.173724 -69.217794) (xy 6.197092 -69.206872) (xy 6.263894 -69.116194) (xy 6.267196 -69.09054)
			(xy 6.262116 -69.078094) (xy 6.247244 -69.039046) (xy 6.224013 -68.958777) (xy 6.208421 -68.876682)
			(xy 6.200604 -68.793486) (xy 6.20014 -68.751704) (xy 6.201156 -68.707762) (xy 6.201918 -68.692522)
			(xy 6.186678 -68.666614) (xy 6.075934 -68.61175) (xy 6.045962 -68.615306) (xy 6.034278 -68.625212)
			(xy 5.999897 -68.653478) (xy 5.926437 -68.703742) (xy 5.848325 -68.746421) (xy 5.766342 -68.781087)
			(xy 5.681308 -68.807394) (xy 5.594071 -68.82508) (xy 5.505505 -68.833967) (xy 5.461 -68.834508) (xy 5.416544 -68.833955)
			(xy 5.328074 -68.825096) (xy 5.240929 -68.807454) (xy 5.155979 -68.781207) (xy 5.074071 -68.746617)
			(xy 5.034788 -68.725796) (xy 5.027216 -68.722007) (xy 5.010531 -68.719189) (xy 4.993846 -68.722007)
			(xy 4.986274 -68.725796) (xy 4.946981 -68.746598) (xy 4.865075 -68.781191) (xy 4.780128 -68.807443)
			(xy 4.692986 -68.825094) (xy 4.604518 -68.833967) (xy 4.560062 -68.834508) (xy 4.517713 -68.83402)
			(xy 4.433398 -68.825969) (xy 4.35023 -68.80994) (xy 4.268962 -68.786078) (xy 4.19033 -68.754599)
			(xy 4.115047 -68.715788) (xy 4.043794 -68.669996) (xy 3.977216 -68.617639) (xy 3.915917 -68.55919)
			(xy 3.860451 -68.495179) (xy 3.811321 -68.426186) (xy 3.768972 -68.352835) (xy 3.733787 -68.27579)
			(xy 3.706084 -68.19575) (xy 3.686116 -68.113439) (xy 3.674062 -68.029603) (xy 3.670032 -67.945) (xy 3.428218 -67.945)
			(xy 3.421431 -68.018085) (xy 3.406279 -68.098996) (xy 3.383715 -68.17816) (xy 3.353934 -68.254901)
			(xy 3.31719 -68.328562) (xy 3.273796 -68.398513) (xy 3.224125 -68.464155) (xy 3.168602 -68.524927)
			(xy 3.1077 -68.580309) (xy 3.041943 -68.629827) (xy 2.971891 -68.673058) (xy 2.935224 -68.69176)
			(xy 2.921508 -68.698618) (xy 2.906268 -68.725288) (xy 2.914904 -68.850002) (xy 2.9337 -68.874386)
			(xy 2.948432 -68.879212) (xy 2.98881 -68.893214) (xy 3.066917 -68.927909) (xy 3.141338 -68.969936)
			(xy 3.211384 -69.018907) (xy 3.27641 -69.07437) (xy 3.335817 -69.135815) (xy 3.389057 -69.202674)
			(xy 3.435638 -69.274331) (xy 3.475132 -69.350126) (xy 3.507174 -69.429359) (xy 3.531469 -69.5113)
			(xy 3.547793 -69.595194) (xy 3.555995 -69.680267) (xy 3.556508 -69.723) (xy 3.556004 -69.765348)
			(xy 3.547953 -69.849662) (xy 3.531924 -69.932828) (xy 3.508063 -70.014095) (xy 3.476584 -70.092725)
			(xy 3.437773 -70.168006) (xy 3.391983 -70.239258) (xy 3.339627 -70.305834) (xy 3.281179 -70.367132)
			(xy 3.217169 -70.422597) (xy 3.148177 -70.471726) (xy 3.074827 -70.514075) (xy 2.997784 -70.549259)
			(xy 2.917745 -70.576961) (xy 2.835436 -70.596929) (xy 2.751601 -70.608982) (xy 2.667 -70.613013)
			(xy 2.582399 -70.608982) (xy 2.498564 -70.596929) (xy 2.416255 -70.576961) (xy 2.336216 -70.549259)
			(xy 2.259173 -70.514075) (xy 2.185823 -70.471726) (xy 2.116831 -70.422597) (xy 2.052821 -70.367132)
			(xy 1.994373 -70.305834) (xy 1.942017 -70.239258) (xy 1.896227 -70.168006) (xy 1.857416 -70.092725)
			(xy 1.825937 -70.014095) (xy 1.802076 -69.932828) (xy 1.786047 -69.849662) (xy 1.777996 -69.765348)
			(xy 1.777492 -69.723) (xy 1.777958 -69.681841) (xy 1.785569 -69.599877) (xy 1.800721 -69.518966)
			(xy 1.823284 -69.439802) (xy 1.853065 -69.36306) (xy 1.88981 -69.289399) (xy 1.933203 -69.219448)
			(xy 1.982874 -69.153806) (xy 2.038397 -69.093033) (xy 2.099299 -69.037651) (xy 2.165056 -68.988133)
			(xy 2.235108 -68.944903) (xy 2.271776 -68.926202) (xy 2.285492 -68.919344) (xy 2.300732 -68.892674)
			(xy 2.292096 -68.76796) (xy 2.2733 -68.743576) (xy 2.258568 -68.73875) (xy 2.216842 -68.724264) (xy 2.136229 -68.688152)
			(xy 2.059595 -68.644224) (xy 1.987695 -68.592913) (xy 1.921238 -68.534725) (xy 1.860878 -68.470234)
			(xy 1.833626 -68.435474) (xy 1.823466 -68.42252) (xy 1.792478 -68.412868) (xy 1.685798 -68.44919)
			(xy 1.675977 -68.453095) (xy 1.660401 -68.467347) (xy 1.651834 -68.486643) (xy 1.651254 -68.497196)
			(xy 1.651254 -68.700904) (xy 1.652778 -68.75145) (xy 1.651254 -68.801996) (xy 1.651254 -71.150226)
			(xy 8.859774 -71.150226) (xy 8.860277 -71.109124) (xy 8.867859 -71.02727) (xy 8.882962 -70.946465)
			(xy 8.905456 -70.867398) (xy 8.93515 -70.790744) (xy 8.97179 -70.717156) (xy 9.015063 -70.647264)
			(xy 9.0646 -70.581662) (xy 9.11998 -70.520911) (xy 9.180728 -70.465528) (xy 9.246327 -70.415988)
			(xy 9.316218 -70.372711) (xy 9.389803 -70.336068) (xy 9.466456 -70.30637) (xy 9.545522 -70.283872)
			(xy 9.626326 -70.268766) (xy 9.70818 -70.261179) (xy 9.749282 -70.260718) (xy 9.791708 -70.261199)
			(xy 9.876177 -70.269262) (xy 9.959493 -70.285335) (xy 10.040899 -70.309272) (xy 10.119655 -70.340856)
			(xy 10.195043 -70.379799) (xy 10.266378 -70.425747) (xy 10.333012 -70.478281) (xy 10.394338 -70.536925)
			(xy 10.449798 -70.601144) (xy 10.498888 -70.670355) (xy 10.541162 -70.743927) (xy 10.576234 -70.821192)
			(xy 10.603786 -70.901447) (xy 10.623566 -70.983962) (xy 10.635397 -71.067986) (xy 10.637774 -71.110348)
			(xy 10.638593 -71.119455) (xy 10.645797 -71.136247) (xy 10.658418 -71.14946) (xy 10.666476 -71.153782)
			(xy 10.703692 -71.172293) (xy 10.774859 -71.215245) (xy 10.781645 -71.22026) (xy 11.19149 -71.22026)
			(xy 11.19149 -71.135564) (xy 11.199541 -71.05125) (xy 11.21557 -70.968084) (xy 11.239431 -70.886817)
			(xy 11.27091 -70.808187) (xy 11.309721 -70.732906) (xy 11.355511 -70.661654) (xy 11.407867 -70.595078)
			(xy 11.466315 -70.53378) (xy 11.530325 -70.478315) (xy 11.599317 -70.429186) (xy 11.672667 -70.386837)
			(xy 11.74971 -70.351653) (xy 11.829749 -70.323951) (xy 11.912058 -70.303983) (xy 11.995893 -70.29193)
			(xy 12.080494 -70.2879) (xy 12.165095 -70.29193) (xy 12.24893 -70.303983) (xy 12.331239 -70.323951)
			(xy 12.411278 -70.351653) (xy 12.488321 -70.386837) (xy 12.561671 -70.429186) (xy 12.630663 -70.478315)
			(xy 12.694673 -70.53378) (xy 12.753121 -70.595078) (xy 12.805477 -70.661654) (xy 12.851267 -70.732906)
			(xy 12.890078 -70.808187) (xy 12.921557 -70.886817) (xy 12.945418 -70.968084) (xy 12.961447 -71.05125)
			(xy 12.969498 -71.135564) (xy 12.970002 -71.177912) (xy 12.969498 -71.22026) (xy 12.961447 -71.304574)
			(xy 12.945418 -71.38774) (xy 12.921557 -71.469007) (xy 12.890078 -71.547637) (xy 12.851267 -71.622918)
			(xy 12.805477 -71.69417) (xy 12.753121 -71.760746) (xy 12.694673 -71.822044) (xy 12.630663 -71.877509)
			(xy 12.561671 -71.926638) (xy 12.488321 -71.968987) (xy 12.411278 -72.004171) (xy 12.331239 -72.031873)
			(xy 12.24893 -72.051841) (xy 12.165095 -72.063894) (xy 12.080494 -72.067925) (xy 11.995893 -72.063894)
			(xy 11.912058 -72.051841) (xy 11.829749 -72.031873) (xy 11.74971 -72.004171) (xy 11.672667 -71.968987)
			(xy 11.599317 -71.926638) (xy 11.530325 -71.877509) (xy 11.466315 -71.822044) (xy 11.407867 -71.760746)
			(xy 11.355511 -71.69417) (xy 11.309721 -71.622918) (xy 11.27091 -71.547637) (xy 11.239431 -71.469007)
			(xy 11.21557 -71.38774) (xy 11.199541 -71.304574) (xy 11.19149 -71.22026) (xy 10.781645 -71.22026)
			(xy 10.841709 -71.26465) (xy 10.903657 -71.320076) (xy 10.960164 -71.381041) (xy 11.010737 -71.447011)
			(xy 11.054934 -71.517412) (xy 11.092371 -71.591629) (xy 11.122719 -71.669016) (xy 11.145716 -71.748896)
			(xy 11.161159 -71.830574) (xy 11.168914 -71.913336) (xy 11.169396 -71.954898) (xy 11.168946 -71.996001)
			(xy 11.161361 -72.077858) (xy 11.146255 -72.158665) (xy 11.123758 -72.237734) (xy 11.094062 -72.314389)
			(xy 11.057419 -72.387978) (xy 11.014142 -72.457872) (xy 10.964601 -72.523474) (xy 10.909218 -72.584225)
			(xy 10.848466 -72.639607) (xy 10.782863 -72.689148) (xy 10.712969 -72.732424) (xy 10.63938 -72.769066)
			(xy 10.562724 -72.798762) (xy 10.483655 -72.821258) (xy 10.402848 -72.836362) (xy 10.320991 -72.843946)
			(xy 10.279888 -72.844406) (xy 10.237462 -72.843921) (xy 10.152993 -72.835858) (xy 10.069677 -72.819785)
			(xy 9.988272 -72.795848) (xy 9.909516 -72.764264) (xy 9.834128 -72.725322) (xy 9.762793 -72.679374)
			(xy 9.696159 -72.62684) (xy 9.634833 -72.568197) (xy 9.579373 -72.503978) (xy 9.530283 -72.434767)
			(xy 9.488009 -72.361195) (xy 9.452937 -72.283931) (xy 9.425385 -72.203676) (xy 9.405604 -72.121162)
			(xy 9.393774 -72.037138) (xy 9.391396 -71.994776) (xy 9.390592 -71.985668) (xy 9.383375 -71.968879)
			(xy 9.370751 -71.955666) (xy 9.362694 -71.951342) (xy 9.325481 -71.932827) (xy 9.254314 -71.889873)
			(xy 9.187466 -71.840468) (xy 9.125518 -71.785042) (xy 9.069012 -71.724078) (xy 9.018439 -71.658108)
			(xy 8.974242 -71.587707) (xy 8.936805 -71.513491) (xy 8.906456 -71.436105) (xy 8.883459 -71.356226)
			(xy 8.868014 -71.274549) (xy 8.860257 -71.191788) (xy 8.859774 -71.150226) (xy 1.651254 -71.150226)
			(xy 1.651254 -72.136) (xy 2.107188 -72.136) (xy 2.111218 -72.051399) (xy 2.123271 -71.967564) (xy 2.143239 -71.885255)
			(xy 2.170941 -71.805216) (xy 2.206125 -71.728173) (xy 2.248474 -71.654823) (xy 2.297603 -71.585831)
			(xy 2.353068 -71.521821) (xy 2.414366 -71.463373) (xy 2.480942 -71.411017) (xy 2.552194 -71.365227)
			(xy 2.627475 -71.326416) (xy 2.706105 -71.294937) (xy 2.787372 -71.271076) (xy 2.870538 -71.255047)
			(xy 2.954852 -71.246996) (xy 2.9972 -71.246492) (xy 3.038245 -71.246968) (xy 3.119985 -71.254538)
			(xy 3.200679 -71.269606) (xy 3.279643 -71.292046) (xy 3.356202 -71.321665) (xy 3.429708 -71.358212)
			(xy 3.499533 -71.401376) (xy 3.565084 -71.45079) (xy 3.625804 -71.506033) (xy 3.681176 -71.566636)
			(xy 3.730728 -71.632083) (xy 3.77404 -71.701816) (xy 3.810743 -71.775244) (xy 3.840524 -71.851741)
			(xy 3.863131 -71.930656) (xy 3.871214 -71.9709) (xy 3.873754 -71.984362) (xy 3.89128 -72.004682)
			(xy 4.0005 -72.042782) (xy 4.026916 -72.037956) (xy 4.037584 -72.028812) (xy 4.067847 -72.003247)
			(xy 4.132161 -71.956983) (xy 4.200336 -71.916624) (xy 4.271832 -71.88249) (xy 4.346081 -71.854852)
			(xy 4.422494 -71.83393) (xy 4.500466 -71.819888) (xy 4.579377 -71.812839) (xy 4.61899 -71.812404)
			(xy 4.665386 -71.812989) (xy 4.757674 -71.822634) (xy 4.848458 -71.841829) (xy 4.936751 -71.870366)
			(xy 4.979416 -71.888604) (xy 4.989356 -71.892424) (xy 5.010624 -71.892424) (xy 5.020564 -71.888604)
			(xy 5.063228 -71.870363) (xy 5.15152 -71.841818) (xy 5.242304 -71.822624) (xy 5.334594 -71.812989)
			(xy 5.38099 -71.812404) (xy 5.427386 -71.812989) (xy 5.519674 -71.822634) (xy 5.610458 -71.841829)
			(xy 5.698751 -71.870366) (xy 5.741416 -71.888604) (xy 5.751356 -71.892424) (xy 5.772624 -71.892424)
			(xy 5.782564 -71.888604) (xy 5.825228 -71.870363) (xy 5.91352 -71.841818) (xy 6.004304 -71.822624)
			(xy 6.096594 -71.812989) (xy 6.14299 -71.812404) (xy 6.189386 -71.812989) (xy 6.281674 -71.822634)
			(xy 6.372458 -71.841829) (xy 6.460751 -71.870366) (xy 6.503416 -71.888604) (xy 6.513356 -71.892424)
			(xy 6.534624 -71.892424) (xy 6.544564 -71.888604) (xy 6.587228 -71.870363) (xy 6.67552 -71.841818)
			(xy 6.766304 -71.822624) (xy 6.858594 -71.812989) (xy 6.90499 -71.812404) (xy 6.946093 -71.812862)
			(xy 7.027949 -71.820447) (xy 7.108756 -71.835553) (xy 7.187824 -71.85805) (xy 7.264479 -71.887746)
			(xy 7.338067 -71.924389) (xy 7.407961 -71.967665) (xy 7.473563 -72.017205) (xy 7.534314 -72.072587)
			(xy 7.589696 -72.133339) (xy 7.639236 -72.198941) (xy 7.682512 -72.268834) (xy 7.719155 -72.342423)
			(xy 7.748851 -72.419078) (xy 7.771348 -72.498146) (xy 7.786453 -72.578953) (xy 7.794038 -72.660809)
			(xy 7.794498 -72.701912) (xy 7.79392 -72.748308) (xy 7.784274 -72.840596) (xy 7.765076 -72.93138)
			(xy 7.762177 -72.940348) (xy 15.493996 -72.940348) (xy 15.493996 -72.855652) (xy 15.502047 -72.771338)
			(xy 15.518076 -72.688172) (xy 15.541937 -72.606905) (xy 15.573416 -72.528275) (xy 15.612227 -72.452994)
			(xy 15.658017 -72.381742) (xy 15.710373 -72.315166) (xy 15.768821 -72.253868) (xy 15.832831 -72.198403)
			(xy 15.901823 -72.149274) (xy 15.975173 -72.106925) (xy 16.052216 -72.071741) (xy 16.132255 -72.044039)
			(xy 16.214564 -72.024071) (xy 16.298399 -72.012018) (xy 16.383 -72.007988) (xy 16.467601 -72.012018)
			(xy 16.551436 -72.024071) (xy 16.633745 -72.044039) (xy 16.713784 -72.071741) (xy 16.790827 -72.106925)
			(xy 16.813789 -72.120182) (xy 17.525996 -72.120182) (xy 17.525996 -72.035486) (xy 17.534047 -71.951172)
			(xy 17.550076 -71.868006) (xy 17.573937 -71.786739) (xy 17.605416 -71.708109) (xy 17.644227 -71.632828)
			(xy 17.690017 -71.561576) (xy 17.742373 -71.495) (xy 17.800821 -71.433702) (xy 17.864831 -71.378237)
			(xy 17.933823 -71.329108) (xy 18.007173 -71.286759) (xy 18.084216 -71.251575) (xy 18.164255 -71.223873)
			(xy 18.246564 -71.203905) (xy 18.330399 -71.191852) (xy 18.415 -71.187822) (xy 18.499601 -71.191852)
			(xy 18.583436 -71.203905) (xy 18.665745 -71.223873) (xy 18.745784 -71.251575) (xy 18.822827 -71.286759)
			(xy 18.896177 -71.329108) (xy 18.965169 -71.378237) (xy 19.029179 -71.433702) (xy 19.087627 -71.495)
			(xy 19.139983 -71.561576) (xy 19.185773 -71.632828) (xy 19.224584 -71.708109) (xy 19.256063 -71.786739)
			(xy 19.279924 -71.868006) (xy 19.295953 -71.951172) (xy 19.304004 -72.035486) (xy 19.304508 -72.077834)
			(xy 19.304004 -72.120182) (xy 19.295953 -72.204496) (xy 19.279924 -72.287662) (xy 19.256063 -72.368929)
			(xy 19.224584 -72.447559) (xy 19.185773 -72.52284) (xy 19.139983 -72.594092) (xy 19.087627 -72.660668)
			(xy 19.029179 -72.721966) (xy 18.965169 -72.777431) (xy 18.896177 -72.82656) (xy 18.822827 -72.868909)
			(xy 18.745784 -72.904093) (xy 18.665745 -72.931795) (xy 18.583436 -72.951763) (xy 18.499601 -72.963816)
			(xy 18.415 -72.967847) (xy 18.330399 -72.963816) (xy 18.246564 -72.951763) (xy 18.164255 -72.931795)
			(xy 18.084216 -72.904093) (xy 18.007173 -72.868909) (xy 17.933823 -72.82656) (xy 17.864831 -72.777431)
			(xy 17.800821 -72.721966) (xy 17.742373 -72.660668) (xy 17.690017 -72.594092) (xy 17.644227 -72.52284)
			(xy 17.605416 -72.447559) (xy 17.573937 -72.368929) (xy 17.550076 -72.287662) (xy 17.534047 -72.204496)
			(xy 17.525996 -72.120182) (xy 16.813789 -72.120182) (xy 16.864177 -72.149274) (xy 16.933169 -72.198403)
			(xy 16.997179 -72.253868) (xy 17.055627 -72.315166) (xy 17.107983 -72.381742) (xy 17.153773 -72.452994)
			(xy 17.192584 -72.528275) (xy 17.224063 -72.606905) (xy 17.247924 -72.688172) (xy 17.263953 -72.771338)
			(xy 17.272004 -72.855652) (xy 17.272508 -72.898) (xy 17.272004 -72.940348) (xy 17.263953 -73.024662)
			(xy 17.247924 -73.107828) (xy 17.224063 -73.189095) (xy 17.192584 -73.267725) (xy 17.153773 -73.343006)
			(xy 17.107983 -73.414258) (xy 17.068935 -73.463912) (xy 31.49092 -73.463912) (xy 31.491505 -73.417516)
			(xy 31.501149 -73.325228) (xy 31.520344 -73.234444) (xy 31.548882 -73.146151) (xy 31.56712 -73.103486)
			(xy 31.570933 -73.093544) (xy 31.570937 -73.072278) (xy 31.56712 -73.062338) (xy 31.548881 -73.019673)
			(xy 31.520335 -72.931382) (xy 31.50114 -72.840598) (xy 31.491506 -72.748308) (xy 31.49092 -72.701912)
			(xy 31.491364 -72.660808) (xy 31.498948 -72.578951) (xy 31.514053 -72.498143) (xy 31.53655 -72.419074)
			(xy 31.566246 -72.342417) (xy 31.602889 -72.268828) (xy 31.646166 -72.198934) (xy 31.695708 -72.133331)
			(xy 31.751091 -72.07258) (xy 31.811844 -72.017197) (xy 31.877447 -71.967657) (xy 31.947342 -71.924381)
			(xy 32.020932 -71.88774) (xy 32.097589 -71.858044) (xy 32.176659 -71.835549) (xy 32.257467 -71.820446)
			(xy 32.339324 -71.812863) (xy 32.380428 -71.812404) (xy 32.426823 -71.813011) (xy 32.519111 -71.822649)
			(xy 32.609894 -71.841838) (xy 32.698189 -71.870369) (xy 32.740854 -71.888604) (xy 32.750794 -71.892424)
			(xy 32.772062 -71.892424) (xy 32.782002 -71.888604) (xy 32.824661 -71.870351) (xy 32.912954 -71.841809)
			(xy 33.00374 -71.822618) (xy 33.096032 -71.812987) (xy 33.142428 -71.812404) (xy 33.188823 -71.813011)
			(xy 33.281111 -71.822649) (xy 33.371894 -71.841838) (xy 33.460189 -71.870369) (xy 33.502854 -71.888604)
			(xy 33.512794 -71.892424) (xy 33.534062 -71.892424) (xy 33.544002 -71.888604) (xy 33.586661 -71.870351)
			(xy 33.674954 -71.841809) (xy 33.76574 -71.822618) (xy 33.858032 -71.812987) (xy 33.904428 -71.812404)
			(xy 33.950823 -71.813011) (xy 34.043111 -71.822649) (xy 34.133894 -71.841838) (xy 34.222189 -71.870369)
			(xy 34.264854 -71.888604) (xy 34.274794 -71.892424) (xy 34.296062 -71.892424) (xy 34.306002 -71.888604)
			(xy 34.348661 -71.870351) (xy 34.436954 -71.841809) (xy 34.52774 -71.822618) (xy 34.620032 -71.812987)
			(xy 34.666428 -71.812404) (xy 34.707531 -71.81284) (xy 34.789387 -71.820427) (xy 34.870193 -71.835535)
			(xy 34.949261 -71.858034) (xy 35.025916 -71.887733) (xy 35.099503 -71.924378) (xy 35.169396 -71.967656)
			(xy 35.234997 -72.017198) (xy 35.295747 -72.072581) (xy 35.351128 -72.133334) (xy 35.400667 -72.198937)
			(xy 35.443942 -72.268832) (xy 35.480583 -72.342421) (xy 35.510278 -72.419077) (xy 35.532774 -72.498145)
			(xy 35.547878 -72.578953) (xy 35.555462 -72.660809) (xy 35.555936 -72.701912) (xy 35.555355 -72.748308)
			(xy 35.545709 -72.840596) (xy 35.526512 -72.93138) (xy 35.497974 -73.019673) (xy 35.479736 -73.062338)
			(xy 35.475911 -73.072276) (xy 35.475916 -73.093546) (xy 35.479736 -73.103486) (xy 35.497986 -73.146146)
			(xy 35.526529 -73.234439) (xy 35.54572 -73.325225) (xy 35.555352 -73.417516) (xy 35.555936 -73.463912)
			(xy 35.555445 -73.505014) (xy 35.547859 -73.586867) (xy 35.532754 -73.667671) (xy 35.510257 -73.746736)
			(xy 35.480561 -73.823389) (xy 35.44392 -73.896975) (xy 35.400645 -73.966866) (xy 35.351107 -74.032466)
			(xy 35.295727 -74.093216) (xy 35.234978 -74.148597) (xy 35.169379 -74.198136) (xy 35.099489 -74.241412)
			(xy 35.025904 -74.278055) (xy 34.949252 -74.307752) (xy 34.870186 -74.33025) (xy 34.789383 -74.345357)
			(xy 34.70753 -74.352944) (xy 34.666428 -74.35342) (xy 34.620033 -74.352826) (xy 34.527745 -74.343184)
			(xy 34.436961 -74.323991) (xy 34.348667 -74.295456) (xy 34.306002 -74.27722) (xy 34.296062 -74.2734)
			(xy 34.274794 -74.2734) (xy 34.264854 -74.27722) (xy 34.222188 -74.295456) (xy 34.133897 -74.324002)
			(xy 34.043113 -74.343198) (xy 33.950824 -74.352834) (xy 33.904428 -74.35342) (xy 33.858033 -74.352826)
			(xy 33.765745 -74.343184) (xy 33.674961 -74.323991) (xy 33.586667 -74.295456) (xy 33.544002 -74.27722)
			(xy 33.534062 -74.2734) (xy 33.512794 -74.2734) (xy 33.502854 -74.27722) (xy 33.460188 -74.295456)
			(xy 33.371897 -74.324002) (xy 33.281113 -74.343198) (xy 33.188824 -74.352834) (xy 33.142428 -74.35342)
			(xy 33.096033 -74.352826) (xy 33.003745 -74.343184) (xy 32.912961 -74.323991) (xy 32.824667 -74.295456)
			(xy 32.782002 -74.27722) (xy 32.772062 -74.2734) (xy 32.750794 -74.2734) (xy 32.740854 -74.27722)
			(xy 32.698188 -74.295456) (xy 32.609897 -74.324002) (xy 32.519113 -74.343198) (xy 32.426824 -74.352834)
			(xy 32.380428 -74.35342) (xy 32.339326 -74.352921) (xy 32.257471 -74.345339) (xy 32.176666 -74.330236)
			(xy 32.097599 -74.307742) (xy 32.020944 -74.278048) (xy 31.947357 -74.241408) (xy 31.877464 -74.198135)
			(xy 31.811862 -74.148597) (xy 31.751111 -74.093218) (xy 31.695728 -74.032469) (xy 31.646188 -73.966869)
			(xy 31.602911 -73.896978) (xy 31.566268 -73.823392) (xy 31.536571 -73.746739) (xy 31.514073 -73.667673)
			(xy 31.498967 -73.586868) (xy 31.491381 -73.505014) (xy 31.49092 -73.463912) (xy 17.068935 -73.463912)
			(xy 17.055627 -73.480834) (xy 16.997179 -73.542132) (xy 16.933169 -73.597597) (xy 16.864177 -73.646726)
			(xy 16.790827 -73.689075) (xy 16.713784 -73.724259) (xy 16.633745 -73.751961) (xy 16.551436 -73.771929)
			(xy 16.467601 -73.783982) (xy 16.383 -73.788013) (xy 16.298399 -73.783982) (xy 16.214564 -73.771929)
			(xy 16.132255 -73.751961) (xy 16.052216 -73.724259) (xy 15.975173 -73.689075) (xy 15.901823 -73.646726)
			(xy 15.832831 -73.597597) (xy 15.768821 -73.542132) (xy 15.710373 -73.480834) (xy 15.658017 -73.414258)
			(xy 15.612227 -73.343006) (xy 15.573416 -73.267725) (xy 15.541937 -73.189095) (xy 15.518076 -73.107828)
			(xy 15.502047 -73.024662) (xy 15.493996 -72.940348) (xy 7.762177 -72.940348) (xy 7.736537 -73.019673)
			(xy 7.718298 -73.062338) (xy 7.714386 -73.072258) (xy 7.714391 -73.093564) (xy 7.718298 -73.103486)
			(xy 7.736546 -73.146147) (xy 7.765089 -73.23444) (xy 7.784282 -73.325225) (xy 7.793914 -73.417516)
			(xy 7.794498 -73.463912) (xy 7.794045 -73.505015) (xy 7.786459 -73.58687) (xy 7.771352 -73.667676)
			(xy 7.748855 -73.746744) (xy 7.719157 -73.823398) (xy 7.682514 -73.896985) (xy 7.639237 -73.966878)
			(xy 7.589696 -74.032479) (xy 7.534314 -74.093229) (xy 7.473562 -74.14861) (xy 7.40796 -74.19815)
			(xy 7.338066 -74.241425) (xy 7.264478 -74.278066) (xy 7.187823 -74.307762) (xy 7.108755 -74.330257)
			(xy 7.027948 -74.345362) (xy 6.946093 -74.352946) (xy 6.90499 -74.35342) (xy 6.858594 -74.35284)
			(xy 6.766306 -74.343194) (xy 6.675522 -74.323997) (xy 6.587229 -74.295458) (xy 6.544564 -74.27722)
			(xy 6.534624 -74.2734) (xy 6.513356 -74.2734) (xy 6.503416 -74.27722) (xy 6.460755 -74.295469) (xy 6.372462 -74.324012)
			(xy 6.281677 -74.343204) (xy 6.189386 -74.352836) (xy 6.14299 -74.35342) (xy 6.096594 -74.35284)
			(xy 6.004306 -74.343194) (xy 5.913522 -74.323997) (xy 5.825229 -74.295458) (xy 5.782564 -74.27722)
			(xy 5.772624 -74.2734) (xy 5.751356 -74.2734) (xy 5.741416 -74.27722) (xy 5.698755 -74.295469) (xy 5.610462 -74.324012)
			(xy 5.519677 -74.343204) (xy 5.427386 -74.352836) (xy 5.38099 -74.35342) (xy 5.334594 -74.35284)
			(xy 5.242306 -74.343194) (xy 5.151522 -74.323997) (xy 5.063229 -74.295458) (xy 5.020564 -74.27722)
			(xy 5.010624 -74.2734) (xy 4.989356 -74.2734) (xy 4.979416 -74.27722) (xy 4.936755 -74.295469) (xy 4.848462 -74.324012)
			(xy 4.757677 -74.343204) (xy 4.665386 -74.352836) (xy 4.61899 -74.35342) (xy 4.577888 -74.352943)
			(xy 4.496033 -74.345358) (xy 4.415228 -74.330253) (xy 4.336161 -74.307757) (xy 4.259508 -74.278061)
			(xy 4.185921 -74.241419) (xy 4.116029 -74.198144) (xy 4.050428 -74.148605) (xy 3.989678 -74.093224)
			(xy 3.934297 -74.032474) (xy 3.884757 -73.966873) (xy 3.841482 -73.896981) (xy 3.80484 -73.823394)
			(xy 3.775144 -73.74674) (xy 3.752647 -73.667674) (xy 3.737542 -73.586869) (xy 3.729957 -73.505014)
			(xy 3.729482 -73.463912) (xy 3.73007 -73.417517) (xy 3.739714 -73.325228) (xy 3.758908 -73.234445)
			(xy 3.787445 -73.146151) (xy 3.805682 -73.103486) (xy 3.80958 -73.093562) (xy 3.809585 -73.07226)
			(xy 3.805682 -73.062338) (xy 3.785605 -73.015164) (xy 3.755172 -72.917257) (xy 3.744976 -72.867012)
			(xy 3.742436 -72.85355) (xy 3.72491 -72.83323) (xy 3.61569 -72.79513) (xy 3.589274 -72.799956) (xy 3.578606 -72.8091)
			(xy 3.548349 -72.834671) (xy 3.484033 -72.880935) (xy 3.415857 -72.921293) (xy 3.344361 -72.955426)
			(xy 3.270111 -72.983063) (xy 3.193697 -73.003985) (xy 3.115725 -73.018025) (xy 3.036813 -73.025074)
			(xy 2.9972 -73.025508) (xy 2.954852 -73.025004) (xy 2.870538 -73.016953) (xy 2.787372 -73.000924)
			(xy 2.706105 -72.977063) (xy 2.627475 -72.945584) (xy 2.552194 -72.906773) (xy 2.480942 -72.860983)
			(xy 2.414366 -72.808627) (xy 2.353068 -72.750179) (xy 2.297603 -72.686169) (xy 2.248474 -72.617177)
			(xy 2.206125 -72.543827) (xy 2.170941 -72.466784) (xy 2.143239 -72.386745) (xy 2.123271 -72.304436)
			(xy 2.111218 -72.220601) (xy 2.107188 -72.136) (xy 1.651254 -72.136) (xy 1.651254 -73.780904) (xy 1.652778 -73.83145)
			(xy 1.651254 -73.881996) (xy 1.651254 -76.63891) (xy 8.55498 -76.63891) (xy 8.55901 -76.554309) (xy 8.571063 -76.470474)
			(xy 8.591031 -76.388165) (xy 8.618733 -76.308127) (xy 8.653917 -76.231084) (xy 8.696266 -76.157734)
			(xy 8.745394 -76.088742) (xy 8.800859 -76.024732) (xy 8.862157 -75.966285) (xy 8.928733 -75.913929)
			(xy 8.999985 -75.868138) (xy 9.075266 -75.829328) (xy 9.153896 -75.797849) (xy 9.235162 -75.773988)
			(xy 9.318328 -75.757959) (xy 9.402642 -75.749908) (xy 9.44499 -75.749404) (xy 9.487154 -75.75042)
			(xy 9.50214 -75.751182) (xy 9.52754 -75.736704) (xy 9.58469 -75.629262) (xy 9.582404 -75.600306)
			(xy 9.573514 -75.588368) (xy 9.549585 -75.555464) (xy 9.507152 -75.486041) (xy 9.471239 -75.413031)
			(xy 9.442147 -75.337046) (xy 9.42012 -75.25872) (xy 9.405341 -75.178709) (xy 9.397934 -75.097682)
			(xy 9.397492 -75.057) (xy 9.397996 -75.014652) (xy 9.406047 -74.930338) (xy 9.422076 -74.847172)
			(xy 9.445937 -74.765905) (xy 9.477416 -74.687275) (xy 9.516227 -74.611994) (xy 9.562017 -74.540742)
			(xy 9.614373 -74.474166) (xy 9.672821 -74.412868) (xy 9.736831 -74.357403) (xy 9.805823 -74.308274)
			(xy 9.879173 -74.265925) (xy 9.956216 -74.230741) (xy 10.036255 -74.203039) (xy 10.118564 -74.183071)
			(xy 10.202399 -74.171018) (xy 10.287 -74.166988) (xy 10.371601 -74.171018) (xy 10.455436 -74.183071)
			(xy 10.537745 -74.203039) (xy 10.617784 -74.230741) (xy 10.694827 -74.265925) (xy 10.768177 -74.308274)
			(xy 10.837169 -74.357403) (xy 10.901179 -74.412868) (xy 10.959627 -74.474166) (xy 11.011983 -74.540742)
			(xy 11.057773 -74.611994) (xy 11.096584 -74.687275) (xy 11.128063 -74.765905) (xy 11.151924 -74.847172)
			(xy 11.167953 -74.930338) (xy 11.176004 -75.014652) (xy 11.176508 -75.057) (xy 11.175996 -75.100784)
			(xy 11.167385 -75.187928) (xy 11.150257 -75.273804) (xy 11.124777 -75.357583) (xy 11.091191 -75.438455)
			(xy 11.049825 -75.515636) (xy 11.025886 -75.5523) (xy 11.01725 -75.565) (xy 11.01725 -75.595988)
			(xy 11.086338 -75.69962) (xy 11.114786 -75.711558) (xy 11.130026 -75.70851) (xy 11.172827 -75.700556)
			(xy 11.25947 -75.692033) (xy 11.303 -75.691492) (xy 11.345348 -75.691996) (xy 11.429662 -75.700047)
			(xy 11.512828 -75.716076) (xy 11.594095 -75.739937) (xy 11.672725 -75.771416) (xy 11.748006 -75.810227)
			(xy 11.772724 -75.826112) (xy 12.318492 -75.826112) (xy 12.31905 -75.784718) (xy 12.326751 -75.702289)
			(xy 12.342077 -75.620933) (xy 12.364897 -75.541352) (xy 12.395012 -75.464236) (xy 12.432162 -75.390252)
			(xy 12.476026 -75.32004) (xy 12.526225 -75.254207) (xy 12.582323 -75.193323) (xy 12.643835 -75.137916)
			(xy 12.71023 -75.088463) (xy 12.780933 -75.045394) (xy 12.855331 -75.00908) (xy 12.932782 -74.979837)
			(xy 13.012615 -74.957917) (xy 13.09414 -74.943509) (xy 13.135356 -74.939652) (xy 13.147849 -74.938011)
			(xy 13.169028 -74.924409) (xy 13.175742 -74.913744) (xy 13.197191 -74.876676) (xy 13.246113 -74.806378)
			(xy 13.301565 -74.741108) (xy 13.363034 -74.68147) (xy 13.429952 -74.628017) (xy 13.501697 -74.581243)
			(xy 13.577606 -74.541583) (xy 13.656976 -74.509403) (xy 13.739072 -74.485001) (xy 13.823133 -74.468603)
			(xy 13.908381 -74.460361) (xy 13.951204 -74.459846) (xy 13.994751 -74.460367) (xy 14.081429 -74.468882)
			(xy 14.166858 -74.48583) (xy 14.250222 -74.511049) (xy 14.330721 -74.544297) (xy 14.407583 -74.585256)
			(xy 14.480073 -74.633533) (xy 14.547497 -74.688665) (xy 14.609207 -74.750125) (xy 14.664613 -74.817324)
			(xy 14.713184 -74.889617) (xy 14.734286 -74.927714) (xy 14.740092 -74.937263) (xy 14.75801 -74.950573)
			(xy 14.76883 -74.953368) (xy 14.810208 -74.962502) (xy 14.89115 -74.987596) (xy 14.96934 -75.020271)
			(xy 15.04407 -75.06023) (xy 15.114663 -75.107112) (xy 15.180479 -75.160493) (xy 15.211044 -75.189842)
			(xy 15.218364 -75.196472) (xy 15.236605 -75.203998) (xy 15.256338 -75.204048) (xy 15.265654 -75.200764)
			(xy 15.305635 -75.185073) (xy 15.387946 -75.160528) (xy 15.472241 -75.144036) (xy 15.557734 -75.135751)
			(xy 15.60068 -75.135232) (xy 15.642332 -75.135702) (xy 15.725272 -75.143461) (xy 15.766288 -75.150726)
			(xy 15.777804 -75.152318) (xy 15.800176 -75.146099) (xy 15.809214 -75.138788) (xy 15.839684 -75.112469)
			(xy 15.904584 -75.064809) (xy 15.973527 -75.023212) (xy 16.045949 -74.988018) (xy 16.121256 -74.959517)
			(xy 16.198832 -74.937941) (xy 16.278041 -74.923467) (xy 16.358234 -74.916213) (xy 16.398494 -74.915776)
			(xy 16.440843 -74.916272) (xy 16.525156 -74.924323) (xy 16.608323 -74.940352) (xy 16.689589 -74.964215)
			(xy 16.768219 -74.995694) (xy 16.843501 -75.034504) (xy 16.914752 -75.080295) (xy 16.981329 -75.132652)
			(xy 17.042627 -75.1911) (xy 17.098091 -75.25511) (xy 17.14722 -75.324102) (xy 17.189569 -75.397452)
			(xy 17.224753 -75.474495) (xy 17.252455 -75.554534) (xy 17.272423 -75.636844) (xy 17.284476 -75.720679)
			(xy 17.288507 -75.80528) (xy 17.284476 -75.889881) (xy 17.272423 -75.973716) (xy 17.252455 -76.056026)
			(xy 17.224753 -76.136065) (xy 17.189569 -76.213108) (xy 17.14722 -76.286458) (xy 17.098091 -76.35545)
			(xy 17.042627 -76.41946) (xy 16.981329 -76.477908) (xy 16.914752 -76.530265) (xy 16.843501 -76.576056)
			(xy 16.768219 -76.614866) (xy 16.689589 -76.646345) (xy 16.608323 -76.670208) (xy 16.525156 -76.686237)
			(xy 16.440843 -76.694288) (xy 16.398494 -76.694792) (xy 16.356842 -76.694325) (xy 16.273902 -76.686564)
			(xy 16.232886 -76.679298) (xy 16.221371 -76.677683) (xy 16.198996 -76.683917) (xy 16.18996 -76.691236)
			(xy 16.159505 -76.717572) (xy 16.114869 -76.750348) (xy 17.320002 -76.750348) (xy 17.320002 -76.665652)
			(xy 17.328053 -76.581338) (xy 17.344082 -76.498172) (xy 17.367943 -76.416905) (xy 17.399422 -76.338275)
			(xy 17.438233 -76.262994) (xy 17.484023 -76.191742) (xy 17.536379 -76.125166) (xy 17.594827 -76.063868)
			(xy 17.658837 -76.008403) (xy 17.727829 -75.959274) (xy 17.801179 -75.916925) (xy 17.878222 -75.881741)
			(xy 17.958261 -75.854039) (xy 18.04057 -75.834071) (xy 18.124405 -75.822018) (xy 18.209006 -75.817988)
			(xy 18.293607 -75.822018) (xy 18.377442 -75.834071) (xy 18.459751 -75.854039) (xy 18.53979 -75.881741)
			(xy 18.616833 -75.916925) (xy 18.690183 -75.959274) (xy 18.759175 -76.008403) (xy 18.823185 -76.063868)
			(xy 18.881633 -76.125166) (xy 18.933989 -76.191742) (xy 18.979779 -76.262994) (xy 19.01859 -76.338275)
			(xy 19.050069 -76.416905) (xy 19.07393 -76.498172) (xy 19.089959 -76.581338) (xy 19.095457 -76.638912)
			(xy 36.31692 -76.638912) (xy 36.317491 -76.596051) (xy 36.325753 -76.510729) (xy 36.342181 -76.426597)
			(xy 36.366624 -76.344434) (xy 36.398855 -76.265003) (xy 36.438575 -76.18904) (xy 36.485417 -76.117248)
			(xy 36.538945 -76.050294) (xy 36.598664 -75.988797) (xy 36.66402 -75.933329) (xy 36.734407 -75.884403)
			(xy 36.809173 -75.842472) (xy 36.887625 -75.807926) (xy 36.969035 -75.781084) (xy 37.05265 -75.762196)
			(xy 37.137693 -75.751436) (xy 37.18052 -75.749658) (xy 37.194744 -75.749404) (xy 37.21862 -75.73391)
			(xy 37.270182 -75.62723) (xy 37.267642 -75.599036) (xy 37.259006 -75.587606) (xy 37.23515 -75.554733)
			(xy 37.192856 -75.485382) (xy 37.15706 -75.412466) (xy 37.128058 -75.33659) (xy 37.106093 -75.258386)
			(xy 37.091348 -75.178506) (xy 37.083944 -75.097615) (xy 37.083492 -75.057) (xy 37.083967 -75.015898)
			(xy 37.091552 -74.934043) (xy 37.106657 -74.853238) (xy 37.129153 -74.774171) (xy 37.158849 -74.697517)
			(xy 37.195491 -74.62393) (xy 37.238766 -74.554038) (xy 37.288306 -74.488437) (xy 37.343687 -74.427687)
			(xy 37.404437 -74.372306) (xy 37.470038 -74.322766) (xy 37.53993 -74.279491) (xy 37.613517 -74.242849)
			(xy 37.690171 -74.213153) (xy 37.769238 -74.190657) (xy 37.850043 -74.175552) (xy 37.931898 -74.167967)
			(xy 37.973 -74.167492) (xy 38.015247 -74.167954) (xy 38.099361 -74.175967) (xy 38.182336 -74.191921)
			(xy 38.263423 -74.215672) (xy 38.341893 -74.247006) (xy 38.417037 -74.285641) (xy 38.488179 -74.331228)
			(xy 38.554677 -74.383356) (xy 38.585648 -74.412094) (xy 38.59397 -74.419324) (xy 38.614768 -74.426568)
			(xy 38.62578 -74.426064) (xy 38.647945 -74.423955) (xy 38.692416 -74.421666) (xy 38.71468 -74.421492)
			(xy 38.755783 -74.421971) (xy 38.837638 -74.429554) (xy 38.918444 -74.444658) (xy 38.997512 -74.467153)
			(xy 39.074167 -74.496848) (xy 39.147755 -74.533489) (xy 39.217648 -74.576764) (xy 39.283251 -74.626303)
			(xy 39.344002 -74.681684) (xy 39.399384 -74.742434) (xy 39.448925 -74.808035) (xy 39.492201 -74.877927)
			(xy 39.528844 -74.951515) (xy 39.55854 -75.028169) (xy 39.581037 -75.107236) (xy 39.596143 -75.188042)
			(xy 39.603728 -75.269897) (xy 39.604188 -75.311) (xy 39.603754 -75.352177) (xy 39.596141 -75.43418)
			(xy 39.580982 -75.515127) (xy 39.558405 -75.594327) (xy 39.528604 -75.671101) (xy 39.491834 -75.744791)
			(xy 39.44841 -75.814767) (xy 39.445206 -75.819) (xy 39.750492 -75.819) (xy 39.750967 -75.777898)
			(xy 39.758552 -75.696043) (xy 39.773657 -75.615238) (xy 39.796153 -75.536171) (xy 39.825849 -75.459517)
			(xy 39.862491 -75.38593) (xy 39.905766 -75.316038) (xy 39.955306 -75.250437) (xy 40.010687 -75.189687)
			(xy 40.071437 -75.134306) (xy 40.137038 -75.084766) (xy 40.20693 -75.041491) (xy 40.280517 -75.004849)
			(xy 40.357171 -74.975153) (xy 40.436238 -74.952657) (xy 40.517043 -74.937552) (xy 40.598898 -74.929967)
			(xy 40.64 -74.929492) (xy 40.680194 -74.929951) (xy 40.760256 -74.937185) (xy 40.83934 -74.951611)
			(xy 40.916799 -74.973112) (xy 40.992003 -75.001513) (xy 41.028366 -75.018646) (xy 41.038214 -75.022958)
			(xy 41.059687 -75.023621) (xy 41.079553 -75.015441) (xy 41.087294 -75.007978) (xy 41.116515 -74.978024)
			(xy 41.179699 -74.92315) (xy 41.247756 -74.874451) (xy 41.320085 -74.832356) (xy 41.396046 -74.797237)
			(xy 41.474969 -74.769405) (xy 41.556156 -74.749106) (xy 41.63889 -74.736519) (xy 41.680638 -74.733658)
			(xy 41.691441 -74.732468) (xy 41.71065 -74.722351) (xy 41.717722 -74.7141) (xy 41.742944 -74.682648)
			(xy 41.79822 -74.623953) (xy 41.85858 -74.570499) (xy 41.923529 -74.522725) (xy 41.992533 -74.481024)
			(xy 42.065028 -74.445737) (xy 42.140418 -74.417153) (xy 42.218084 -74.395508) (xy 42.297391 -74.380978)
			(xy 42.377687 -74.373684) (xy 42.418 -74.373232) (xy 42.460944 -74.373761) (xy 42.546434 -74.382022)
			(xy 42.630729 -74.398486) (xy 42.713044 -74.423) (xy 42.792613 -74.455335) (xy 42.868694 -74.495191)
			(xy 42.940578 -74.542195) (xy 43.007596 -74.595911) (xy 43.069123 -74.655837) (xy 43.124586 -74.721416)
			(xy 43.173469 -74.792036) (xy 43.215316 -74.867039) (xy 43.249737 -74.945728) (xy 43.263566 -74.986388)
			(xy 43.267219 -74.995991) (xy 43.280789 -75.011397) (xy 43.299306 -75.020263) (xy 43.30954 -75.021186)
			(xy 43.34839 -75.023304) (xy 43.425536 -75.033452) (xy 43.501501 -75.0503) (xy 43.575704 -75.07372)
			(xy 43.6118 -75.088242) (xy 43.623749 -75.09247) (xy 43.648936 -75.089935) (xy 43.659806 -75.083416)
			(xy 43.696719 -75.058969) (xy 43.774522 -75.016706) (xy 43.85614 -74.982383) (xy 43.940764 -74.956339)
			(xy 44.027558 -74.938834) (xy 44.115661 -74.930039) (xy 44.159932 -74.929492) (xy 44.20228 -74.929997)
			(xy 44.286591 -74.938051) (xy 44.369755 -74.954082) (xy 44.451018 -74.977946) (xy 44.529646 -75.009426)
			(xy 44.604925 -75.048237) (xy 44.676174 -75.094028) (xy 44.742747 -75.146385) (xy 44.804043 -75.204832)
			(xy 44.859505 -75.268841) (xy 44.908632 -75.337833) (xy 44.950979 -75.411181) (xy 44.986162 -75.488223)
			(xy 45.013862 -75.56826) (xy 45.03383 -75.650568) (xy 45.045883 -75.734401) (xy 45.049913 -75.819)
			(xy 45.045883 -75.903599) (xy 45.03383 -75.987432) (xy 45.013862 -76.06974) (xy 44.998078 -76.115348)
			(xy 45.719996 -76.115348) (xy 45.719996 -76.030652) (xy 45.728047 -75.946338) (xy 45.744076 -75.863172)
			(xy 45.767937 -75.781905) (xy 45.799416 -75.703275) (xy 45.838227 -75.627994) (xy 45.884017 -75.556742)
			(xy 45.936373 -75.490166) (xy 45.994821 -75.428868) (xy 46.058831 -75.373403) (xy 46.127823 -75.324274)
			(xy 46.201173 -75.281925) (xy 46.278216 -75.246741) (xy 46.358255 -75.219039) (xy 46.440564 -75.199071)
			(xy 46.524399 -75.187018) (xy 46.609 -75.182988) (xy 46.693601 -75.187018) (xy 46.777436 -75.199071)
			(xy 46.859745 -75.219039) (xy 46.939784 -75.246741) (xy 47.016827 -75.281925) (xy 47.090177 -75.324274)
			(xy 47.159169 -75.373403) (xy 47.223179 -75.428868) (xy 47.281627 -75.490166) (xy 47.333983 -75.556742)
			(xy 47.379773 -75.627994) (xy 47.418584 -75.703275) (xy 47.450063 -75.781905) (xy 47.473924 -75.863172)
			(xy 47.489953 -75.946338) (xy 47.498004 -76.030652) (xy 47.498508 -76.073) (xy 47.498004 -76.115348)
			(xy 47.489953 -76.199662) (xy 47.473924 -76.282828) (xy 47.450063 -76.364095) (xy 47.418584 -76.442725)
			(xy 47.379773 -76.518006) (xy 47.333983 -76.589258) (xy 47.281627 -76.655834) (xy 47.223179 -76.717132)
			(xy 47.159169 -76.772597) (xy 47.090177 -76.821726) (xy 47.016827 -76.864075) (xy 46.939784 -76.899259)
			(xy 46.859745 -76.926961) (xy 46.777436 -76.946929) (xy 46.693601 -76.958982) (xy 46.609 -76.963013)
			(xy 46.524399 -76.958982) (xy 46.440564 -76.946929) (xy 46.358255 -76.926961) (xy 46.278216 -76.899259)
			(xy 46.201173 -76.864075) (xy 46.127823 -76.821726) (xy 46.058831 -76.772597) (xy 45.994821 -76.717132)
			(xy 45.936373 -76.655834) (xy 45.884017 -76.589258) (xy 45.838227 -76.518006) (xy 45.799416 -76.442725)
			(xy 45.767937 -76.364095) (xy 45.744076 -76.282828) (xy 45.728047 -76.199662) (xy 45.719996 -76.115348)
			(xy 44.998078 -76.115348) (xy 44.986162 -76.149777) (xy 44.950979 -76.226819) (xy 44.908632 -76.300167)
			(xy 44.859505 -76.369159) (xy 44.804043 -76.433168) (xy 44.742747 -76.491615) (xy 44.676174 -76.543972)
			(xy 44.604925 -76.589763) (xy 44.529646 -76.628574) (xy 44.451018 -76.660054) (xy 44.369755 -76.683918)
			(xy 44.286591 -76.699949) (xy 44.20228 -76.708003) (xy 44.159932 -76.708508) (xy 44.116198 -76.707985)
			(xy 44.029151 -76.699417) (xy 43.943364 -76.682351) (xy 43.859665 -76.656953) (xy 43.819064 -76.64069)
			(xy 43.807123 -76.636432) (xy 43.781927 -76.638985) (xy 43.771058 -76.645516) (xy 43.73413 -76.669938)
			(xy 43.65633 -76.712205) (xy 43.574715 -76.746531) (xy 43.490094 -76.772579) (xy 43.403303 -76.79009)
			(xy 43.315202 -76.79889) (xy 43.270932 -76.79944) (xy 43.230293 -76.798998) (xy 43.149355 -76.791578)
			(xy 43.069432 -76.776804) (xy 42.991189 -76.754802) (xy 42.91528 -76.725753) (xy 42.842337 -76.689901)
			(xy 42.772969 -76.647544) (xy 42.707755 -76.599036) (xy 42.647237 -76.54478) (xy 42.591921 -76.48523)
			(xy 42.542268 -76.420883) (xy 42.498693 -76.352274) (xy 42.479722 -76.316332) (xy 42.474134 -76.305664)
			(xy 42.455592 -76.291694) (xy 42.35323 -76.272644) (xy 42.330878 -76.27874) (xy 42.321734 -76.286614)
			(xy 42.302308 -76.303641) (xy 42.261769 -76.335665) (xy 42.240708 -76.350622) (xy 42.232955 -76.356607)
			(xy 42.222317 -76.373029) (xy 42.218654 -76.392249) (xy 42.220134 -76.40193) (xy 42.227767 -76.443932)
			(xy 42.235911 -76.528915) (xy 42.23639 -76.571602) (xy 42.23595 -76.612706) (xy 42.228364 -76.694562)
			(xy 42.213258 -76.77537) (xy 42.190761 -76.854439) (xy 42.161064 -76.931095) (xy 42.12442 -77.004684)
			(xy 42.081143 -77.074578) (xy 42.031601 -77.14018) (xy 41.976218 -77.200932) (xy 41.915465 -77.256314)
			(xy 41.849861 -77.305854) (xy 41.779967 -77.34913) (xy 41.706377 -77.385772) (xy 41.62972 -77.415467)
			(xy 41.550651 -77.437963) (xy 41.469843 -77.453067) (xy 41.387986 -77.460651) (xy 41.346882 -77.46111)
			(xy 41.305422 -77.460587) (xy 41.222861 -77.452877) (xy 41.141376 -77.437516) (xy 41.061674 -77.414638)
			(xy 40.984448 -77.384442) (xy 40.910367 -77.347188) (xy 40.840075 -77.303201) (xy 40.774183 -77.252863)
			(xy 40.713261 -77.196611) (xy 40.657839 -77.134933) (xy 40.608399 -77.068364) (xy 40.565369 -76.997482)
			(xy 40.529123 -76.922904) (xy 40.499975 -76.845275) (xy 40.478179 -76.765271) (xy 40.470582 -76.72451)
			(xy 40.468434 -76.714878) (xy 40.457948 -76.698179) (xy 40.441953 -76.686647) (xy 40.432482 -76.68387)
			(xy 40.391329 -76.673533) (xy 40.311069 -76.645979) (xy 40.233798 -76.610906) (xy 40.16022 -76.568631)
			(xy 40.091003 -76.51954) (xy 40.026777 -76.464078) (xy 39.968127 -76.402751) (xy 39.915585 -76.336116)
			(xy 39.869629 -76.264779) (xy 39.830677 -76.189389) (xy 39.799084 -76.110631) (xy 39.775137 -76.029222)
			(xy 39.759053 -75.945902) (xy 39.750979 -75.861429) (xy 39.750492 -75.819) (xy 39.445206 -75.819)
			(xy 39.398704 -75.88043) (xy 39.343141 -75.941217) (xy 39.282197 -75.996609) (xy 39.216394 -76.046129)
			(xy 39.146296 -76.089355) (xy 39.072502 -76.125917) (xy 38.995644 -76.155501) (xy 38.916381 -76.177855)
			(xy 38.87597 -76.185776) (xy 38.864794 -76.187808) (xy 38.846506 -76.201016) (xy 38.79723 -76.2889)
			(xy 38.795452 -76.311252) (xy 38.799516 -76.32192) (xy 38.813542 -76.359941) (xy 38.835424 -76.437976)
			(xy 38.850113 -76.51768) (xy 38.857488 -76.598389) (xy 38.857936 -76.638912) (xy 38.857445 -76.680014)
			(xy 38.849859 -76.761867) (xy 38.834754 -76.842671) (xy 38.812257 -76.921736) (xy 38.782561 -76.998389)
			(xy 38.74592 -77.071975) (xy 38.702645 -77.141866) (xy 38.653107 -77.207466) (xy 38.597727 -77.268216)
			(xy 38.536978 -77.323597) (xy 38.471379 -77.373136) (xy 38.401489 -77.416412) (xy 38.327904 -77.453055)
			(xy 38.251252 -77.482752) (xy 38.172186 -77.50525) (xy 38.091383 -77.520357) (xy 38.00953 -77.527944)
			(xy 37.968428 -77.52842) (xy 37.922033 -77.527826) (xy 37.829745 -77.518184) (xy 37.738961 -77.498991)
			(xy 37.650667 -77.470456) (xy 37.608002 -77.45222) (xy 37.598062 -77.4484) (xy 37.576794 -77.4484)
			(xy 37.566854 -77.45222) (xy 37.524188 -77.470456) (xy 37.435897 -77.499002) (xy 37.345113 -77.518198)
			(xy 37.252824 -77.527834) (xy 37.206428 -77.52842) (xy 37.165326 -77.527921) (xy 37.083471 -77.520339)
			(xy 37.002666 -77.505236) (xy 36.923599 -77.482742) (xy 36.846944 -77.453048) (xy 36.773357 -77.416408)
			(xy 36.703464 -77.373135) (xy 36.637862 -77.323597) (xy 36.577111 -77.268218) (xy 36.521728 -77.207469)
			(xy 36.472188 -77.141869) (xy 36.428911 -77.071978) (xy 36.392268 -76.998392) (xy 36.362571 -76.921739)
			(xy 36.340073 -76.842673) (xy 36.324967 -76.761868) (xy 36.317381 -76.680014) (xy 36.31692 -76.638912)
			(xy 19.095457 -76.638912) (xy 19.09801 -76.665652) (xy 19.098514 -76.708) (xy 19.09801 -76.750348)
			(xy 19.089959 -76.834662) (xy 19.07393 -76.917828) (xy 19.050069 -76.999095) (xy 19.01859 -77.077725)
			(xy 18.979779 -77.153006) (xy 18.933989 -77.224258) (xy 18.881633 -77.290834) (xy 18.823185 -77.352132)
			(xy 18.759175 -77.407597) (xy 18.690183 -77.456726) (xy 18.616833 -77.499075) (xy 18.53979 -77.534259)
			(xy 18.459751 -77.561961) (xy 18.377442 -77.581929) (xy 18.293607 -77.593982) (xy 18.209006 -77.598013)
			(xy 18.124405 -77.593982) (xy 18.04057 -77.581929) (xy 17.958261 -77.561961) (xy 17.878222 -77.534259)
			(xy 17.801179 -77.499075) (xy 17.727829 -77.456726) (xy 17.658837 -77.407597) (xy 17.594827 -77.352132)
			(xy 17.536379 -77.290834) (xy 17.484023 -77.224258) (xy 17.438233 -77.153006) (xy 17.399422 -77.077725)
			(xy 17.367943 -76.999095) (xy 17.344082 -76.917828) (xy 17.328053 -76.834662) (xy 17.320002 -76.750348)
			(xy 16.114869 -76.750348) (xy 16.094602 -76.76523) (xy 16.025656 -76.806825) (xy 15.953232 -76.842016)
			(xy 15.877923 -76.870516) (xy 15.800345 -76.89209) (xy 15.721135 -76.906562) (xy 15.640941 -76.913813)
			(xy 15.60068 -76.914248) (xy 15.557466 -76.913729) (xy 15.471445 -76.905348) (xy 15.386642 -76.888668)
			(xy 15.303856 -76.863845) (xy 15.223866 -76.831114) (xy 15.147425 -76.790782) (xy 15.075255 -76.74323)
			(xy 15.008034 -76.688905) (xy 14.976856 -76.658978) (xy 14.969535 -76.652349) (xy 14.951294 -76.644821)
			(xy 14.931561 -76.644771) (xy 14.922246 -76.648056) (xy 14.882266 -76.663748) (xy 14.799954 -76.688292)
			(xy 14.715659 -76.704784) (xy 14.630167 -76.713069) (xy 14.58722 -76.713588) (xy 14.557988 -76.713356)
			(xy 14.499648 -76.709545) (xy 14.470634 -76.705968) (xy 14.461289 -76.705188) (xy 14.443063 -76.709496)
			(xy 14.427623 -76.720096) (xy 14.417054 -76.735557) (xy 14.4145 -76.744576) (xy 14.404133 -76.785789)
			(xy 14.376685 -76.866222) (xy 14.341689 -76.943669) (xy 14.299466 -77.017425) (xy 14.2504 -77.086818)
			(xy 14.194939 -77.151213) (xy 14.133588 -77.210025) (xy 14.066908 -77.262717) (xy 13.995505 -77.308808)
			(xy 13.920031 -77.347879) (xy 13.841174 -77.379571) (xy 13.759655 -77.403598) (xy 13.676215 -77.419739)
			(xy 13.591615 -77.427848) (xy 13.549122 -77.428344) (xy 13.505803 -77.427846) (xy 13.419575 -77.419434)
			(xy 13.334573 -77.402678) (xy 13.251603 -77.377736) (xy 13.171452 -77.344846) (xy 13.094878 -77.304318)
			(xy 13.022607 -77.256536) (xy 12.955325 -77.201954) (xy 12.893669 -77.141089) (xy 12.838222 -77.074518)
			(xy 12.789511 -77.00287) (xy 12.747998 -76.926826) (xy 12.714075 -76.847106) (xy 12.688064 -76.764465)
			(xy 12.670211 -76.679687) (xy 12.660686 -76.593575) (xy 12.659614 -76.550266) (xy 12.659008 -76.539186)
			(xy 12.649505 -76.519159) (xy 12.641326 -76.511658) (xy 12.608136 -76.483539) (xy 12.546806 -76.421843)
			(xy 12.491793 -76.354453) (xy 12.443623 -76.282013) (xy 12.402757 -76.205216) (xy 12.369585 -76.124796)
			(xy 12.344424 -76.04152) (xy 12.327515 -75.956186) (xy 12.31902 -75.869609) (xy 12.318492 -75.826112)
			(xy 11.772724 -75.826112) (xy 11.819258 -75.856017) (xy 11.885834 -75.908373) (xy 11.947132 -75.966821)
			(xy 12.002597 -76.030831) (xy 12.051726 -76.099823) (xy 12.094075 -76.173173) (xy 12.129259 -76.250216)
			(xy 12.156961 -76.330255) (xy 12.176929 -76.412564) (xy 12.188982 -76.496399) (xy 12.193013 -76.581)
			(xy 12.188982 -76.665601) (xy 12.176929 -76.749436) (xy 12.156961 -76.831745) (xy 12.129259 -76.911784)
			(xy 12.094075 -76.988827) (xy 12.051726 -77.062177) (xy 12.002597 -77.131169) (xy 11.947132 -77.195179)
			(xy 11.885834 -77.253627) (xy 11.819258 -77.305983) (xy 11.748006 -77.351773) (xy 11.672725 -77.390584)
			(xy 11.594095 -77.422063) (xy 11.512828 -77.445924) (xy 11.429662 -77.461953) (xy 11.345348 -77.470004)
			(xy 11.303 -77.470508) (xy 11.260713 -77.470022) (xy 11.17652 -77.461999) (xy 11.093468 -77.446026)
			(xy 11.012306 -77.422246) (xy 10.933766 -77.390873) (xy 10.858556 -77.352192) (xy 10.822686 -77.329792)
			(xy 10.813494 -77.324502) (xy 10.792572 -77.321188) (xy 10.772101 -77.32663) (xy 10.763504 -77.33284)
			(xy 10.72968 -77.359324) (xy 10.657785 -77.406356) (xy 10.581691 -77.446238) (xy 10.502107 -77.478598)
			(xy 10.419773 -77.503136) (xy 10.335458 -77.519622) (xy 10.249946 -77.527903) (xy 10.20699 -77.52842)
			(xy 10.160594 -77.52784) (xy 10.068306 -77.518194) (xy 9.977522 -77.498997) (xy 9.889229 -77.470458)
			(xy 9.846564 -77.45222) (xy 9.836624 -77.4484) (xy 9.815356 -77.4484) (xy 9.805416 -77.45222) (xy 9.762755 -77.470469)
			(xy 9.674462 -77.499012) (xy 9.583677 -77.518204) (xy 9.491386 -77.527836) (xy 9.44499 -77.52842)
			(xy 9.402642 -77.527912) (xy 9.318328 -77.519861) (xy 9.235162 -77.503832) (xy 9.153896 -77.479971)
			(xy 9.075266 -77.448492) (xy 8.999985 -77.409682) (xy 8.928733 -77.363891) (xy 8.862157 -77.311535)
			(xy 8.800859 -77.253088) (xy 8.745394 -77.189078) (xy 8.696266 -77.120086) (xy 8.653917 -77.046736)
			(xy 8.618733 -76.969693) (xy 8.591031 -76.889655) (xy 8.571063 -76.807346) (xy 8.55901 -76.723511)
			(xy 8.55498 -76.63891) (xy 1.651254 -76.63891) (xy 1.651254 -78.860904) (xy 1.652778 -78.91145) (xy 1.651254 -78.961996)
			(xy 1.651254 -80.521048) (xy 14.270482 -80.521048) (xy 14.270914 -80.48276) (xy 14.277536 -80.40647)
			(xy 14.290684 -80.33103) (xy 14.310262 -80.256998) (xy 14.322806 -80.22082) (xy 14.325424 -80.212376)
			(xy 14.325439 -80.194714) (xy 14.322806 -80.186276) (xy 14.310234 -80.150107) (xy 14.290642 -80.076075)
			(xy 14.277495 -80.000632) (xy 14.27089 -79.924338) (xy 14.270482 -79.886048) (xy 14.270998 -79.844946)
			(xy 14.278579 -79.763092) (xy 14.29368 -79.682287) (xy 14.316172 -79.60322) (xy 14.345864 -79.526565)
			(xy 14.382503 -79.452978) (xy 14.425775 -79.383085) (xy 14.475312 -79.317483) (xy 14.53069 -79.256731)
			(xy 14.591438 -79.201349) (xy 14.657037 -79.151808) (xy 14.726927 -79.108531) (xy 14.800512 -79.071888)
			(xy 14.877165 -79.042191) (xy 14.95623 -79.019693) (xy 15.037035 -79.004587) (xy 15.118888 -78.997001)
			(xy 15.15999 -78.99654) (xy 15.199559 -78.996973) (xy 15.278387 -79.003976) (xy 15.356281 -79.017955)
			(xy 15.432625 -79.038799) (xy 15.46987 -79.052166) (xy 15.478537 -79.055006) (xy 15.496763 -79.055006)
			(xy 15.50543 -79.052166) (xy 15.542679 -79.038809) (xy 15.619021 -79.017959) (xy 15.696914 -79.003973)
			(xy 15.775741 -78.996962) (xy 15.81531 -78.99654) (xy 15.853598 -78.996981) (xy 15.929888 -79.0036)
			(xy 16.005328 -79.016746) (xy 16.07936 -79.036321) (xy 16.115538 -79.048864) (xy 16.123976 -79.051506)
			(xy 16.141644 -79.051506) (xy 16.150082 -79.048864) (xy 16.186255 -79.036302) (xy 16.260285 -79.016708)
			(xy 16.335727 -79.003558) (xy 16.41202 -78.99695) (xy 16.45031 -78.99654) (xy 16.491412 -78.997017)
			(xy 16.573267 -79.004602) (xy 16.654072 -79.019707) (xy 16.733139 -79.042203) (xy 16.809792 -79.071899)
			(xy 16.883379 -79.108541) (xy 16.953271 -79.151816) (xy 17.018872 -79.201355) (xy 17.079622 -79.256736)
			(xy 17.135003 -79.317486) (xy 17.184543 -79.383087) (xy 17.227818 -79.452979) (xy 17.26446 -79.526566)
			(xy 17.294156 -79.60322) (xy 17.316653 -79.682286) (xy 17.331758 -79.763091) (xy 17.339343 -79.844946)
			(xy 17.339818 -79.886048) (xy 17.339385 -79.924336) (xy 17.332763 -80.000626) (xy 17.319615 -80.076066)
			(xy 17.300038 -80.150098) (xy 17.287494 -80.186276) (xy 17.284829 -80.194708) (xy 17.284844 -80.212382)
			(xy 17.287494 -80.22082) (xy 17.300064 -80.25699) (xy 17.319657 -80.331021) (xy 17.332805 -80.406464)
			(xy 17.339409 -80.482758) (xy 17.339818 -80.521048) (xy 42.03192 -80.521048) (xy 42.032349 -80.48276)
			(xy 42.038972 -80.406469) (xy 42.052121 -80.33103) (xy 42.071699 -80.256997) (xy 42.084244 -80.22082)
			(xy 42.08686 -80.212376) (xy 42.086876 -80.194714) (xy 42.084244 -80.186276) (xy 42.071674 -80.150106)
			(xy 42.052081 -80.076075) (xy 42.038933 -80.000632) (xy 42.032329 -79.924338) (xy 42.03192 -79.886048)
			(xy 42.032398 -79.844945) (xy 42.039979 -79.763089) (xy 42.055081 -79.682281) (xy 42.077575 -79.603212)
			(xy 42.107268 -79.526556) (xy 42.143909 -79.452967) (xy 42.187183 -79.383073) (xy 42.236722 -79.31747)
			(xy 42.292104 -79.256718) (xy 42.352854 -79.201335) (xy 42.418456 -79.151795) (xy 42.48835 -79.108519)
			(xy 42.561938 -79.071876) (xy 42.638593 -79.042181) (xy 42.717662 -79.019685) (xy 42.798469 -79.004582)
			(xy 42.880325 -78.996999) (xy 42.921428 -78.99654) (xy 42.960998 -78.996961) (xy 43.039826 -79.003968)
			(xy 43.117719 -79.01795) (xy 43.194063 -79.038797) (xy 43.231308 -79.052166) (xy 43.239975 -79.055006)
			(xy 43.258201 -79.055006) (xy 43.266868 -79.052166) (xy 43.304113 -79.038798) (xy 43.380457 -79.017951)
			(xy 43.458351 -79.003969) (xy 43.537179 -78.996961) (xy 43.576748 -78.99654) (xy 43.615036 -78.996969)
			(xy 43.691327 -79.003592) (xy 43.766766 -79.016741) (xy 43.840799 -79.036319) (xy 43.876976 -79.048864)
			(xy 43.885414 -79.051506) (xy 43.903082 -79.051506) (xy 43.91152 -79.048864) (xy 43.947689 -79.036292)
			(xy 44.021721 -79.0167) (xy 44.097164 -79.003553) (xy 44.173458 -78.996949) (xy 44.211748 -78.99654)
			(xy 44.252853 -78.996921) (xy 44.334711 -79.004511) (xy 44.41552 -79.019621) (xy 44.49459 -79.042123)
			(xy 44.571246 -79.071824) (xy 44.644835 -79.108472) (xy 44.714729 -79.151754) (xy 44.78033 -79.2013)
			(xy 44.841081 -79.256687) (xy 44.896462 -79.317443) (xy 44.946 -79.383051) (xy 44.989274 -79.452949)
			(xy 45.025914 -79.526542) (xy 45.055608 -79.603201) (xy 45.078101 -79.682274) (xy 45.093203 -79.763084)
			(xy 45.100784 -79.844943) (xy 45.101256 -79.886048) (xy 45.100827 -79.924336) (xy 45.094204 -80.000627)
			(xy 45.081055 -80.076066) (xy 45.061477 -80.150099) (xy 45.048932 -80.186276) (xy 45.046265 -80.194708)
			(xy 45.046281 -80.212382) (xy 45.048932 -80.22082) (xy 45.061504 -80.256989) (xy 45.081096 -80.331021)
			(xy 45.094243 -80.406464) (xy 45.100847 -80.482758) (xy 45.101256 -80.521048) (xy 45.100779 -80.56215)
			(xy 45.093191 -80.644003) (xy 45.078082 -80.724806) (xy 45.055583 -80.803871) (xy 45.025886 -80.880523)
			(xy 44.989243 -80.954108) (xy 44.945967 -81.023998) (xy 44.896427 -81.089598) (xy 44.841047 -81.150347)
			(xy 44.780298 -81.205727) (xy 44.714698 -81.255267) (xy 44.644808 -81.298543) (xy 44.571223 -81.335186)
			(xy 44.494571 -81.364883) (xy 44.415506 -81.387382) (xy 44.334703 -81.402491) (xy 44.25285 -81.410079)
			(xy 44.211748 -81.410556) (xy 44.172816 -81.410118) (xy 44.095252 -81.403283) (xy 44.018584 -81.389688)
			(xy 43.9434 -81.369438) (xy 43.906694 -81.356454) (xy 43.898145 -81.35369) (xy 43.880191 -81.35369)
			(xy 43.871642 -81.356454) (xy 43.834933 -81.369427) (xy 43.759747 -81.389667) (xy 43.68308 -81.403265)
			(xy 43.605519 -81.410115) (xy 43.566588 -81.410556) (xy 43.527656 -81.410136) (xy 43.450092 -81.403296)
			(xy 43.373423 -81.389696) (xy 43.298239 -81.36944) (xy 43.261534 -81.356454) (xy 43.252985 -81.35369)
			(xy 43.235031 -81.35369) (xy 43.226482 -81.356454) (xy 43.189769 -81.369415) (xy 43.114584 -81.389659)
			(xy 43.037919 -81.403259) (xy 42.960359 -81.410113) (xy 42.921428 -81.410556) (xy 42.880327 -81.410007)
			(xy 42.798477 -81.402425) (xy 42.717674 -81.387323) (xy 42.63861 -81.364831) (xy 42.561959 -81.335139)
			(xy 42.488374 -81.298501) (xy 42.418483 -81.255231) (xy 42.352883 -81.205696) (xy 42.292134 -81.15032)
			(xy 42.236752 -81.089575) (xy 42.187212 -81.023979) (xy 42.143936 -80.954092) (xy 42.107292 -80.880511)
			(xy 42.077594 -80.803862) (xy 42.055094 -80.7248) (xy 42.039986 -80.643999) (xy 42.032397 -80.562149)
			(xy 42.03192 -80.521048) (xy 17.339818 -80.521048) (xy 17.339379 -80.562151) (xy 17.33179 -80.644006)
			(xy 17.316681 -80.724812) (xy 17.294181 -80.803878) (xy 17.264482 -80.880532) (xy 17.227837 -80.954119)
			(xy 17.184559 -81.02401) (xy 17.135017 -81.089611) (xy 17.079634 -81.15036) (xy 17.018881 -81.205741)
			(xy 16.953279 -81.25528) (xy 16.883385 -81.298555) (xy 16.809797 -81.335197) (xy 16.733142 -81.364893)
			(xy 16.654075 -81.38739) (xy 16.573268 -81.402495) (xy 16.491413 -81.410081) (xy 16.45031 -81.410556)
			(xy 16.411378 -81.410129) (xy 16.333814 -81.403291) (xy 16.257146 -81.389693) (xy 16.181961 -81.369439)
			(xy 16.145256 -81.356454) (xy 16.136707 -81.35369) (xy 16.118753 -81.35369) (xy 16.110204 -81.356454)
			(xy 16.073499 -81.369437) (xy 15.998311 -81.389675) (xy 15.921643 -81.403269) (xy 15.844082 -81.410117)
			(xy 15.80515 -81.410556) (xy 15.766218 -81.410117) (xy 15.688654 -81.403283) (xy 15.611986 -81.389688)
			(xy 15.536802 -81.369438) (xy 15.500096 -81.356454) (xy 15.491547 -81.35369) (xy 15.473593 -81.35369)
			(xy 15.465044 -81.356454) (xy 15.428335 -81.369426) (xy 15.353149 -81.389667) (xy 15.276482 -81.403264)
			(xy 15.198921 -81.410115) (xy 15.15999 -81.410556) (xy 15.118887 -81.410098) (xy 15.037031 -81.402513)
			(xy 14.956224 -81.387407) (xy 14.877156 -81.36491) (xy 14.800501 -81.335214) (xy 14.726913 -81.298571)
			(xy 14.657019 -81.255295) (xy 14.591417 -81.205755) (xy 14.530666 -81.150373) (xy 14.475284 -81.089621)
			(xy 14.425744 -81.024019) (xy 14.382468 -80.954126) (xy 14.345825 -80.880537) (xy 14.316129 -80.803882)
			(xy 14.293632 -80.724814) (xy 14.278527 -80.644007) (xy 14.270942 -80.562151) (xy 14.270482 -80.521048)
			(xy 1.651254 -80.521048) (xy 1.651254 -83.940904) (xy 1.652778 -83.99145) (xy 1.651254 -84.041996)
			(xy 1.651254 -84.385912) (xy 39.460424 -84.385912) (xy 39.461008 -84.339516) (xy 39.470653 -84.247228)
			(xy 39.489848 -84.156444) (xy 39.518386 -84.068151) (xy 39.536624 -84.025486) (xy 39.540436 -84.015544)
			(xy 39.540441 -83.994278) (xy 39.536624 -83.984338) (xy 39.518385 -83.941673) (xy 39.489839 -83.853382)
			(xy 39.470644 -83.762598) (xy 39.46101 -83.670308) (xy 39.460424 -83.623912) (xy 39.460928 -83.581564)
			(xy 39.468979 -83.49725) (xy 39.485008 -83.414084) (xy 39.508869 -83.332817) (xy 39.540348 -83.254187)
			(xy 39.579159 -83.178906) (xy 39.624949 -83.107654) (xy 39.677305 -83.041078) (xy 39.735753 -82.97978)
			(xy 39.799763 -82.924315) (xy 39.868755 -82.875186) (xy 39.942105 -82.832837) (xy 40.019148 -82.797653)
			(xy 40.099187 -82.769951) (xy 40.181496 -82.749983) (xy 40.265331 -82.73793) (xy 40.349932 -82.7339)
			(xy 40.434533 -82.73793) (xy 40.518368 -82.749983) (xy 40.600677 -82.769951) (xy 40.680716 -82.797653)
			(xy 40.757759 -82.832837) (xy 40.831109 -82.875186) (xy 40.900101 -82.924315) (xy 40.964111 -82.97978)
			(xy 41.022559 -83.041078) (xy 41.074915 -83.107654) (xy 41.120705 -83.178906) (xy 41.159516 -83.254187)
			(xy 41.190995 -83.332817) (xy 41.214856 -83.414084) (xy 41.230885 -83.49725) (xy 41.238936 -83.581564)
			(xy 41.23944 -83.623912) (xy 41.238867 -83.670308) (xy 41.22922 -83.762597) (xy 41.210021 -83.853381)
			(xy 41.18148 -83.941674) (xy 41.16324 -83.984338) (xy 41.159415 -83.994276) (xy 41.15942 -84.015546)
			(xy 41.16324 -84.025486) (xy 41.181491 -84.068146) (xy 41.210033 -84.156439) (xy 41.229224 -84.247225)
			(xy 41.238856 -84.339516) (xy 41.23944 -84.385912) (xy 41.238936 -84.42826) (xy 41.230885 -84.512574)
			(xy 41.214856 -84.59574) (xy 41.190995 -84.677007) (xy 41.159516 -84.755637) (xy 41.120705 -84.830918)
			(xy 41.074915 -84.90217) (xy 41.022559 -84.968746) (xy 40.964111 -85.030044) (xy 40.900101 -85.085509)
			(xy 40.831109 -85.134638) (xy 40.757759 -85.176987) (xy 40.680716 -85.212171) (xy 40.600677 -85.239873)
			(xy 40.518368 -85.259841) (xy 40.434533 -85.271894) (xy 40.349932 -85.275925) (xy 40.265331 -85.271894)
			(xy 40.181496 -85.259841) (xy 40.099187 -85.239873) (xy 40.019148 -85.212171) (xy 39.942105 -85.176987)
			(xy 39.868755 -85.134638) (xy 39.799763 -85.085509) (xy 39.735753 -85.030044) (xy 39.677305 -84.968746)
			(xy 39.624949 -84.90217) (xy 39.579159 -84.830918) (xy 39.540348 -84.755637) (xy 39.508869 -84.677007)
			(xy 39.485008 -84.59574) (xy 39.468979 -84.512574) (xy 39.460928 -84.42826) (xy 39.460424 -84.385912)
			(xy 1.651254 -84.385912) (xy 1.651254 -85.32571) (xy 2.66599 -85.32571) (xy 2.67002 -85.241109) (xy 2.682073 -85.157274)
			(xy 2.702041 -85.074965) (xy 2.729743 -84.994927) (xy 2.764927 -84.917884) (xy 2.807276 -84.844534)
			(xy 2.856404 -84.775542) (xy 2.911869 -84.711532) (xy 2.973167 -84.653085) (xy 3.039743 -84.600729)
			(xy 3.110995 -84.554938) (xy 3.186276 -84.516128) (xy 3.264906 -84.484649) (xy 3.346172 -84.460788)
			(xy 3.429338 -84.444759) (xy 3.513652 -84.436708) (xy 3.556 -84.436204) (xy 3.602396 -84.436786)
			(xy 3.694684 -84.446431) (xy 3.785468 -84.465627) (xy 3.873761 -84.494166) (xy 3.916426 -84.512404)
			(xy 3.926366 -84.516224) (xy 3.947634 -84.516224) (xy 3.957574 -84.512404) (xy 4.000236 -84.49416)
			(xy 4.088529 -84.465616) (xy 4.179314 -84.446422) (xy 4.271604 -84.436789) (xy 4.318 -84.436204)
			(xy 4.364396 -84.436786) (xy 4.456684 -84.446431) (xy 4.547468 -84.465627) (xy 4.635761 -84.494166)
			(xy 4.678426 -84.512404) (xy 4.688366 -84.516224) (xy 4.709634 -84.516224) (xy 4.719574 -84.512404)
			(xy 4.762236 -84.49416) (xy 4.850529 -84.465616) (xy 4.941314 -84.446422) (xy 5.033604 -84.436789)
			(xy 5.08 -84.436204) (xy 5.126396 -84.436786) (xy 5.218684 -84.446431) (xy 5.309468 -84.465627) (xy 5.397761 -84.494166)
			(xy 5.440426 -84.512404) (xy 5.450366 -84.516224) (xy 5.471634 -84.516224) (xy 5.481574 -84.512404)
			(xy 5.524236 -84.49416) (xy 5.612529 -84.465616) (xy 5.703314 -84.446422) (xy 5.795604 -84.436789)
			(xy 5.842 -84.436204) (xy 5.888396 -84.436786) (xy 5.980684 -84.446431) (xy 6.071468 -84.465627)
			(xy 6.159761 -84.494166) (xy 6.202426 -84.512404) (xy 6.212366 -84.516224) (xy 6.233634 -84.516224)
			(xy 6.243574 -84.512404) (xy 6.286236 -84.49416) (xy 6.374529 -84.465616) (xy 6.465314 -84.446422)
			(xy 6.557604 -84.436789) (xy 6.604 -84.436204) (xy 6.646349 -84.436704) (xy 6.730662 -84.444755)
			(xy 6.813829 -84.460784) (xy 6.895095 -84.484646) (xy 6.973725 -84.516124) (xy 7.049007 -84.554935)
			(xy 7.120259 -84.600726) (xy 7.186836 -84.653082) (xy 7.248134 -84.71153) (xy 7.303599 -84.77554)
			(xy 7.352728 -84.844532) (xy 7.395076 -84.917882) (xy 7.430261 -84.994925) (xy 7.457963 -85.074964)
			(xy 7.477931 -85.157274) (xy 7.489984 -85.241109) (xy 7.494015 -85.32571) (xy 7.489984 -85.410311)
			(xy 7.477931 -85.494146) (xy 7.457963 -85.576456) (xy 7.430261 -85.656495) (xy 7.395076 -85.733538)
			(xy 7.352728 -85.806888) (xy 7.303599 -85.87588) (xy 7.248134 -85.93989) (xy 7.186836 -85.998338)
			(xy 7.120259 -86.050694) (xy 7.049007 -86.096485) (xy 6.973725 -86.135296) (xy 6.895095 -86.166774)
			(xy 6.813829 -86.190636) (xy 6.730662 -86.206665) (xy 6.646349 -86.214716) (xy 6.604 -86.21522) (xy 6.557604 -86.214636)
			(xy 6.465316 -86.204991) (xy 6.374532 -86.185796) (xy 6.286239 -86.157258) (xy 6.243574 -86.13902)
			(xy 6.233634 -86.1352) (xy 6.212366 -86.1352) (xy 6.202426 -86.13902) (xy 6.159764 -86.157266) (xy 6.071472 -86.185809)
			(xy 5.980686 -86.205002) (xy 5.888396 -86.214635) (xy 5.842 -86.21522) (xy 5.795604 -86.214636) (xy 5.703316 -86.204991)
			(xy 5.612532 -86.185796) (xy 5.524239 -86.157258) (xy 5.481574 -86.13902) (xy 5.471634 -86.1352)
			(xy 5.450366 -86.1352) (xy 5.440426 -86.13902) (xy 5.397764 -86.157266) (xy 5.309472 -86.185809)
			(xy 5.218686 -86.205002) (xy 5.126396 -86.214635) (xy 5.08 -86.21522) (xy 5.033604 -86.214636) (xy 4.941316 -86.204991)
			(xy 4.850532 -86.185796) (xy 4.762239 -86.157258) (xy 4.719574 -86.13902) (xy 4.709634 -86.1352)
			(xy 4.688366 -86.1352) (xy 4.678426 -86.13902) (xy 4.635764 -86.157266) (xy 4.547472 -86.185809)
			(xy 4.456686 -86.205002) (xy 4.364396 -86.214635) (xy 4.318 -86.21522) (xy 4.271604 -86.214636) (xy 4.179316 -86.204991)
			(xy 4.088532 -86.185796) (xy 4.000239 -86.157258) (xy 3.957574 -86.13902) (xy 3.947634 -86.1352)
			(xy 3.926366 -86.1352) (xy 3.916426 -86.13902) (xy 3.873764 -86.157266) (xy 3.785472 -86.185809)
			(xy 3.694686 -86.205002) (xy 3.602396 -86.214635) (xy 3.556 -86.21522) (xy 3.513652 -86.214712) (xy 3.429338 -86.206661)
			(xy 3.346172 -86.190632) (xy 3.264906 -86.166771) (xy 3.186276 -86.135292) (xy 3.110995 -86.096482)
			(xy 3.039743 -86.050691) (xy 2.973167 -85.998335) (xy 2.911869 -85.939888) (xy 2.856404 -85.875878)
			(xy 2.807276 -85.806886) (xy 2.764927 -85.733536) (xy 2.729743 -85.656493) (xy 2.702041 -85.576455)
			(xy 2.682073 -85.494146) (xy 2.67002 -85.410311) (xy 2.66599 -85.32571) (xy 1.651254 -85.32571) (xy 1.651254 -89.020904)
			(xy 1.652778 -89.07145) (xy 1.651254 -89.121996) (xy 1.651254 -89.153238) (xy 12.572492 -89.153238)
			(xy 12.57292 -89.11495) (xy 12.579543 -89.038659) (xy 12.592693 -88.96322) (xy 12.612271 -88.889187)
			(xy 12.624816 -88.85301) (xy 12.627438 -88.844567) (xy 12.627451 -88.826904) (xy 12.624816 -88.818466)
			(xy 12.612242 -88.782297) (xy 12.59265 -88.708266) (xy 12.579504 -88.632823) (xy 12.5729 -88.556528)
			(xy 12.572492 -88.518238) (xy 12.57292 -88.47995) (xy 12.579543 -88.403659) (xy 12.592693 -88.32822)
			(xy 12.612271 -88.254187) (xy 12.624816 -88.21801) (xy 12.627438 -88.209567) (xy 12.627451 -88.191904)
			(xy 12.624816 -88.183466) (xy 12.612242 -88.147297) (xy 12.59265 -88.073266) (xy 12.579504 -87.997823)
			(xy 12.5729 -87.921528) (xy 12.572492 -87.883238) (xy 12.572994 -87.842031) (xy 12.580608 -87.759969)
			(xy 12.595782 -87.678965) (xy 12.618388 -87.599711) (xy 12.64823 -87.52289) (xy 12.685053 -87.44916)
			(xy 12.728541 -87.379154) (xy 12.77832 -87.313472) (xy 12.833963 -87.252678) (xy 12.894994 -87.197295)
			(xy 12.960888 -87.147796) (xy 13.031079 -87.104608) (xy 13.104965 -87.0681) (xy 13.181913 -87.038586)
			(xy 13.221462 -87.027004) (xy 13.231796 -87.023552) (xy 13.248429 -87.00951) (xy 13.25781 -86.989868)
			(xy 13.258546 -86.978998) (xy 13.259811 -86.935841) (xy 13.269705 -86.850066) (xy 13.287866 -86.765653)
			(xy 13.314122 -86.683398) (xy 13.348227 -86.604074) (xy 13.38986 -86.52843) (xy 13.438627 -86.457176)
			(xy 13.494071 -86.390985) (xy 13.555669 -86.330479) (xy 13.622842 -86.276227) (xy 13.694956 -86.228741)
			(xy 13.771333 -86.188468) (xy 13.851253 -86.155787) (xy 13.933965 -86.131006) (xy 14.018689 -86.114357)
			(xy 14.104628 -86.105999) (xy 14.1478 -86.105492) (xy 14.188902 -86.105967) (xy 14.270757 -86.113552)
			(xy 14.351562 -86.128657) (xy 14.430629 -86.151153) (xy 14.507283 -86.180849) (xy 14.58087 -86.217491)
			(xy 14.650762 -86.260766) (xy 14.716363 -86.310306) (xy 14.777113 -86.365687) (xy 14.832494 -86.426437)
			(xy 14.882034 -86.492038) (xy 14.894642 -86.5124) (xy 17.728692 -86.5124) (xy 17.729138 -86.474112)
			(xy 17.735756 -86.397822) (xy 17.7489 -86.322382) (xy 17.768474 -86.24835) (xy 17.781016 -86.212172)
			(xy 17.783657 -86.203734) (xy 17.783657 -86.186066) (xy 17.781016 -86.177628) (xy 17.76846 -86.141453)
			(xy 17.748863 -86.067424) (xy 17.735712 -85.991983) (xy 17.729103 -85.915689) (xy 17.728692 -85.8774)
			(xy 17.729196 -85.835052) (xy 17.737247 -85.750738) (xy 17.753276 -85.667572) (xy 17.777137 -85.586305)
			(xy 17.808616 -85.507675) (xy 17.847427 -85.432394) (xy 17.893217 -85.361142) (xy 17.945573 -85.294566)
			(xy 18.004021 -85.233268) (xy 18.068031 -85.177803) (xy 18.137023 -85.128674) (xy 18.210373 -85.086325)
			(xy 18.287416 -85.051141) (xy 18.367455 -85.023439) (xy 18.449764 -85.003471) (xy 18.533599 -84.991418)
			(xy 18.6182 -84.987388) (xy 18.702801 -84.991418) (xy 18.786636 -85.003471) (xy 18.868945 -85.023439)
			(xy 18.948984 -85.051141) (xy 19.026027 -85.086325) (xy 19.099377 -85.128674) (xy 19.168369 -85.177803)
			(xy 19.232379 -85.233268) (xy 19.290827 -85.294566) (xy 19.343183 -85.361142) (xy 19.388973 -85.432394)
			(xy 19.427784 -85.507675) (xy 19.459263 -85.586305) (xy 19.483124 -85.667572) (xy 19.499153 -85.750738)
			(xy 19.507204 -85.835052) (xy 19.507708 -85.8774) (xy 19.507262 -85.915688) (xy 19.500644 -85.991978)
			(xy 19.4875 -86.067418) (xy 19.467926 -86.14145) (xy 19.455384 -86.177628) (xy 19.452743 -86.186066)
			(xy 19.452743 -86.203734) (xy 19.455384 -86.212172) (xy 19.46794 -86.248347) (xy 19.487537 -86.322376)
			(xy 19.500688 -86.397817) (xy 19.507297 -86.474111) (xy 19.507708 -86.5124) (xy 19.507278 -86.552642)
			(xy 19.500011 -86.632798) (xy 19.485536 -86.71197) (xy 19.463972 -86.789512) (xy 19.435495 -86.86479)
			(xy 19.400338 -86.93719) (xy 19.379946 -86.971886) (xy 19.374612 -86.980776) (xy 19.371564 -87.000588)
			(xy 19.395186 -87.091266) (xy 19.407378 -87.107268) (xy 19.416268 -87.112348) (xy 19.452864 -87.133902)
			(xy 19.522185 -87.182984) (xy 19.586512 -87.238451) (xy 19.645259 -87.299797) (xy 19.69789 -87.366464)
			(xy 19.743926 -87.437844) (xy 19.782949 -87.513287) (xy 19.814602 -87.592107) (xy 19.838598 -87.673585)
			(xy 19.854718 -87.75698) (xy 19.862814 -87.841531) (xy 19.863308 -87.884) (xy 19.862862 -87.922288)
			(xy 19.856244 -87.998578) (xy 19.8431 -88.074018) (xy 19.823526 -88.14805) (xy 19.810984 -88.184228)
			(xy 19.808343 -88.192666) (xy 19.808343 -88.210334) (xy 19.810984 -88.218772) (xy 19.82354 -88.254947)
			(xy 19.843137 -88.328976) (xy 19.856288 -88.404417) (xy 19.862897 -88.480711) (xy 19.863308 -88.519)
			(xy 19.862862 -88.557288) (xy 19.856244 -88.633578) (xy 19.8431 -88.709018) (xy 19.823526 -88.78305)
			(xy 19.810984 -88.819228) (xy 19.808343 -88.827666) (xy 19.808343 -88.845334) (xy 19.810984 -88.853772)
			(xy 19.82354 -88.889947) (xy 19.843137 -88.963976) (xy 19.856288 -89.039417) (xy 19.862897 -89.115711)
			(xy 19.863308 -89.154) (xy 19.862804 -89.196348) (xy 19.854753 -89.280662) (xy 19.840001 -89.3572)
			(xy 31.597092 -89.3572) (xy 31.597697 -89.310821) (xy 31.607347 -89.218567) (xy 31.626542 -89.127818)
			(xy 31.655073 -89.039558) (xy 31.692632 -88.954745) (xy 31.715202 -88.914224) (xy 31.720854 -88.902947)
			(xy 31.721537 -88.877768) (xy 31.716472 -88.866218) (xy 31.698422 -88.829098) (xy 31.668498 -88.752167)
			(xy 31.645827 -88.672795) (xy 31.630604 -88.591665) (xy 31.62296 -88.509473) (xy 31.622492 -88.4682)
			(xy 31.623091 -88.421938) (xy 31.632718 -88.329916) (xy 31.651848 -88.239391) (xy 31.680274 -88.151341)
			(xy 31.698438 -88.10879) (xy 31.702568 -88.098102) (xy 31.701773 -88.075225) (xy 31.696914 -88.064848)
			(xy 31.677781 -88.026831) (xy 31.646 -87.947874) (xy 31.621906 -87.866242) (xy 31.60572 -87.782681)
			(xy 31.59759 -87.697957) (xy 31.597092 -87.6554) (xy 31.597579 -87.613222) (xy 31.60558 -87.529246)
			(xy 31.621493 -87.446404) (xy 31.645173 -87.365439) (xy 31.676409 -87.287079) (xy 31.71492 -87.212026)
			(xy 31.76036 -87.140954) (xy 31.812322 -87.074502) (xy 31.870339 -87.013264) (xy 31.933891 -86.957792)
			(xy 32.002407 -86.908582) (xy 32.075272 -86.866077) (xy 32.151832 -86.830658) (xy 32.191452 -86.816184)
			(xy 32.201612 -86.812628) (xy 32.216852 -86.798404) (xy 32.25546 -86.711536) (xy 32.25546 -86.690454)
			(xy 32.251396 -86.680802) (xy 32.234605 -86.639633) (xy 32.208357 -86.554679) (xy 32.190708 -86.467531)
			(xy 32.181835 -86.379058) (xy 32.181292 -86.3346) (xy 32.181738 -86.296312) (xy 32.188356 -86.220022)
			(xy 32.2015 -86.144582) (xy 32.221074 -86.07055) (xy 32.233616 -86.034372) (xy 32.236257 -86.025934)
			(xy 32.236257 -86.008266) (xy 32.233616 -85.999828) (xy 32.22106 -85.963653) (xy 32.201463 -85.889624)
			(xy 32.188312 -85.814183) (xy 32.181703 -85.737889) (xy 32.181292 -85.6996) (xy 32.181796 -85.657252)
			(xy 32.189847 -85.572938) (xy 32.205876 -85.489772) (xy 32.229737 -85.408505) (xy 32.261216 -85.329875)
			(xy 32.300027 -85.254594) (xy 32.345817 -85.183342) (xy 32.398173 -85.116766) (xy 32.456621 -85.055468)
			(xy 32.520631 -85.000003) (xy 32.589623 -84.950874) (xy 32.662973 -84.908525) (xy 32.740016 -84.873341)
			(xy 32.820055 -84.845639) (xy 32.902364 -84.825671) (xy 32.986199 -84.813618) (xy 33.0708 -84.809588)
			(xy 33.155401 -84.813618) (xy 33.239236 -84.825671) (xy 33.321545 -84.845639) (xy 33.401584 -84.873341)
			(xy 33.478627 -84.908525) (xy 33.551977 -84.950874) (xy 33.620969 -85.000003) (xy 33.684979 -85.055468)
			(xy 33.743427 -85.116766) (xy 33.795783 -85.183342) (xy 33.841573 -85.254594) (xy 33.880384 -85.329875)
			(xy 33.911863 -85.408505) (xy 33.935724 -85.489772) (xy 33.951753 -85.572938) (xy 33.959804 -85.657252)
			(xy 33.960308 -85.6996) (xy 33.959862 -85.737888) (xy 33.953244 -85.814178) (xy 33.9401 -85.889618)
			(xy 33.920526 -85.96365) (xy 33.907984 -85.999828) (xy 33.905343 -86.008266) (xy 33.905343 -86.025934)
			(xy 33.907984 -86.034372) (xy 33.92054 -86.070547) (xy 33.940137 -86.144576) (xy 33.953288 -86.220017)
			(xy 33.959897 -86.296311) (xy 33.960112 -86.316312) (xy 35.838892 -86.316312) (xy 35.839383 -86.274361)
			(xy 35.847275 -86.19083) (xy 35.86299 -86.108412) (xy 35.886388 -86.027838) (xy 35.901376 -85.988652)
			(xy 35.904581 -85.979525) (xy 35.904565 -85.960194) (xy 35.901376 -85.95106) (xy 35.886389 -85.911873)
			(xy 35.862968 -85.831304) (xy 35.847246 -85.748886) (xy 35.839364 -85.665352) (xy 35.838892 -85.6234)
			(xy 35.839396 -85.581052) (xy 35.847447 -85.496738) (xy 35.863476 -85.413572) (xy 35.887337 -85.332305)
			(xy 35.918816 -85.253675) (xy 35.957627 -85.178394) (xy 36.003417 -85.107142) (xy 36.055773 -85.040566)
			(xy 36.114221 -84.979268) (xy 36.178231 -84.923803) (xy 36.247223 -84.874674) (xy 36.320573 -84.832325)
			(xy 36.397616 -84.797141) (xy 36.477655 -84.769439) (xy 36.559964 -84.749471) (xy 36.643799 -84.737418)
			(xy 36.7284 -84.733388) (xy 36.813001 -84.737418) (xy 36.896836 -84.749471) (xy 36.979145 -84.769439)
			(xy 37.059184 -84.797141) (xy 37.136227 -84.832325) (xy 37.209577 -84.874674) (xy 37.278569 -84.923803)
			(xy 37.342579 -84.979268) (xy 37.401027 -85.040566) (xy 37.453383 -85.107142) (xy 37.499173 -85.178394)
			(xy 37.537984 -85.253675) (xy 37.55665 -85.3003) (xy 44.184284 -85.3003) (xy 44.188314 -85.215697)
			(xy 44.200368 -85.13186) (xy 44.220338 -85.049548) (xy 44.248041 -84.969507) (xy 44.283227 -84.892462)
			(xy 44.325577 -84.819111) (xy 44.374709 -84.750118) (xy 44.430176 -84.686107) (xy 44.491477 -84.627659)
			(xy 44.558056 -84.575303) (xy 44.62931 -84.529513) (xy 44.704595 -84.490703) (xy 44.783228 -84.459226)
			(xy 44.864497 -84.435366) (xy 44.947666 -84.419339) (xy 45.031982 -84.411291) (xy 45.074332 -84.410804)
			(xy 45.120727 -84.41141) (xy 45.213015 -84.421048) (xy 45.303799 -84.440237) (xy 45.392093 -84.468769)
			(xy 45.434758 -84.487004) (xy 45.444698 -84.490824) (xy 45.465966 -84.490824) (xy 45.475906 -84.487004)
			(xy 45.518564 -84.468749) (xy 45.606858 -84.440208) (xy 45.697644 -84.421017) (xy 45.789936 -84.411387)
			(xy 45.836332 -84.410804) (xy 45.882727 -84.41141) (xy 45.975015 -84.421048) (xy 46.065799 -84.440237)
			(xy 46.154093 -84.468769) (xy 46.196758 -84.487004) (xy 46.206698 -84.490824) (xy 46.227966 -84.490824)
			(xy 46.237906 -84.487004) (xy 46.280564 -84.468749) (xy 46.368858 -84.440208) (xy 46.459644 -84.421017)
			(xy 46.551936 -84.411387) (xy 46.598332 -84.410804) (xy 46.644727 -84.41141) (xy 46.737015 -84.421048)
			(xy 46.827799 -84.440237) (xy 46.916093 -84.468769) (xy 46.958758 -84.487004) (xy 46.968698 -84.490824)
			(xy 46.989966 -84.490824) (xy 46.999906 -84.487004) (xy 47.042564 -84.468749) (xy 47.130858 -84.440208)
			(xy 47.221644 -84.421017) (xy 47.313936 -84.411387) (xy 47.360332 -84.410804) (xy 47.40268 -84.411285)
			(xy 47.486993 -84.419339) (xy 47.570158 -84.43537) (xy 47.651422 -84.459234) (xy 47.730051 -84.490715)
			(xy 47.805331 -84.529527) (xy 47.876581 -84.575319) (xy 47.943155 -84.627676) (xy 48.004452 -84.686124)
			(xy 48.059915 -84.750134) (xy 48.109043 -84.819126) (xy 48.15139 -84.892476) (xy 48.186573 -84.969519)
			(xy 48.214274 -85.049557) (xy 48.234241 -85.131866) (xy 48.246295 -85.2157) (xy 48.250325 -85.3003)
			(xy 48.246295 -85.3849) (xy 48.234241 -85.468734) (xy 48.214274 -85.551043) (xy 48.186573 -85.631081)
			(xy 48.15139 -85.708124) (xy 48.109043 -85.781474) (xy 48.059915 -85.850466) (xy 48.004452 -85.914476)
			(xy 47.943155 -85.972924) (xy 47.876581 -86.025281) (xy 47.805331 -86.071073) (xy 47.730051 -86.109885)
			(xy 47.651422 -86.141366) (xy 47.570158 -86.16523) (xy 47.486993 -86.181261) (xy 47.40268 -86.189315)
			(xy 47.360332 -86.18982) (xy 47.313937 -86.189225) (xy 47.221649 -86.179583) (xy 47.130865 -86.160391)
			(xy 47.042571 -86.131856) (xy 46.999906 -86.11362) (xy 46.989966 -86.1098) (xy 46.968698 -86.1098)
			(xy 46.958758 -86.11362) (xy 46.916092 -86.131855) (xy 46.827801 -86.160401) (xy 46.737017 -86.179597)
			(xy 46.644728 -86.189233) (xy 46.598332 -86.18982) (xy 46.551937 -86.189225) (xy 46.459649 -86.179583)
			(xy 46.368865 -86.160391) (xy 46.280571 -86.131856) (xy 46.237906 -86.11362) (xy 46.227966 -86.1098)
			(xy 46.206698 -86.1098) (xy 46.196758 -86.11362) (xy 46.154092 -86.131855) (xy 46.065801 -86.160401)
			(xy 45.975017 -86.179597) (xy 45.882728 -86.189233) (xy 45.836332 -86.18982) (xy 45.789937 -86.189225)
			(xy 45.697649 -86.179583) (xy 45.606865 -86.160391) (xy 45.518571 -86.131856) (xy 45.475906 -86.11362)
			(xy 45.465966 -86.1098) (xy 45.444698 -86.1098) (xy 45.434758 -86.11362) (xy 45.392092 -86.131855)
			(xy 45.303801 -86.160401) (xy 45.213017 -86.179597) (xy 45.120728 -86.189233) (xy 45.074332 -86.18982)
			(xy 45.031982 -86.189309) (xy 44.947666 -86.181261) (xy 44.864497 -86.165234) (xy 44.783228 -86.141374)
			(xy 44.704595 -86.109897) (xy 44.62931 -86.071087) (xy 44.558056 -86.025297) (xy 44.491477 -85.972941)
			(xy 44.430176 -85.914493) (xy 44.374709 -85.850482) (xy 44.325577 -85.781489) (xy 44.283227 -85.708138)
			(xy 44.248041 -85.631093) (xy 44.220338 -85.551052) (xy 44.200368 -85.46874) (xy 44.188314 -85.384903)
			(xy 44.184284 -85.3003) (xy 37.55665 -85.3003) (xy 37.569463 -85.332305) (xy 37.593324 -85.413572)
			(xy 37.609353 -85.496738) (xy 37.617404 -85.581052) (xy 37.617908 -85.6234) (xy 37.617421 -85.665351)
			(xy 37.609528 -85.748882) (xy 37.593812 -85.8313) (xy 37.570412 -85.911874) (xy 37.555424 -85.95106)
			(xy 37.552267 -85.9602) (xy 37.552252 -85.979519) (xy 37.555424 -85.988652) (xy 37.570414 -86.027838)
			(xy 37.593835 -86.108407) (xy 37.609556 -86.190826) (xy 37.617436 -86.27436) (xy 37.617908 -86.316312)
			(xy 37.617404 -86.35866) (xy 37.609353 -86.442974) (xy 37.593324 -86.52614) (xy 37.569463 -86.607407)
			(xy 37.537984 -86.686037) (xy 37.499173 -86.761318) (xy 37.453383 -86.83257) (xy 37.401027 -86.899146)
			(xy 37.342579 -86.960444) (xy 37.278569 -87.015909) (xy 37.209577 -87.065038) (xy 37.136227 -87.107387)
			(xy 37.059184 -87.142571) (xy 36.979145 -87.170273) (xy 36.896836 -87.190241) (xy 36.813001 -87.202294)
			(xy 36.7284 -87.206325) (xy 36.643799 -87.202294) (xy 36.559964 -87.190241) (xy 36.477655 -87.170273)
			(xy 36.397616 -87.142571) (xy 36.320573 -87.107387) (xy 36.247223 -87.065038) (xy 36.178231 -87.015909)
			(xy 36.114221 -86.960444) (xy 36.055773 -86.899146) (xy 36.003417 -86.83257) (xy 35.957627 -86.761318)
			(xy 35.918816 -86.686037) (xy 35.887337 -86.607407) (xy 35.863476 -86.52614) (xy 35.847447 -86.442974)
			(xy 35.839396 -86.35866) (xy 35.838892 -86.316312) (xy 33.960112 -86.316312) (xy 33.960308 -86.3346)
			(xy 33.959821 -86.376778) (xy 33.95182 -86.460754) (xy 33.935907 -86.543596) (xy 33.912227 -86.624561)
			(xy 33.880991 -86.702921) (xy 33.84248 -86.777974) (xy 33.79704 -86.849046) (xy 33.745078 -86.915498)
			(xy 33.687061 -86.976736) (xy 33.623509 -87.032208) (xy 33.554993 -87.081418) (xy 33.482128 -87.123923)
			(xy 33.405568 -87.159342) (xy 33.365948 -87.173816) (xy 33.355788 -87.177372) (xy 33.340548 -87.191596)
			(xy 33.30194 -87.278464) (xy 33.30194 -87.299546) (xy 33.306004 -87.309198) (xy 33.322795 -87.350367)
			(xy 33.349043 -87.435321) (xy 33.366692 -87.522469) (xy 33.375565 -87.610942) (xy 33.376108 -87.6554)
			(xy 33.375509 -87.701662) (xy 33.365882 -87.793684) (xy 33.346752 -87.884209) (xy 33.318326 -87.972259)
			(xy 33.300162 -88.01481) (xy 33.296032 -88.025498) (xy 33.296827 -88.048375) (xy 33.301686 -88.058752)
			(xy 33.320819 -88.096769) (xy 33.3526 -88.175726) (xy 33.376694 -88.257358) (xy 33.39288 -88.340919)
			(xy 33.40101 -88.425643) (xy 33.401508 -88.4682) (xy 33.400903 -88.514579) (xy 33.391253 -88.606833)
			(xy 33.372058 -88.697582) (xy 33.343527 -88.785842) (xy 33.305968 -88.870655) (xy 33.283398 -88.911176)
			(xy 33.277746 -88.922453) (xy 33.277063 -88.947632) (xy 33.282128 -88.959182) (xy 33.300178 -88.996302)
			(xy 33.330102 -89.073233) (xy 33.352773 -89.152605) (xy 33.367996 -89.233735) (xy 33.37564 -89.315927)
			(xy 33.376108 -89.3572) (xy 37.185092 -89.3572) (xy 37.185584 -89.314525) (xy 37.193782 -89.22957)
			(xy 37.210083 -89.145791) (xy 37.234337 -89.06396) (xy 37.249862 -89.024206) (xy 37.253139 -89.01496)
			(xy 37.253123 -88.995359) (xy 37.249862 -88.986106) (xy 37.23435 -88.946348) (xy 37.210108 -88.864516)
			(xy 37.193811 -88.780738) (xy 37.18561 -88.695786) (xy 37.185092 -88.653112) (xy 37.185583 -88.611161)
			(xy 37.193475 -88.52763) (xy 37.20919 -88.445212) (xy 37.232588 -88.364638) (xy 37.247576 -88.325452)
			(xy 37.250781 -88.316325) (xy 37.250765 -88.296994) (xy 37.247576 -88.28786) (xy 37.232589 -88.248673)
			(xy 37.209168 -88.168104) (xy 37.193446 -88.085686) (xy 37.185564 -88.002152) (xy 37.185092 -87.9602)
			(xy 37.185596 -87.917852) (xy 37.193647 -87.833538) (xy 37.209676 -87.750372) (xy 37.233537 -87.669105)
			(xy 37.265016 -87.590475) (xy 37.303827 -87.515194) (xy 37.349617 -87.443942) (xy 37.401973 -87.377366)
			(xy 37.460421 -87.316068) (xy 37.524431 -87.260603) (xy 37.593423 -87.211474) (xy 37.666773 -87.169125)
			(xy 37.743816 -87.133941) (xy 37.823855 -87.106239) (xy 37.906164 -87.086271) (xy 37.989999 -87.074218)
			(xy 38.0746 -87.070188) (xy 38.159201 -87.074218) (xy 38.243036 -87.086271) (xy 38.325345 -87.106239)
			(xy 38.405384 -87.133941) (xy 38.482427 -87.169125) (xy 38.555777 -87.211474) (xy 38.624769 -87.260603)
			(xy 38.688779 -87.316068) (xy 38.747227 -87.377366) (xy 38.799583 -87.443942) (xy 38.845373 -87.515194)
			(xy 38.884184 -87.590475) (xy 38.915663 -87.669105) (xy 38.939524 -87.750372) (xy 38.955553 -87.833538)
			(xy 38.963604 -87.917852) (xy 38.964108 -87.9602) (xy 38.963621 -88.002151) (xy 38.955728 -88.085682)
			(xy 38.940012 -88.1681) (xy 38.916612 -88.248674) (xy 38.901624 -88.28786) (xy 38.898467 -88.297)
			(xy 38.898452 -88.316319) (xy 38.901624 -88.325452) (xy 38.916614 -88.364638) (xy 38.940035 -88.445207)
			(xy 38.955756 -88.527626) (xy 38.963636 -88.61116) (xy 38.964108 -88.653112) (xy 38.963587 -88.695786)
			(xy 38.955397 -88.780741) (xy 38.939104 -88.864519) (xy 38.914858 -88.946351) (xy 38.899338 -88.986106)
			(xy 38.89611 -88.995365) (xy 38.896094 -89.014954) (xy 38.899338 -89.024206) (xy 38.914853 -89.063963)
			(xy 38.939095 -89.145795) (xy 38.955391 -89.229573) (xy 38.96359 -89.314526) (xy 38.964108 -89.3572)
			(xy 38.963604 -89.399548) (xy 38.955553 -89.483862) (xy 38.939524 -89.567028) (xy 38.915663 -89.648295)
			(xy 38.884184 -89.726925) (xy 38.845373 -89.802206) (xy 38.799583 -89.873458) (xy 38.747227 -89.940034)
			(xy 38.688779 -90.001332) (xy 38.624769 -90.056797) (xy 38.555777 -90.105926) (xy 38.482427 -90.148275)
			(xy 38.405384 -90.183459) (xy 38.325345 -90.211161) (xy 38.243036 -90.231129) (xy 38.159201 -90.243182)
			(xy 38.0746 -90.247213) (xy 37.989999 -90.243182) (xy 37.906164 -90.231129) (xy 37.823855 -90.211161)
			(xy 37.743816 -90.183459) (xy 37.666773 -90.148275) (xy 37.593423 -90.105926) (xy 37.524431 -90.056797)
			(xy 37.460421 -90.001332) (xy 37.401973 -89.940034) (xy 37.349617 -89.873458) (xy 37.303827 -89.802206)
			(xy 37.265016 -89.726925) (xy 37.233537 -89.648295) (xy 37.209676 -89.567028) (xy 37.193647 -89.483862)
			(xy 37.185596 -89.399548) (xy 37.185092 -89.3572) (xy 33.376108 -89.3572) (xy 33.375604 -89.399548)
			(xy 33.367553 -89.483862) (xy 33.351524 -89.567028) (xy 33.327663 -89.648295) (xy 33.296184 -89.726925)
			(xy 33.257373 -89.802206) (xy 33.211583 -89.873458) (xy 33.159227 -89.940034) (xy 33.100779 -90.001332)
			(xy 33.036769 -90.056797) (xy 32.967777 -90.105926) (xy 32.894427 -90.148275) (xy 32.817384 -90.183459)
			(xy 32.737345 -90.211161) (xy 32.655036 -90.231129) (xy 32.571201 -90.243182) (xy 32.4866 -90.247213)
			(xy 32.401999 -90.243182) (xy 32.318164 -90.231129) (xy 32.235855 -90.211161) (xy 32.155816 -90.183459)
			(xy 32.078773 -90.148275) (xy 32.005423 -90.105926) (xy 31.936431 -90.056797) (xy 31.872421 -90.001332)
			(xy 31.813973 -89.940034) (xy 31.761617 -89.873458) (xy 31.715827 -89.802206) (xy 31.677016 -89.726925)
			(xy 31.645537 -89.648295) (xy 31.621676 -89.567028) (xy 31.605647 -89.483862) (xy 31.597596 -89.399548)
			(xy 31.597092 -89.3572) (xy 19.840001 -89.3572) (xy 19.838724 -89.363828) (xy 19.814863 -89.445095)
			(xy 19.783384 -89.523725) (xy 19.744573 -89.599006) (xy 19.698783 -89.670258) (xy 19.646427 -89.736834)
			(xy 19.587979 -89.798132) (xy 19.523969 -89.853597) (xy 19.454977 -89.902726) (xy 19.381627 -89.945075)
			(xy 19.304584 -89.980259) (xy 19.224545 -90.007961) (xy 19.142236 -90.027929) (xy 19.058401 -90.039982)
			(xy 18.9738 -90.044013) (xy 18.889199 -90.039982) (xy 18.805364 -90.027929) (xy 18.723055 -90.007961)
			(xy 18.643016 -89.980259) (xy 18.565973 -89.945075) (xy 18.492623 -89.902726) (xy 18.423631 -89.853597)
			(xy 18.359621 -89.798132) (xy 18.301173 -89.736834) (xy 18.248817 -89.670258) (xy 18.203027 -89.599006)
			(xy 18.164216 -89.523725) (xy 18.132737 -89.445095) (xy 18.108876 -89.363828) (xy 18.092847 -89.280662)
			(xy 18.084796 -89.196348) (xy 18.084292 -89.154) (xy 18.084738 -89.115712) (xy 18.091356 -89.039422)
			(xy 18.1045 -88.963982) (xy 18.124074 -88.88995) (xy 18.136616 -88.853772) (xy 18.139257 -88.845334)
			(xy 18.139257 -88.827666) (xy 18.136616 -88.819228) (xy 18.12406 -88.783053) (xy 18.104463 -88.709024)
			(xy 18.091312 -88.633583) (xy 18.084703 -88.557289) (xy 18.084292 -88.519) (xy 18.084738 -88.480712)
			(xy 18.091356 -88.404422) (xy 18.1045 -88.328982) (xy 18.124074 -88.25495) (xy 18.136616 -88.218772)
			(xy 18.139257 -88.210334) (xy 18.139257 -88.192666) (xy 18.136616 -88.184228) (xy 18.12406 -88.148053)
			(xy 18.104463 -88.074024) (xy 18.091312 -87.998583) (xy 18.084703 -87.922289) (xy 18.084292 -87.884)
			(xy 18.084722 -87.843758) (xy 18.091989 -87.763602) (xy 18.106464 -87.68443) (xy 18.128028 -87.606888)
			(xy 18.156505 -87.53161) (xy 18.191662 -87.45921) (xy 18.212054 -87.424514) (xy 18.217388 -87.415624)
			(xy 18.220436 -87.395812) (xy 18.196814 -87.305134) (xy 18.184622 -87.289132) (xy 18.175732 -87.284052)
			(xy 18.139136 -87.262498) (xy 18.069815 -87.213416) (xy 18.005488 -87.157949) (xy 17.946741 -87.096603)
			(xy 17.89411 -87.029936) (xy 17.848074 -86.958556) (xy 17.809051 -86.883113) (xy 17.777398 -86.804293)
			(xy 17.753402 -86.722815) (xy 17.737282 -86.63942) (xy 17.729186 -86.554869) (xy 17.728692 -86.5124)
			(xy 14.894642 -86.5124) (xy 14.925309 -86.56193) (xy 14.961951 -86.635517) (xy 14.991647 -86.712171)
			(xy 15.014143 -86.791238) (xy 15.029248 -86.872043) (xy 15.036833 -86.953898) (xy 15.037308 -86.995)
			(xy 15.036841 -87.036208) (xy 15.029224 -87.11827) (xy 15.014046 -87.199276) (xy 14.991437 -87.27853)
			(xy 14.961592 -87.355351) (xy 14.924766 -87.429082) (xy 14.881275 -87.499088) (xy 14.831493 -87.564769)
			(xy 14.775847 -87.625562) (xy 14.714815 -87.680946) (xy 14.648919 -87.730444) (xy 14.578726 -87.773631)
			(xy 14.504837 -87.810139) (xy 14.427887 -87.839652) (xy 14.388338 -87.851234) (xy 14.377991 -87.854656)
			(xy 14.361357 -87.86871) (xy 14.351983 -87.888365) (xy 14.351254 -87.89924) (xy 14.349729 -87.947607)
			(xy 14.337494 -88.043602) (xy 14.314912 -88.137703) (xy 14.299184 -88.183466) (xy 14.296524 -88.191899)
			(xy 14.296536 -88.209572) (xy 14.299184 -88.21801) (xy 14.311751 -88.254181) (xy 14.331345 -88.328212)
			(xy 14.344493 -88.403654) (xy 14.351099 -88.479948) (xy 14.351508 -88.518238) (xy 14.351073 -88.556526)
			(xy 14.344452 -88.632816) (xy 14.331304 -88.708256) (xy 14.311728 -88.782288) (xy 14.299184 -88.818466)
			(xy 14.296524 -88.826899) (xy 14.296536 -88.844572) (xy 14.299184 -88.85301) (xy 14.311751 -88.889181)
			(xy 14.331345 -88.963212) (xy 14.344493 -89.038654) (xy 14.351099 -89.114948) (xy 14.351508 -89.153238)
			(xy 14.351004 -89.195586) (xy 14.342953 -89.2799) (xy 14.326924 -89.363066) (xy 14.303063 -89.444333)
			(xy 14.271584 -89.522963) (xy 14.232773 -89.598244) (xy 14.186983 -89.669496) (xy 14.134627 -89.736072)
			(xy 14.076179 -89.79737) (xy 14.012169 -89.852835) (xy 13.943177 -89.901964) (xy 13.869827 -89.944313)
			(xy 13.792784 -89.979497) (xy 13.712745 -90.007199) (xy 13.630436 -90.027167) (xy 13.546601 -90.03922)
			(xy 13.462 -90.043251) (xy 13.377399 -90.03922) (xy 13.293564 -90.027167) (xy 13.211255 -90.007199)
			(xy 13.131216 -89.979497) (xy 13.054173 -89.944313) (xy 12.980823 -89.901964) (xy 12.911831 -89.852835)
			(xy 12.847821 -89.79737) (xy 12.789373 -89.736072) (xy 12.737017 -89.669496) (xy 12.691227 -89.598244)
			(xy 12.652416 -89.522963) (xy 12.620937 -89.444333) (xy 12.597076 -89.363066) (xy 12.581047 -89.2799)
			(xy 12.572996 -89.195586) (xy 12.572492 -89.153238) (xy 1.651254 -89.153238) (xy 1.651254 -91.878912)
			(xy 3.555492 -91.878912) (xy 3.556079 -91.832517) (xy 3.565723 -91.740228) (xy 3.584918 -91.649445)
			(xy 3.613455 -91.561151) (xy 3.631692 -91.518486) (xy 3.63559 -91.508562) (xy 3.635594 -91.48726)
			(xy 3.631692 -91.477338) (xy 3.613451 -91.434674) (xy 3.584906 -91.346382) (xy 3.565712 -91.255598)
			(xy 3.556077 -91.163308) (xy 3.555492 -91.116912) (xy 3.555964 -91.075809) (xy 3.563548 -90.993954)
			(xy 3.578652 -90.913147) (xy 3.601148 -90.834079) (xy 3.630843 -90.757424) (xy 3.667485 -90.683836)
			(xy 3.71076 -90.613943) (xy 3.7603 -90.548341) (xy 3.815681 -90.487589) (xy 3.876432 -90.432207)
			(xy 3.942033 -90.382667) (xy 4.011926 -90.339391) (xy 4.085513 -90.302748) (xy 4.162168 -90.273052)
			(xy 4.241236 -90.250555) (xy 4.322042 -90.235449) (xy 4.403897 -90.227864) (xy 4.445 -90.227404)
			(xy 4.491396 -90.227986) (xy 4.583684 -90.237631) (xy 4.674468 -90.256827) (xy 4.762761 -90.285366)
			(xy 4.805426 -90.303604) (xy 4.815366 -90.307424) (xy 4.836634 -90.307424) (xy 4.846574 -90.303604)
			(xy 4.889236 -90.28536) (xy 4.977529 -90.256816) (xy 5.068314 -90.237622) (xy 5.160604 -90.227989)
			(xy 5.207 -90.227404) (xy 5.253396 -90.227986) (xy 5.345684 -90.237631) (xy 5.436468 -90.256827)
			(xy 5.524761 -90.285366) (xy 5.567426 -90.303604) (xy 5.577366 -90.307424) (xy 5.598634 -90.307424)
			(xy 5.608574 -90.303604) (xy 5.651236 -90.28536) (xy 5.739529 -90.256816) (xy 5.830314 -90.237622)
			(xy 5.922604 -90.227989) (xy 5.969 -90.227404) (xy 6.015396 -90.227986) (xy 6.107684 -90.237631)
			(xy 6.198468 -90.256827) (xy 6.286761 -90.285366) (xy 6.329426 -90.303604) (xy 6.339366 -90.307424)
			(xy 6.360634 -90.307424) (xy 6.370574 -90.303604) (xy 6.413236 -90.28536) (xy 6.501529 -90.256816)
			(xy 6.592314 -90.237622) (xy 6.684604 -90.227989) (xy 6.731 -90.227404) (xy 6.772103 -90.227862)
			(xy 6.853959 -90.235447) (xy 6.934766 -90.250553) (xy 7.013834 -90.27305) (xy 7.090489 -90.302746)
			(xy 7.164077 -90.339389) (xy 7.233971 -90.382665) (xy 7.299573 -90.432205) (xy 7.360324 -90.487587)
			(xy 7.415706 -90.548339) (xy 7.465246 -90.613941) (xy 7.508522 -90.683834) (xy 7.545165 -90.757423)
			(xy 7.574861 -90.834078) (xy 7.597358 -90.913146) (xy 7.612463 -90.993953) (xy 7.620048 -91.075809)
			(xy 7.620508 -91.116912) (xy 7.619929 -91.163308) (xy 7.610283 -91.255596) (xy 7.591086 -91.34638)
			(xy 7.562546 -91.434673) (xy 7.544308 -91.477338) (xy 7.540396 -91.487258) (xy 7.5404 -91.508564)
			(xy 7.544308 -91.518486) (xy 7.562557 -91.561147) (xy 7.5911 -91.64944) (xy 7.610292 -91.740225)
			(xy 7.619924 -91.832516) (xy 7.620508 -91.878912) (xy 7.620045 -91.920015) (xy 7.612459 -92.001869)
			(xy 7.597353 -92.082675) (xy 7.574855 -92.161742) (xy 7.545158 -92.238396) (xy 7.508516 -92.311983)
			(xy 7.465239 -92.381875) (xy 7.415699 -92.447476) (xy 7.360317 -92.508226) (xy 7.299566 -92.563607)
			(xy 7.233965 -92.613146) (xy 7.164072 -92.656421) (xy 7.090485 -92.693063) (xy 7.01383 -92.722759)
			(xy 6.934763 -92.745255) (xy 6.853957 -92.76036) (xy 6.772103 -92.767945) (xy 6.731 -92.76842) (xy 6.684604 -92.767836)
			(xy 6.592316 -92.758191) (xy 6.501532 -92.738996) (xy 6.413239 -92.710458) (xy 6.370574 -92.69222)
			(xy 6.360634 -92.6884) (xy 6.339366 -92.6884) (xy 6.329426 -92.69222) (xy 6.286764 -92.710466) (xy 6.198472 -92.739009)
			(xy 6.107686 -92.758202) (xy 6.015396 -92.767835) (xy 5.969 -92.76842) (xy 5.922604 -92.767836) (xy 5.830316 -92.758191)
			(xy 5.739532 -92.738996) (xy 5.651239 -92.710458) (xy 5.608574 -92.69222) (xy 5.598634 -92.6884)
			(xy 5.577366 -92.6884) (xy 5.567426 -92.69222) (xy 5.524764 -92.710466) (xy 5.436472 -92.739009)
			(xy 5.345686 -92.758202) (xy 5.253396 -92.767835) (xy 5.207 -92.76842) (xy 5.160604 -92.767836) (xy 5.068316 -92.758191)
			(xy 4.977532 -92.738996) (xy 4.889239 -92.710458) (xy 4.846574 -92.69222) (xy 4.836634 -92.6884)
			(xy 4.815366 -92.6884) (xy 4.805426 -92.69222) (xy 4.762764 -92.710466) (xy 4.674472 -92.739009)
			(xy 4.583686 -92.758202) (xy 4.491396 -92.767835) (xy 4.445 -92.76842) (xy 4.403898 -92.767943) (xy 4.322043 -92.760358)
			(xy 4.241238 -92.745253) (xy 4.162171 -92.722757) (xy 4.085518 -92.693061) (xy 4.011931 -92.656419)
			(xy 3.942039 -92.613144) (xy 3.876438 -92.563605) (xy 3.815688 -92.508224) (xy 3.760307 -92.447474)
			(xy 3.710767 -92.381873) (xy 3.667492 -92.311981) (xy 3.63085 -92.238394) (xy 3.601154 -92.16174)
			(xy 3.578657 -92.082674) (xy 3.563552 -92.001869) (xy 3.555967 -91.920014) (xy 3.555492 -91.878912)
			(xy 1.651254 -91.878912) (xy 1.651254 -93.979238) (xy 12.572492 -93.979238) (xy 12.57292 -93.94095)
			(xy 12.579543 -93.864659) (xy 12.592693 -93.78922) (xy 12.612271 -93.715187) (xy 12.624816 -93.67901)
			(xy 12.627438 -93.670567) (xy 12.627451 -93.652904) (xy 12.624816 -93.644466) (xy 12.612242 -93.608297)
			(xy 12.59265 -93.534266) (xy 12.579504 -93.458823) (xy 12.5729 -93.382528) (xy 12.572492 -93.344238)
			(xy 12.57292 -93.30595) (xy 12.579543 -93.229659) (xy 12.592693 -93.15422) (xy 12.612271 -93.080187)
			(xy 12.624816 -93.04401) (xy 12.627438 -93.035567) (xy 12.627451 -93.017904) (xy 12.624816 -93.009466)
			(xy 12.612242 -92.973297) (xy 12.59265 -92.899266) (xy 12.579504 -92.823823) (xy 12.5729 -92.747528)
			(xy 12.572492 -92.709238) (xy 12.572996 -92.66689) (xy 12.581047 -92.582576) (xy 12.597076 -92.49941)
			(xy 12.620937 -92.418143) (xy 12.652416 -92.339513) (xy 12.691227 -92.264232) (xy 12.737017 -92.19298)
			(xy 12.789373 -92.126404) (xy 12.847821 -92.065106) (xy 12.911831 -92.009641) (xy 12.980823 -91.960512)
			(xy 13.054173 -91.918163) (xy 13.131216 -91.882979) (xy 13.211255 -91.855277) (xy 13.293564 -91.835309)
			(xy 13.377399 -91.823256) (xy 13.462 -91.819226) (xy 13.546601 -91.823256) (xy 13.630436 -91.835309)
			(xy 13.712745 -91.855277) (xy 13.792784 -91.882979) (xy 13.869827 -91.918163) (xy 13.943177 -91.960512)
			(xy 14.012169 -92.009641) (xy 14.076179 -92.065106) (xy 14.134627 -92.126404) (xy 14.186983 -92.19298)
			(xy 14.232773 -92.264232) (xy 14.271584 -92.339513) (xy 14.303063 -92.418143) (xy 14.326924 -92.49941)
			(xy 14.342953 -92.582576) (xy 14.351004 -92.66689) (xy 14.351508 -92.709238) (xy 14.351073 -92.747526)
			(xy 14.344452 -92.823816) (xy 14.331304 -92.899256) (xy 14.311728 -92.973288) (xy 14.299184 -93.009466)
			(xy 14.296524 -93.017899) (xy 14.296536 -93.035572) (xy 14.299184 -93.04401) (xy 14.311751 -93.080181)
			(xy 14.331345 -93.154212) (xy 14.344493 -93.229654) (xy 14.351099 -93.305948) (xy 14.351508 -93.344238)
			(xy 14.351073 -93.382526) (xy 14.344452 -93.458816) (xy 14.331304 -93.534256) (xy 14.311728 -93.608288)
			(xy 14.299184 -93.644466) (xy 14.296524 -93.652899) (xy 14.296536 -93.670572) (xy 14.299184 -93.67901)
			(xy 14.311751 -93.715181) (xy 14.331345 -93.789212) (xy 14.344493 -93.864654) (xy 14.351099 -93.940948)
			(xy 14.351508 -93.979238) (xy 14.351004 -94.021586) (xy 14.342953 -94.1059) (xy 14.342741 -94.107)
			(xy 18.015204 -94.107) (xy 18.01565 -94.068712) (xy 18.022268 -93.992422) (xy 18.035412 -93.916982)
			(xy 18.054985 -93.84295) (xy 18.067528 -93.806772) (xy 18.070168 -93.798334) (xy 18.070168 -93.780666)
			(xy 18.067528 -93.772228) (xy 18.054972 -93.736053) (xy 18.035375 -93.662024) (xy 18.022224 -93.586583)
			(xy 18.015615 -93.510289) (xy 18.015204 -93.472) (xy 18.01565 -93.433712) (xy 18.022268 -93.357422)
			(xy 18.035412 -93.281982) (xy 18.054985 -93.20795) (xy 18.067528 -93.171772) (xy 18.070168 -93.163334)
			(xy 18.070168 -93.145666) (xy 18.067528 -93.137228) (xy 18.054972 -93.101053) (xy 18.035375 -93.027024)
			(xy 18.022224 -92.951583) (xy 18.015615 -92.875289) (xy 18.015204 -92.837) (xy 18.015708 -92.794652)
			(xy 18.023759 -92.710338) (xy 18.039788 -92.627172) (xy 18.063649 -92.545905) (xy 18.095128 -92.467275)
			(xy 18.133939 -92.391994) (xy 18.179729 -92.320742) (xy 18.232085 -92.254166) (xy 18.290533 -92.192868)
			(xy 18.354543 -92.137403) (xy 18.423535 -92.088274) (xy 18.496885 -92.045925) (xy 18.573928 -92.010741)
			(xy 18.653967 -91.983039) (xy 18.736276 -91.963071) (xy 18.820111 -91.951018) (xy 18.904712 -91.946988)
			(xy 18.989313 -91.951018) (xy 19.073148 -91.963071) (xy 19.155457 -91.983039) (xy 19.235496 -92.010741)
			(xy 19.312539 -92.045925) (xy 19.385889 -92.088274) (xy 19.454881 -92.137403) (xy 19.518891 -92.192868)
			(xy 19.577339 -92.254166) (xy 19.629695 -92.320742) (xy 19.675485 -92.391994) (xy 19.714296 -92.467275)
			(xy 19.745775 -92.545905) (xy 19.769636 -92.627172) (xy 19.785665 -92.710338) (xy 19.793716 -92.794652)
			(xy 19.79422 -92.837) (xy 19.793773 -92.875288) (xy 19.787155 -92.951578) (xy 19.774011 -93.027017)
			(xy 19.754438 -93.10105) (xy 19.741896 -93.137228) (xy 19.739254 -93.145666) (xy 19.739254 -93.163334)
			(xy 19.741896 -93.171772) (xy 19.754453 -93.207946) (xy 19.774049 -93.281976) (xy 19.7872 -93.357417)
			(xy 19.793809 -93.433711) (xy 19.79422 -93.472) (xy 19.793773 -93.510288) (xy 19.787155 -93.586578)
			(xy 19.774011 -93.662017) (xy 19.754438 -93.73605) (xy 19.741896 -93.772228) (xy 19.739254 -93.780666)
			(xy 19.739254 -93.798334) (xy 19.741896 -93.806772) (xy 19.754453 -93.842946) (xy 19.774049 -93.916976)
			(xy 19.7872 -93.992417) (xy 19.793809 -94.068711) (xy 19.79422 -94.107) (xy 19.793716 -94.149348)
			(xy 19.788058 -94.2086) (xy 31.571692 -94.2086) (xy 31.572124 -94.168487) (xy 31.579356 -94.088587)
			(xy 31.593752 -94.009663) (xy 31.615195 -93.932356) (xy 31.643511 -93.857293) (xy 31.660592 -93.820996)
			(xy 31.6647 -93.811172) (xy 31.665348 -93.789911) (xy 31.661862 -93.779848) (xy 31.646338 -93.740061)
			(xy 31.62208 -93.658166) (xy 31.605783 -93.574324) (xy 31.597597 -93.489306) (xy 31.597092 -93.4466)
			(xy 31.597669 -93.401417) (xy 31.60683 -93.311516) (xy 31.625059 -93.223007) (xy 31.652168 -93.136803)
			(xy 31.687876 -93.053791) (xy 31.70936 -93.014038) (xy 31.713235 -93.006354) (xy 31.716122 -92.9894)
			(xy 31.713235 -92.972446) (xy 31.70936 -92.964762) (xy 31.687877 -92.925008) (xy 31.652161 -92.841998)
			(xy 31.625046 -92.755795) (xy 31.606813 -92.667285) (xy 31.597649 -92.577384) (xy 31.597092 -92.5322)
			(xy 31.597596 -92.489852) (xy 31.605647 -92.405538) (xy 31.621676 -92.322372) (xy 31.645537 -92.241105)
			(xy 31.677016 -92.162475) (xy 31.715827 -92.087194) (xy 31.761617 -92.015942) (xy 31.813973 -91.949366)
			(xy 31.872421 -91.888068) (xy 31.936431 -91.832603) (xy 32.005423 -91.783474) (xy 32.078773 -91.741125)
			(xy 32.155816 -91.705941) (xy 32.235855 -91.678239) (xy 32.318164 -91.658271) (xy 32.401999 -91.646218)
			(xy 32.4866 -91.642188) (xy 32.571201 -91.646218) (xy 32.655036 -91.658271) (xy 32.737345 -91.678239)
			(xy 32.817384 -91.705941) (xy 32.894427 -91.741125) (xy 32.967777 -91.783474) (xy 33.036769 -91.832603)
			(xy 33.100779 -91.888068) (xy 33.159227 -91.949366) (xy 33.211583 -92.015942) (xy 33.257373 -92.087194)
			(xy 33.296184 -92.162475) (xy 33.327663 -92.241105) (xy 33.351524 -92.322372) (xy 33.367553 -92.405538)
			(xy 33.375604 -92.489852) (xy 33.376108 -92.5322) (xy 33.375531 -92.577383) (xy 33.36637 -92.667284)
			(xy 33.348141 -92.755793) (xy 33.321032 -92.841997) (xy 33.285324 -92.925009) (xy 33.26384 -92.964762)
			(xy 33.259965 -92.972446) (xy 33.257078 -92.9894) (xy 33.259965 -93.006354) (xy 33.26384 -93.014038)
			(xy 33.285323 -93.053792) (xy 33.321039 -93.136802) (xy 33.348154 -93.223005) (xy 33.366387 -93.311515)
			(xy 33.375551 -93.401416) (xy 33.376108 -93.4466) (xy 33.375676 -93.486713) (xy 33.368444 -93.566613)
			(xy 33.354048 -93.645537) (xy 33.332605 -93.722844) (xy 33.304289 -93.797907) (xy 33.287208 -93.834204)
			(xy 33.2831 -93.844028) (xy 33.282452 -93.865289) (xy 33.285938 -93.875352) (xy 33.301462 -93.915139)
			(xy 33.32572 -93.997034) (xy 33.337221 -94.0562) (xy 37.185092 -94.0562) (xy 37.185584 -94.013525)
			(xy 37.193782 -93.92857) (xy 37.210083 -93.844791) (xy 37.234337 -93.76296) (xy 37.249862 -93.723206)
			(xy 37.253139 -93.71396) (xy 37.253123 -93.694359) (xy 37.249862 -93.685106) (xy 37.23435 -93.645348)
			(xy 37.210108 -93.563516) (xy 37.193811 -93.479738) (xy 37.18561 -93.394786) (xy 37.185092 -93.352112)
			(xy 37.185526 -93.311974) (xy 37.19274 -93.232022) (xy 37.207128 -93.153046) (xy 37.228573 -93.075687)
			(xy 37.256901 -93.000575) (xy 37.273992 -92.964254) (xy 37.278542 -92.95367) (xy 37.278524 -92.930651)
			(xy 37.273992 -92.920058) (xy 37.256885 -92.883745) (xy 37.228557 -92.808631) (xy 37.207114 -92.731271)
			(xy 37.19273 -92.652292) (xy 37.185523 -92.572339) (xy 37.185092 -92.5322) (xy 37.185596 -92.489852)
			(xy 37.193647 -92.405538) (xy 37.209676 -92.322372) (xy 37.233537 -92.241105) (xy 37.265016 -92.162475)
			(xy 37.303827 -92.087194) (xy 37.349617 -92.015942) (xy 37.401973 -91.949366) (xy 37.460421 -91.888068)
			(xy 37.524431 -91.832603) (xy 37.593423 -91.783474) (xy 37.666773 -91.741125) (xy 37.743816 -91.705941)
			(xy 37.823855 -91.678239) (xy 37.906164 -91.658271) (xy 37.989999 -91.646218) (xy 38.0746 -91.642188)
			(xy 38.159201 -91.646218) (xy 38.243036 -91.658271) (xy 38.325345 -91.678239) (xy 38.405384 -91.705941)
			(xy 38.482427 -91.741125) (xy 38.555777 -91.783474) (xy 38.624769 -91.832603) (xy 38.688779 -91.888068)
			(xy 38.747227 -91.949366) (xy 38.799583 -92.015942) (xy 38.803258 -92.02166) (xy 44.032424 -92.02166)
			(xy 44.032857 -91.983372) (xy 44.039478 -91.907082) (xy 44.052626 -91.831642) (xy 44.072204 -91.75761)
			(xy 44.084748 -91.721432) (xy 44.087408 -91.712999) (xy 44.087395 -91.695326) (xy 44.084748 -91.686888)
			(xy 44.072177 -91.650718) (xy 44.052585 -91.576687) (xy 44.039438 -91.501244) (xy 44.032833 -91.42495)
			(xy 44.032424 -91.38666) (xy 44.032829 -91.345556) (xy 44.040417 -91.263699) (xy 44.055527 -91.182891)
			(xy 44.078027 -91.103822) (xy 44.107728 -91.027166) (xy 44.144374 -90.953578) (xy 44.187654 -90.883685)
			(xy 44.237198 -90.818084) (xy 44.292584 -90.757333) (xy 44.353339 -90.701952) (xy 44.418945 -90.652413)
			(xy 44.488841 -90.609139) (xy 44.562432 -90.572499) (xy 44.63909 -90.542805) (xy 44.718161 -90.52031)
			(xy 44.79897 -90.505207) (xy 44.880828 -90.497625) (xy 44.921932 -90.497152) (xy 44.968327 -90.497754)
			(xy 45.060615 -90.507393) (xy 45.151399 -90.526583) (xy 45.239693 -90.555116) (xy 45.282358 -90.573352)
			(xy 45.292298 -90.577172) (xy 45.313566 -90.577172) (xy 45.323506 -90.573352) (xy 45.366163 -90.555094)
			(xy 45.454457 -90.526554) (xy 45.545244 -90.507365) (xy 45.637536 -90.497735) (xy 45.683932 -90.497152)
			(xy 45.730327 -90.497754) (xy 45.822615 -90.507393) (xy 45.913399 -90.526583) (xy 46.001693 -90.555116)
			(xy 46.044358 -90.573352) (xy 46.054298 -90.577172) (xy 46.075566 -90.577172) (xy 46.085506 -90.573352)
			(xy 46.128163 -90.555094) (xy 46.216457 -90.526554) (xy 46.307244 -90.507365) (xy 46.399536 -90.497735)
			(xy 46.445932 -90.497152) (xy 46.492327 -90.497754) (xy 46.584615 -90.507393) (xy 46.675399 -90.526583)
			(xy 46.763693 -90.555116) (xy 46.806358 -90.573352) (xy 46.816298 -90.577172) (xy 46.837566 -90.577172)
			(xy 46.847506 -90.573352) (xy 46.890163 -90.555094) (xy 46.978457 -90.526554) (xy 47.069244 -90.507365)
			(xy 47.161536 -90.497735) (xy 47.207932 -90.497152) (xy 47.249034 -90.497636) (xy 47.330887 -90.505223)
			(xy 47.41169 -90.52033) (xy 47.490755 -90.542828) (xy 47.567408 -90.572525) (xy 47.640993 -90.609167)
			(xy 47.710884 -90.652442) (xy 47.776483 -90.701981) (xy 47.837233 -90.757362) (xy 47.892614 -90.81811)
			(xy 47.942153 -90.88371) (xy 47.985429 -90.9536) (xy 48.022072 -91.027185) (xy 48.051769 -91.103837)
			(xy 48.074268 -91.182902) (xy 48.089375 -91.263705) (xy 48.096964 -91.345558) (xy 48.09744 -91.38666)
			(xy 48.097009 -91.424948) (xy 48.090387 -91.501238) (xy 48.077238 -91.576678) (xy 48.05766 -91.65071)
			(xy 48.045116 -91.686888) (xy 48.042493 -91.695331) (xy 48.04248 -91.712994) (xy 48.045116 -91.721432)
			(xy 48.057691 -91.7576) (xy 48.077282 -91.831632) (xy 48.090428 -91.907075) (xy 48.097032 -91.98337)
			(xy 48.09744 -92.02166) (xy 48.09691 -92.062762) (xy 48.089329 -92.144614) (xy 48.074227 -92.225418)
			(xy 48.051735 -92.304484) (xy 48.022043 -92.381138) (xy 47.985405 -92.454725) (xy 47.942134 -92.524617)
			(xy 47.892598 -92.590218) (xy 47.83722 -92.65097) (xy 47.776474 -92.706352) (xy 47.710876 -92.755893)
			(xy 47.640988 -92.79917) (xy 47.567404 -92.835814) (xy 47.490753 -92.865512) (xy 47.411689 -92.888011)
			(xy 47.330886 -92.903119) (xy 47.249034 -92.910706) (xy 47.207932 -92.911168) (xy 47.161537 -92.910577)
			(xy 47.069248 -92.900935) (xy 46.978465 -92.881741) (xy 46.890171 -92.853205) (xy 46.847506 -92.834968)
			(xy 46.837566 -92.831148) (xy 46.816298 -92.831148) (xy 46.806358 -92.834968) (xy 46.76369 -92.8532)
			(xy 46.6754 -92.881748) (xy 46.584617 -92.900945) (xy 46.492328 -92.910581) (xy 46.445932 -92.911168)
			(xy 46.399537 -92.910577) (xy 46.307248 -92.900935) (xy 46.216465 -92.881741) (xy 46.128171 -92.853205)
			(xy 46.085506 -92.834968) (xy 46.075566 -92.831148) (xy 46.054298 -92.831148) (xy 46.044358 -92.834968)
			(xy 46.00169 -92.8532) (xy 45.9134 -92.881748) (xy 45.822617 -92.900945) (xy 45.730328 -92.910581)
			(xy 45.683932 -92.911168) (xy 45.637537 -92.910577) (xy 45.545248 -92.900935) (xy 45.454465 -92.881741)
			(xy 45.366171 -92.853205) (xy 45.323506 -92.834968) (xy 45.313566 -92.831148) (xy 45.292298 -92.831148)
			(xy 45.282358 -92.834968) (xy 45.23969 -92.8532) (xy 45.1514 -92.881748) (xy 45.060617 -92.900945)
			(xy 44.968328 -92.910581) (xy 44.921932 -92.911168) (xy 44.880828 -92.910717) (xy 44.798971 -92.903135)
			(xy 44.718163 -92.888031) (xy 44.639093 -92.865536) (xy 44.562436 -92.83584) (xy 44.488846 -92.799198)
			(xy 44.418952 -92.755922) (xy 44.353349 -92.706381) (xy 44.292597 -92.650998) (xy 44.237214 -92.590245)
			(xy 44.187674 -92.524642) (xy 44.144398 -92.454747) (xy 44.107757 -92.381157) (xy 44.078062 -92.3045)
			(xy 44.055567 -92.225429) (xy 44.040464 -92.144621) (xy 44.032882 -92.062764) (xy 44.032424 -92.02166)
			(xy 38.803258 -92.02166) (xy 38.845373 -92.087194) (xy 38.884184 -92.162475) (xy 38.915663 -92.241105)
			(xy 38.939524 -92.322372) (xy 38.955553 -92.405538) (xy 38.963604 -92.489852) (xy 38.964108 -92.5322)
			(xy 38.963678 -92.572338) (xy 38.956464 -92.65229) (xy 38.942074 -92.731267) (xy 38.920628 -92.808626)
			(xy 38.892299 -92.883738) (xy 38.875208 -92.920058) (xy 38.870715 -92.93066) (xy 38.870697 -92.953661)
			(xy 38.875208 -92.964254) (xy 38.89232 -93.000565) (xy 38.920646 -93.075679) (xy 38.942088 -93.15304)
			(xy 38.956471 -93.232019) (xy 38.963678 -93.311973) (xy 38.964108 -93.352112) (xy 38.963587 -93.394786)
			(xy 38.955397 -93.479741) (xy 38.939104 -93.563519) (xy 38.914858 -93.645351) (xy 38.899338 -93.685106)
			(xy 38.89611 -93.694365) (xy 38.896094 -93.713954) (xy 38.899338 -93.723206) (xy 38.914853 -93.762963)
			(xy 38.939095 -93.844795) (xy 38.955391 -93.928573) (xy 38.96359 -94.013526) (xy 38.964108 -94.0562)
			(xy 38.963604 -94.098548) (xy 38.955553 -94.182862) (xy 38.939524 -94.266028) (xy 38.915663 -94.347295)
			(xy 38.884184 -94.425925) (xy 38.845373 -94.501206) (xy 38.799583 -94.572458) (xy 38.747227 -94.639034)
			(xy 38.688779 -94.700332) (xy 38.624769 -94.755797) (xy 38.555777 -94.804926) (xy 38.482427 -94.847275)
			(xy 38.405384 -94.882459) (xy 38.325345 -94.910161) (xy 38.243036 -94.930129) (xy 38.159201 -94.942182)
			(xy 38.0746 -94.946213) (xy 37.989999 -94.942182) (xy 37.906164 -94.930129) (xy 37.823855 -94.910161)
			(xy 37.743816 -94.882459) (xy 37.666773 -94.847275) (xy 37.593423 -94.804926) (xy 37.524431 -94.755797)
			(xy 37.460421 -94.700332) (xy 37.401973 -94.639034) (xy 37.349617 -94.572458) (xy 37.303827 -94.501206)
			(xy 37.265016 -94.425925) (xy 37.233537 -94.347295) (xy 37.209676 -94.266028) (xy 37.193647 -94.182862)
			(xy 37.185596 -94.098548) (xy 37.185092 -94.0562) (xy 33.337221 -94.0562) (xy 33.342017 -94.080876)
			(xy 33.350203 -94.165894) (xy 33.350708 -94.2086) (xy 33.350204 -94.250948) (xy 33.342153 -94.335262)
			(xy 33.326124 -94.418428) (xy 33.302263 -94.499695) (xy 33.270784 -94.578325) (xy 33.231973 -94.653606)
			(xy 33.186183 -94.724858) (xy 33.133827 -94.791434) (xy 33.075379 -94.852732) (xy 33.011369 -94.908197)
			(xy 32.942377 -94.957326) (xy 32.869027 -94.999675) (xy 32.791984 -95.034859) (xy 32.711945 -95.062561)
			(xy 32.629636 -95.082529) (xy 32.545801 -95.094582) (xy 32.4612 -95.098613) (xy 32.376599 -95.094582)
			(xy 32.292764 -95.082529) (xy 32.210455 -95.062561) (xy 32.130416 -95.034859) (xy 32.053373 -94.999675)
			(xy 31.980023 -94.957326) (xy 31.911031 -94.908197) (xy 31.847021 -94.852732) (xy 31.788573 -94.791434)
			(xy 31.736217 -94.724858) (xy 31.690427 -94.653606) (xy 31.651616 -94.578325) (xy 31.620137 -94.499695)
			(xy 31.596276 -94.418428) (xy 31.580247 -94.335262) (xy 31.572196 -94.250948) (xy 31.571692 -94.2086)
			(xy 19.788058 -94.2086) (xy 19.785665 -94.233662) (xy 19.769636 -94.316828) (xy 19.745775 -94.398095)
			(xy 19.714296 -94.476725) (xy 19.675485 -94.552006) (xy 19.629695 -94.623258) (xy 19.577339 -94.689834)
			(xy 19.518891 -94.751132) (xy 19.454881 -94.806597) (xy 19.385889 -94.855726) (xy 19.312539 -94.898075)
			(xy 19.235496 -94.933259) (xy 19.155457 -94.960961) (xy 19.073148 -94.980929) (xy 18.989313 -94.992982)
			(xy 18.904712 -94.997013) (xy 18.820111 -94.992982) (xy 18.736276 -94.980929) (xy 18.653967 -94.960961)
			(xy 18.573928 -94.933259) (xy 18.496885 -94.898075) (xy 18.423535 -94.855726) (xy 18.354543 -94.806597)
			(xy 18.290533 -94.751132) (xy 18.232085 -94.689834) (xy 18.179729 -94.623258) (xy 18.133939 -94.552006)
			(xy 18.095128 -94.476725) (xy 18.063649 -94.398095) (xy 18.039788 -94.316828) (xy 18.023759 -94.233662)
			(xy 18.015708 -94.149348) (xy 18.015204 -94.107) (xy 14.342741 -94.107) (xy 14.326924 -94.189066)
			(xy 14.303063 -94.270333) (xy 14.271584 -94.348963) (xy 14.232773 -94.424244) (xy 14.186983 -94.495496)
			(xy 14.134627 -94.562072) (xy 14.076179 -94.62337) (xy 14.012169 -94.678835) (xy 13.943177 -94.727964)
			(xy 13.869827 -94.770313) (xy 13.792784 -94.805497) (xy 13.712745 -94.833199) (xy 13.630436 -94.853167)
			(xy 13.546601 -94.86522) (xy 13.462 -94.869251) (xy 13.377399 -94.86522) (xy 13.293564 -94.853167)
			(xy 13.211255 -94.833199) (xy 13.131216 -94.805497) (xy 13.054173 -94.770313) (xy 12.980823 -94.727964)
			(xy 12.911831 -94.678835) (xy 12.847821 -94.62337) (xy 12.789373 -94.562072) (xy 12.737017 -94.495496)
			(xy 12.691227 -94.424244) (xy 12.652416 -94.348963) (xy 12.620937 -94.270333) (xy 12.597076 -94.189066)
			(xy 12.581047 -94.1059) (xy 12.572996 -94.021586) (xy 12.572492 -93.979238) (xy 1.651254 -93.979238)
			(xy 1.651254 -94.100904) (xy 1.652778 -94.15145) (xy 1.651254 -94.201996) (xy 1.651254 -98.975348)
			(xy 20.065996 -98.975348) (xy 20.065996 -98.890652) (xy 20.074047 -98.806338) (xy 20.090076 -98.723172)
			(xy 20.113937 -98.641905) (xy 20.145416 -98.563275) (xy 20.184227 -98.487994) (xy 20.230017 -98.416742)
			(xy 20.282373 -98.350166) (xy 20.340821 -98.288868) (xy 20.404831 -98.233403) (xy 20.473823 -98.184274)
			(xy 20.547173 -98.141925) (xy 20.624216 -98.106741) (xy 20.704255 -98.079039) (xy 20.786564 -98.059071)
			(xy 20.870399 -98.047018) (xy 20.955 -98.042988) (xy 21.039601 -98.047018) (xy 21.123436 -98.059071)
			(xy 21.205745 -98.079039) (xy 21.285784 -98.106741) (xy 21.362827 -98.141925) (xy 21.436177 -98.184274)
			(xy 21.505169 -98.233403) (xy 21.569179 -98.288868) (xy 21.627627 -98.350166) (xy 21.679983 -98.416742)
			(xy 21.725773 -98.487994) (xy 21.764584 -98.563275) (xy 21.796063 -98.641905) (xy 21.819924 -98.723172)
			(xy 21.835953 -98.806338) (xy 21.844004 -98.890652) (xy 21.844508 -98.933) (xy 26.288492 -98.933)
			(xy 26.288967 -98.891898) (xy 26.296552 -98.810043) (xy 26.311657 -98.729238) (xy 26.334153 -98.650171)
			(xy 26.363849 -98.573517) (xy 26.400491 -98.49993) (xy 26.443766 -98.430038) (xy 26.493306 -98.364437)
			(xy 26.548687 -98.303687) (xy 26.609437 -98.248306) (xy 26.675038 -98.198766) (xy 26.74493 -98.155491)
			(xy 26.818517 -98.118849) (xy 26.895171 -98.089153) (xy 26.974238 -98.066657) (xy 27.055043 -98.051552)
			(xy 27.136898 -98.043967) (xy 27.178 -98.043492) (xy 27.219391 -98.04394) (xy 27.301817 -98.051616)
			(xy 27.383173 -98.066921) (xy 27.462754 -98.089722) (xy 27.53987 -98.119822) (xy 27.613855 -98.15696)
			(xy 27.684068 -98.200814) (xy 27.7499 -98.251004) (xy 27.810782 -98.307097) (xy 27.866186 -98.368606)
			(xy 27.915633 -98.434999) (xy 27.958694 -98.5057) (xy 27.994996 -98.580098) (xy 28.024226 -98.657549)
			(xy 28.046131 -98.737381) (xy 28.053792 -98.77806) (xy 28.056084 -98.788186) (xy 28.067487 -98.805513)
			(xy 28.084814 -98.816916) (xy 28.09494 -98.819208) (xy 28.135228 -98.826791) (xy 28.214301 -98.848446)
			(xy 28.291049 -98.877281) (xy 28.364819 -98.913053) (xy 28.434986 -98.955457) (xy 28.500956 -99.004135)
			(xy 28.562171 -99.058673) (xy 28.618109 -99.11861) (xy 28.668299 -99.183438) (xy 28.712314 -99.252606)
			(xy 28.731464 -99.288854) (xy 28.735749 -99.296351) (xy 28.748286 -99.308207) (xy 28.764042 -99.315241)
			(xy 28.772612 -99.316286) (xy 28.813905 -99.320066) (xy 28.895597 -99.334314) (xy 28.975608 -99.356103)
			(xy 29.053244 -99.385245) (xy 29.12783 -99.421486) (xy 29.19872 -99.464512) (xy 29.265297 -99.513948)
			(xy 29.326984 -99.569367) (xy 29.383246 -99.630287) (xy 29.433593 -99.696179) (xy 29.477589 -99.766471)
			(xy 29.514851 -99.840552) (xy 29.545057 -99.91778) (xy 29.567944 -99.997484) (xy 29.583313 -100.078972)
			(xy 29.591031 -100.161537) (xy 29.591508 -100.203) (xy 29.591 -100.23602) (xy 29.590492 -100.24745)
			(xy 29.599382 -100.268278) (xy 29.675074 -100.335588) (xy 29.696664 -100.341938) (xy 29.708094 -100.34016)
			(xy 29.742102 -100.335185) (xy 29.810632 -100.329842) (xy 29.845 -100.329492) (xy 29.886102 -100.329967)
			(xy 29.967957 -100.337552) (xy 30.048762 -100.352657) (xy 30.127829 -100.375153) (xy 30.204483 -100.404849)
			(xy 30.27807 -100.441491) (xy 30.347962 -100.484766) (xy 30.413563 -100.534306) (xy 30.474313 -100.589687)
			(xy 30.529694 -100.650437) (xy 30.579234 -100.716038) (xy 30.622509 -100.78593) (xy 30.659151 -100.859517)
			(xy 30.688847 -100.936171) (xy 30.711343 -101.015238) (xy 30.726448 -101.096043) (xy 30.729997 -101.134348)
			(xy 35.008054 -101.134348) (xy 35.008054 -101.049652) (xy 35.016105 -100.965338) (xy 35.032134 -100.882172)
			(xy 35.055995 -100.800905) (xy 35.087474 -100.722275) (xy 35.126285 -100.646994) (xy 35.172075 -100.575742)
			(xy 35.224431 -100.509166) (xy 35.282879 -100.447868) (xy 35.346889 -100.392403) (xy 35.415881 -100.343274)
			(xy 35.489231 -100.300925) (xy 35.566274 -100.265741) (xy 35.646313 -100.238039) (xy 35.728622 -100.218071)
			(xy 35.812457 -100.206018) (xy 35.897058 -100.201988) (xy 35.981659 -100.206018) (xy 36.065494 -100.218071)
			(xy 36.147803 -100.238039) (xy 36.227842 -100.265741) (xy 36.304885 -100.300925) (xy 36.378235 -100.343274)
			(xy 36.447227 -100.392403) (xy 36.511237 -100.447868) (xy 36.569685 -100.509166) (xy 36.622041 -100.575742)
			(xy 36.667831 -100.646994) (xy 36.706642 -100.722275) (xy 36.738121 -100.800905) (xy 36.761982 -100.882172)
			(xy 36.778011 -100.965338) (xy 36.786062 -101.049652) (xy 36.786566 -101.092) (xy 36.786062 -101.134348)
			(xy 36.778011 -101.218662) (xy 36.761982 -101.301828) (xy 36.738121 -101.383095) (xy 36.706642 -101.461725)
			(xy 36.667831 -101.537006) (xy 36.622041 -101.608258) (xy 36.569685 -101.674834) (xy 36.511237 -101.736132)
			(xy 36.447227 -101.791597) (xy 36.378235 -101.840726) (xy 36.304885 -101.883075) (xy 36.227842 -101.918259)
			(xy 36.147803 -101.945961) (xy 36.065494 -101.965929) (xy 35.981659 -101.977982) (xy 35.897058 -101.982013)
			(xy 35.812457 -101.977982) (xy 35.728622 -101.965929) (xy 35.646313 -101.945961) (xy 35.566274 -101.918259)
			(xy 35.489231 -101.883075) (xy 35.415881 -101.840726) (xy 35.346889 -101.791597) (xy 35.282879 -101.736132)
			(xy 35.224431 -101.674834) (xy 35.172075 -101.608258) (xy 35.126285 -101.537006) (xy 35.087474 -101.461725)
			(xy 35.055995 -101.383095) (xy 35.032134 -101.301828) (xy 35.016105 -101.218662) (xy 35.008054 -101.134348)
			(xy 30.729997 -101.134348) (xy 30.734033 -101.177898) (xy 30.734508 -101.219) (xy 30.734083 -101.259071)
			(xy 30.726875 -101.338888) (xy 30.712518 -101.417733) (xy 30.691128 -101.494968) (xy 30.662878 -101.569966)
			(xy 30.627998 -101.642119) (xy 30.607762 -101.676708) (xy 30.603213 -101.684951) (xy 30.599944 -101.703477)
			(xy 30.601412 -101.712776) (xy 30.607254 -101.74224) (xy 30.60947 -101.751435) (xy 30.619647 -101.767362)
			(xy 30.627066 -101.773228) (xy 30.660246 -101.798325) (xy 30.722296 -101.853749) (xy 30.778899 -101.914726)
			(xy 30.82956 -101.980722) (xy 30.873835 -102.051162) (xy 30.911339 -102.125428) (xy 30.941744 -102.202872)
			(xy 30.964783 -102.282818) (xy 30.980255 -102.364565) (xy 30.988025 -102.447401) (xy 30.988508 -102.489)
			(xy 30.988004 -102.531348) (xy 30.979953 -102.615662) (xy 30.963924 -102.698828) (xy 30.940063 -102.780095)
			(xy 30.908584 -102.858725) (xy 30.869773 -102.934006) (xy 30.823983 -103.005258) (xy 30.771627 -103.071834)
			(xy 30.713179 -103.133132) (xy 30.649169 -103.188597) (xy 30.580177 -103.237726) (xy 30.506827 -103.280075)
			(xy 30.429784 -103.315259) (xy 30.349745 -103.342961) (xy 30.267436 -103.362929) (xy 30.183601 -103.374982)
			(xy 30.099 -103.379013) (xy 30.014399 -103.374982) (xy 29.930564 -103.362929) (xy 29.848255 -103.342961)
			(xy 29.768216 -103.315259) (xy 29.691173 -103.280075) (xy 29.617823 -103.237726) (xy 29.548831 -103.188597)
			(xy 29.484821 -103.133132) (xy 29.426373 -103.071834) (xy 29.374017 -103.005258) (xy 29.328227 -102.934006)
			(xy 29.289416 -102.858725) (xy 29.257937 -102.780095) (xy 29.234076 -102.698828) (xy 29.218047 -102.615662)
			(xy 29.209996 -102.531348) (xy 29.209492 -102.489) (xy 29.209917 -102.448929) (xy 29.217125 -102.369112)
			(xy 29.231482 -102.290267) (xy 29.252872 -102.213032) (xy 29.281122 -102.138034) (xy 29.316002 -102.065881)
			(xy 29.336238 -102.031292) (xy 29.340787 -102.023049) (xy 29.344056 -102.004523) (xy 29.342588 -101.995224)
			(xy 29.336746 -101.96576) (xy 29.33453 -101.956565) (xy 29.324353 -101.940638) (xy 29.316934 -101.934772)
			(xy 29.283754 -101.909675) (xy 29.221704 -101.854251) (xy 29.165101 -101.793274) (xy 29.11444 -101.727278)
			(xy 29.070165 -101.656838) (xy 29.032661 -101.582572) (xy 29.002256 -101.505128) (xy 28.979217 -101.425182)
			(xy 28.963745 -101.343435) (xy 28.955975 -101.260599) (xy 28.955492 -101.219) (xy 28.956 -101.18598)
			(xy 28.956508 -101.17455) (xy 28.947618 -101.153722) (xy 28.871926 -101.086412) (xy 28.850336 -101.080062)
			(xy 28.838906 -101.08184) (xy 28.804898 -101.086815) (xy 28.736368 -101.092158) (xy 28.702 -101.092508)
			(xy 28.661347 -101.092004) (xy 28.580382 -101.084578) (xy 28.500432 -101.069796) (xy 28.422163 -101.047783)
			(xy 28.346229 -101.018722) (xy 28.273263 -100.982855) (xy 28.203872 -100.940481) (xy 28.138637 -100.891954)
			(xy 28.0781 -100.837678) (xy 28.022768 -100.778106) (xy 27.9731 -100.713735) (xy 27.929512 -100.645101)
			(xy 27.910536 -100.609146) (xy 27.906251 -100.601649) (xy 27.893714 -100.589793) (xy 27.877958 -100.582759)
			(xy 27.869388 -100.581714) (xy 27.827744 -100.577882) (xy 27.745369 -100.563423) (xy 27.664714 -100.541296)
			(xy 27.586492 -100.511699) (xy 27.511393 -100.474891) (xy 27.440079 -100.431198) (xy 27.37318 -100.381006)
			(xy 27.311287 -100.324757) (xy 27.254945 -100.262948) (xy 27.204652 -100.196125) (xy 27.160853 -100.124876)
			(xy 27.123933 -100.049832) (xy 27.094218 -99.971654) (xy 27.071971 -99.891033) (xy 27.064208 -99.84994)
			(xy 27.061916 -99.839814) (xy 27.050513 -99.822487) (xy 27.033186 -99.811084) (xy 27.02306 -99.808792)
			(xy 26.982399 -99.801057) (xy 26.902582 -99.779137) (xy 26.825146 -99.749896) (xy 26.750762 -99.713586)
			(xy 26.680074 -99.670522) (xy 26.613692 -99.621077) (xy 26.552192 -99.565678) (xy 26.496106 -99.504804)
			(xy 26.445917 -99.438982) (xy 26.402062 -99.368782) (xy 26.364919 -99.294811) (xy 26.334809 -99.217709)
			(xy 26.311994 -99.138142) (xy 26.29667 -99.0568) (xy 26.28897 -98.974386) (xy 26.288492 -98.933)
			(xy 21.844508 -98.933) (xy 21.844004 -98.975348) (xy 21.835953 -99.059662) (xy 21.819924 -99.142828)
			(xy 21.796063 -99.224095) (xy 21.764584 -99.302725) (xy 21.725773 -99.378006) (xy 21.679983 -99.449258)
			(xy 21.627627 -99.515834) (xy 21.569179 -99.577132) (xy 21.505169 -99.632597) (xy 21.436177 -99.681726)
			(xy 21.362827 -99.724075) (xy 21.285784 -99.759259) (xy 21.205745 -99.786961) (xy 21.123436 -99.806929)
			(xy 21.039601 -99.818982) (xy 20.955 -99.823013) (xy 20.870399 -99.818982) (xy 20.786564 -99.806929)
			(xy 20.704255 -99.786961) (xy 20.624216 -99.759259) (xy 20.547173 -99.724075) (xy 20.473823 -99.681726)
			(xy 20.404831 -99.632597) (xy 20.340821 -99.577132) (xy 20.282373 -99.515834) (xy 20.230017 -99.449258)
			(xy 20.184227 -99.378006) (xy 20.145416 -99.302725) (xy 20.113937 -99.224095) (xy 20.090076 -99.142828)
			(xy 20.074047 -99.059662) (xy 20.065996 -98.975348) (xy 1.651254 -98.975348) (xy 1.651254 -99.180904)
			(xy 1.652778 -99.23145) (xy 1.651254 -99.281996) (xy 1.651254 -104.260904) (xy 1.652778 -104.31145)
			(xy 1.651254 -104.361996) (xy 1.651254 -109.340904) (xy 1.652778 -109.39145) (xy 1.651254 -109.441996)
			(xy 1.651254 -114.420904) (xy 1.652778 -114.47145) (xy 1.651254 -114.521996) (xy 1.651254 -118.709948)
			(xy 5.378704 -118.709948) (xy 5.379195 -118.658457) (xy 5.387211 -118.555786) (xy 5.403195 -118.454052)
			(xy 5.427049 -118.35387) (xy 5.458627 -118.255848) (xy 5.49774 -118.160582) (xy 5.544149 -118.068649)
			(xy 5.597573 -117.980607) (xy 5.657687 -117.896991) (xy 5.724127 -117.818307) (xy 5.759958 -117.781324)
			(xy 5.767324 -117.774212) (xy 5.77469 -117.755924) (xy 5.77469 -117.663976) (xy 5.767324 -117.645688)
			(xy 5.759958 -117.638576) (xy 5.724129 -117.601591) (xy 5.657689 -117.522907) (xy 5.597575 -117.439291)
			(xy 5.544152 -117.351249) (xy 5.497743 -117.259317) (xy 5.458631 -117.164051) (xy 5.427053 -117.066029)
			(xy 5.4032 -116.965847) (xy 5.387217 -116.864113) (xy 5.379201 -116.761443) (xy 5.379201 -116.65846)
			(xy 5.387217 -116.55579) (xy 5.4032 -116.454056) (xy 5.427052 -116.353874) (xy 5.45863 -116.255852)
			(xy 5.497742 -116.160586) (xy 5.544151 -116.068653) (xy 5.597574 -115.980611) (xy 5.657688 -115.896995)
			(xy 5.724128 -115.818311) (xy 5.759958 -115.781328) (xy 5.767324 -115.774216) (xy 5.77469 -115.755928)
			(xy 5.77469 -115.66398) (xy 5.767324 -115.645692) (xy 5.759958 -115.63858) (xy 5.724127 -115.601597)
			(xy 5.657687 -115.522913) (xy 5.597573 -115.439297) (xy 5.54415 -115.351255) (xy 5.497741 -115.259322)
			(xy 5.458629 -115.164056) (xy 5.427051 -115.066034) (xy 5.403198 -114.965852) (xy 5.387215 -114.864117)
			(xy 5.379199 -114.761447) (xy 5.379199 -114.658465) (xy 5.387215 -114.555795) (xy 5.403198 -114.45406)
			(xy 5.427051 -114.353878) (xy 5.458629 -114.255856) (xy 5.497741 -114.16059) (xy 5.54415 -114.068657)
			(xy 5.597573 -113.980615) (xy 5.657687 -113.896999) (xy 5.724127 -113.818315) (xy 5.759958 -113.781332)
			(xy 5.767324 -113.77422) (xy 5.77469 -113.755932) (xy 5.77469 -113.663984) (xy 5.767324 -113.645696)
			(xy 5.759958 -113.638584) (xy 5.724127 -113.601601) (xy 5.657687 -113.522917) (xy 5.597573 -113.439301)
			(xy 5.54415 -113.351259) (xy 5.497742 -113.259326) (xy 5.45863 -113.16406) (xy 5.427051 -113.066038)
			(xy 5.403198 -112.965856) (xy 5.387216 -112.864121) (xy 5.3792 -112.761451) (xy 5.3792 -112.658469)
			(xy 5.387216 -112.555799) (xy 5.403198 -112.454064) (xy 5.427051 -112.353882) (xy 5.45863 -112.25586)
			(xy 5.497742 -112.160594) (xy 5.54415 -112.068661) (xy 5.597573 -111.980619) (xy 5.657687 -111.897003)
			(xy 5.724127 -111.818319) (xy 5.759958 -111.781336) (xy 5.767324 -111.774224) (xy 5.77469 -111.755936)
			(xy 5.77469 -111.663988) (xy 5.767324 -111.6457) (xy 5.759958 -111.638588) (xy 5.724127 -111.601605)
			(xy 5.657687 -111.522921) (xy 5.597573 -111.439305) (xy 5.54415 -111.351263) (xy 5.497741 -111.25933)
			(xy 5.458629 -111.164064) (xy 5.427051 -111.066042) (xy 5.403198 -110.96586) (xy 5.387215 -110.864125)
			(xy 5.379199 -110.761455) (xy 5.379199 -110.658473) (xy 5.387215 -110.555803) (xy 5.403198 -110.454068)
			(xy 5.427051 -110.353886) (xy 5.458629 -110.255864) (xy 5.497741 -110.160598) (xy 5.54415 -110.068665)
			(xy 5.597573 -109.980623) (xy 5.657687 -109.897007) (xy 5.724127 -109.818323) (xy 5.759958 -109.78134)
			(xy 5.767324 -109.774228) (xy 5.77469 -109.75594) (xy 5.77469 -109.663992) (xy 5.767324 -109.645704)
			(xy 5.759958 -109.638592) (xy 5.724125 -109.601611) (xy 5.657685 -109.522927) (xy 5.597571 -109.43931)
			(xy 5.544148 -109.351268) (xy 5.49774 -109.259335) (xy 5.458628 -109.164069) (xy 5.42705 -109.066047)
			(xy 5.403197 -108.965865) (xy 5.387214 -108.86413) (xy 5.379198 -108.76146) (xy 5.379199 -108.658477)
			(xy 5.387214 -108.555807) (xy 5.403197 -108.454072) (xy 5.42705 -108.35389) (xy 5.458629 -108.255869)
			(xy 5.497741 -108.160602) (xy 5.54415 -108.068669) (xy 5.597573 -107.980627) (xy 5.657687 -107.897011)
			(xy 5.724127 -107.818327) (xy 5.759958 -107.781344) (xy 5.767324 -107.774232) (xy 5.77469 -107.755944)
			(xy 5.77469 -107.663996) (xy 5.767324 -107.645708) (xy 5.759958 -107.638596) (xy 5.724129 -107.601611)
			(xy 5.657689 -107.522927) (xy 5.597575 -107.439311) (xy 5.544152 -107.351269) (xy 5.497743 -107.259337)
			(xy 5.458631 -107.164071) (xy 5.427053 -107.066049) (xy 5.4032 -106.965867) (xy 5.387217 -106.864133)
			(xy 5.379201 -106.761463) (xy 5.379201 -106.65848) (xy 5.387217 -106.55581) (xy 5.4032 -106.454076)
			(xy 5.427052 -106.353894) (xy 5.45863 -106.255872) (xy 5.497742 -106.160606) (xy 5.544151 -106.068673)
			(xy 5.597574 -105.980631) (xy 5.657688 -105.897015) (xy 5.724128 -105.818331) (xy 5.759958 -105.781348)
			(xy 5.767324 -105.774236) (xy 5.77469 -105.755948) (xy 5.77469 -105.664) (xy 5.767324 -105.645712)
			(xy 5.759958 -105.6386) (xy 5.724127 -105.601617) (xy 5.657686 -105.522933) (xy 5.597572 -105.439317)
			(xy 5.544148 -105.351276) (xy 5.497739 -105.259343) (xy 5.458627 -105.164076) (xy 5.427048 -105.066055)
			(xy 5.403195 -104.965873) (xy 5.387212 -104.864138) (xy 5.379197 -104.761467) (xy 5.378704 -104.709976)
			(xy 5.379221 -104.659157) (xy 5.387025 -104.55782) (xy 5.402592 -104.457382) (xy 5.425831 -104.358437)
			(xy 5.456604 -104.261571) (xy 5.49473 -104.167355) (xy 5.539981 -104.076347) (xy 5.592092 -103.989086)
			(xy 5.650755 -103.906087) (xy 5.715621 -103.82784) (xy 5.786308 -103.754809) (xy 5.862397 -103.687426)
			(xy 5.943439 -103.626088) (xy 6.028955 -103.571159) (xy 6.118438 -103.522964) (xy 6.211361 -103.481786)
			(xy 6.307172 -103.447871) (xy 6.405307 -103.421417) (xy 6.455156 -103.411528) (xy 6.466586 -103.409496)
			(xy 6.484874 -103.396288) (xy 6.533642 -103.307388) (xy 6.535166 -103.284782) (xy 6.530848 -103.274114)
			(xy 6.512841 -103.227433) (xy 6.483432 -103.13179) (xy 6.461716 -103.034113) (xy 6.447829 -102.935019)
			(xy 6.441858 -102.835135) (xy 6.443843 -102.735092) (xy 6.453771 -102.635524) (xy 6.471577 -102.537059)
			(xy 6.497151 -102.44032) (xy 6.53033 -102.345918) (xy 6.570905 -102.254452) (xy 6.618619 -102.166498)
			(xy 6.67317 -102.082613) (xy 6.734213 -102.003328) (xy 6.801363 -101.929143) (xy 6.874194 -101.860528)
			(xy 6.952248 -101.797917) (xy 7.035028 -101.741705) (xy 7.122014 -101.692248) (xy 7.212654 -101.649859)
			(xy 7.306375 -101.614805) (xy 7.402585 -101.587308) (xy 7.500676 -101.567542) (xy 7.600027 -101.555633)
			(xy 7.70001 -101.551655) (xy 7.799993 -101.555633) (xy 7.899344 -101.567542) (xy 7.997435 -101.587308)
			(xy 8.093645 -101.614805) (xy 8.167284 -101.642348) (xy 16.560796 -101.642348) (xy 16.560796 -101.557652)
			(xy 16.568847 -101.473338) (xy 16.584876 -101.390172) (xy 16.608737 -101.308905) (xy 16.640216 -101.230275)
			(xy 16.679027 -101.154994) (xy 16.724817 -101.083742) (xy 16.777173 -101.017166) (xy 16.835621 -100.955868)
			(xy 16.899631 -100.900403) (xy 16.968623 -100.851274) (xy 17.041973 -100.808925) (xy 17.119016 -100.773741)
			(xy 17.199055 -100.746039) (xy 17.281364 -100.726071) (xy 17.365199 -100.714018) (xy 17.4498 -100.709988)
			(xy 17.534401 -100.714018) (xy 17.618236 -100.726071) (xy 17.700545 -100.746039) (xy 17.780584 -100.773741)
			(xy 17.857627 -100.808925) (xy 17.930977 -100.851274) (xy 17.999969 -100.900403) (xy 18.063979 -100.955868)
			(xy 18.122427 -101.017166) (xy 18.174783 -101.083742) (xy 18.220573 -101.154994) (xy 18.259384 -101.230275)
			(xy 18.290863 -101.308905) (xy 18.314724 -101.390172) (xy 18.330753 -101.473338) (xy 18.338804 -101.557652)
			(xy 18.339308 -101.6) (xy 18.338804 -101.642348) (xy 18.330753 -101.726662) (xy 18.314724 -101.809828)
			(xy 18.290863 -101.891095) (xy 18.259384 -101.969725) (xy 18.220573 -102.045006) (xy 18.174783 -102.116258)
			(xy 18.122427 -102.182834) (xy 18.063979 -102.244132) (xy 17.999969 -102.299597) (xy 17.930977 -102.348726)
			(xy 17.857627 -102.391075) (xy 17.780584 -102.426259) (xy 17.700545 -102.453961) (xy 17.618236 -102.473929)
			(xy 17.534401 -102.485982) (xy 17.4498 -102.490013) (xy 17.365199 -102.485982) (xy 17.281364 -102.473929)
			(xy 17.199055 -102.453961) (xy 17.119016 -102.426259) (xy 17.041973 -102.391075) (xy 16.968623 -102.348726)
			(xy 16.899631 -102.299597) (xy 16.835621 -102.244132) (xy 16.777173 -102.182834) (xy 16.724817 -102.116258)
			(xy 16.679027 -102.045006) (xy 16.640216 -101.969725) (xy 16.608737 -101.891095) (xy 16.584876 -101.809828)
			(xy 16.568847 -101.726662) (xy 16.560796 -101.642348) (xy 8.167284 -101.642348) (xy 8.187366 -101.649859)
			(xy 8.278006 -101.692248) (xy 8.364992 -101.741705) (xy 8.447772 -101.797917) (xy 8.525826 -101.860528)
			(xy 8.598657 -101.929143) (xy 8.665807 -102.003328) (xy 8.72685 -102.082613) (xy 8.781401 -102.166498)
			(xy 8.829115 -102.254452) (xy 8.86969 -102.345918) (xy 8.902869 -102.44032) (xy 8.928443 -102.537059)
			(xy 8.946249 -102.635524) (xy 8.956177 -102.735092) (xy 8.958162 -102.835135) (xy 8.952191 -102.935019)
			(xy 8.938304 -103.034113) (xy 8.916588 -103.13179) (xy 8.887179 -103.227433) (xy 8.869172 -103.274114)
			(xy 8.864854 -103.284782) (xy 8.866378 -103.307388) (xy 8.915146 -103.396288) (xy 8.933434 -103.409496)
			(xy 8.944864 -103.411528) (xy 8.994713 -103.421421) (xy 9.092846 -103.447877) (xy 9.188657 -103.481795)
			(xy 9.281579 -103.522974) (xy 9.371062 -103.571171) (xy 9.456577 -103.626101) (xy 9.537619 -103.687439)
			(xy 9.613709 -103.754822) (xy 9.684397 -103.827852) (xy 9.749265 -103.906097) (xy 9.807929 -103.989095)
			(xy 9.860043 -104.076355) (xy 9.905298 -104.167361) (xy 9.943428 -104.261575) (xy 9.974206 -104.35844)
			(xy 9.99745 -104.457384) (xy 10.013024 -104.557821) (xy 10.020835 -104.659157) (xy 10.021316 -104.709976)
			(xy 10.02079 -104.761467) (xy 10.016205 -104.82021) (xy 14.912834 -104.82021) (xy 14.916864 -104.735607)
			(xy 14.928918 -104.651771) (xy 14.948887 -104.56946) (xy 14.976589 -104.48942) (xy 15.011774 -104.412375)
			(xy 15.054123 -104.339024) (xy 15.103253 -104.270031) (xy 15.158719 -104.20602) (xy 15.220019 -104.147572)
			(xy 15.286596 -104.095215) (xy 15.357849 -104.049424) (xy 15.433132 -104.010613) (xy 15.511764 -103.979134)
			(xy 15.593032 -103.955272) (xy 15.6762 -103.939243) (xy 15.760515 -103.931192) (xy 15.802864 -103.930704)
			(xy 15.848111 -103.931266) (xy 15.938136 -103.940457) (xy 16.026763 -103.958737) (xy 16.113078 -103.985917)
			(xy 16.196189 -104.021718) (xy 16.275237 -104.065768) (xy 16.312642 -104.091232) (xy 16.320104 -104.096077)
			(xy 16.337291 -104.100643) (xy 16.355001 -104.099034) (xy 16.363188 -104.09555) (xy 16.398512 -104.079589)
			(xy 16.471377 -104.053128) (xy 16.546266 -104.033103) (xy 16.622613 -104.019665) (xy 16.69984 -104.012916)
			(xy 16.7386 -104.012492) (xy 16.780948 -104.012996) (xy 16.865262 -104.021047) (xy 16.948428 -104.037076)
			(xy 17.029695 -104.060937) (xy 17.108325 -104.092416) (xy 17.183606 -104.131227) (xy 17.254858 -104.177017)
			(xy 17.321434 -104.229373) (xy 17.382732 -104.287821) (xy 17.438197 -104.351831) (xy 17.487326 -104.420823)
			(xy 17.529675 -104.494173) (xy 17.564859 -104.571216) (xy 17.592561 -104.651255) (xy 17.612529 -104.733564)
			(xy 17.624582 -104.817399) (xy 17.628613 -104.902) (xy 17.624582 -104.986601) (xy 17.612529 -105.070436)
			(xy 17.592561 -105.152745) (xy 17.564859 -105.232784) (xy 17.529675 -105.309827) (xy 17.487326 -105.383177)
			(xy 17.438197 -105.452169) (xy 17.382732 -105.516179) (xy 17.321434 -105.574627) (xy 17.254858 -105.626983)
			(xy 17.183606 -105.672773) (xy 17.108325 -105.711584) (xy 17.029695 -105.743063) (xy 16.948428 -105.766924)
			(xy 16.865262 -105.782953) (xy 16.780948 -105.791004) (xy 16.7386 -105.791508) (xy 16.693353 -105.790963)
			(xy 16.603327 -105.781769) (xy 16.514699 -105.763486) (xy 16.428384 -105.736302) (xy 16.345274 -105.700499)
			(xy 16.266227 -105.656446) (xy 16.228822 -105.63098) (xy 16.221333 -105.626183) (xy 16.204163 -105.6216)
			(xy 16.186462 -105.623188) (xy 16.178276 -105.626662) (xy 16.142958 -105.642636) (xy 16.070091 -105.669094)
			(xy 15.9952 -105.689117) (xy 15.918852 -105.702552) (xy 15.841625 -105.709297) (xy 15.802864 -105.70972)
			(xy 15.760515 -105.709228) (xy 15.6762 -105.701177) (xy 15.593032 -105.685148) (xy 15.511764 -105.661286)
			(xy 15.433132 -105.629807) (xy 15.357849 -105.590996) (xy 15.286596 -105.545205) (xy 15.220019 -105.492848)
			(xy 15.158719 -105.4344) (xy 15.103253 -105.370389) (xy 15.054123 -105.301396) (xy 15.011774 -105.228045)
			(xy 14.976589 -105.151) (xy 14.948887 -105.07096) (xy 14.928918 -104.988649) (xy 14.916864 -104.904813)
			(xy 14.912834 -104.82021) (xy 10.016205 -104.82021) (xy 10.012776 -104.864136) (xy 9.996796 -104.965869)
			(xy 9.972946 -105.066051) (xy 9.941371 -105.164072) (xy 9.902262 -105.259338) (xy 9.855857 -105.351271)
			(xy 9.802437 -105.439313) (xy 9.742327 -105.522931) (xy 9.675891 -105.601616) (xy 9.640062 -105.6386)
			(xy 9.632696 -105.645712) (xy 9.62533 -105.664) (xy 9.62533 -105.755948) (xy 9.632696 -105.774236)
			(xy 9.640062 -105.781348) (xy 9.675895 -105.818329) (xy 9.742335 -105.897013) (xy 9.802449 -105.98063)
			(xy 9.855872 -106.068672) (xy 9.90228 -106.160605) (xy 9.941392 -106.255871) (xy 9.97297 -106.353893)
			(xy 9.996823 -106.454075) (xy 10.012806 -106.55581) (xy 10.020822 -106.65848) (xy 10.020821 -106.761463)
			(xy 10.012806 -106.864133) (xy 9.996823 -106.965868) (xy 9.97297 -107.06605) (xy 9.941391 -107.164071)
			(xy 9.902279 -107.259338) (xy 9.85587 -107.351271) (xy 9.802447 -107.439313) (xy 9.742333 -107.522929)
			(xy 9.675893 -107.601613) (xy 9.640062 -107.638596) (xy 9.632696 -107.645708) (xy 9.62533 -107.663996)
			(xy 9.62533 -107.755944) (xy 9.632696 -107.774232) (xy 9.640062 -107.781344) (xy 9.675891 -107.818329)
			(xy 9.742331 -107.897013) (xy 9.802445 -107.980629) (xy 9.855868 -108.068671) (xy 9.902277 -108.160603)
			(xy 9.941389 -108.255869) (xy 9.972967 -108.353891) (xy 9.99682 -108.454073) (xy 10.012803 -108.555807)
			(xy 10.020819 -108.658477) (xy 10.020819 -108.76146) (xy 10.012803 -108.86413) (xy 9.99682 -108.965864)
			(xy 9.983 -109.023912) (xy 14.471142 -109.023912) (xy 14.471657 -108.982407) (xy 14.479391 -108.899759)
			(xy 14.494794 -108.818191) (xy 14.51773 -108.738413) (xy 14.548001 -108.66112) (xy 14.585343 -108.586984)
			(xy 14.629431 -108.516651) (xy 14.654276 -108.4834) (xy 14.660609 -108.474195) (xy 14.665444 -108.45241)
			(xy 14.660617 -108.430622) (xy 14.654276 -108.421424) (xy 14.629441 -108.388165) (xy 14.585343 -108.317836)
			(xy 14.547991 -108.243703) (xy 14.517712 -108.166412) (xy 14.494768 -108.086635) (xy 14.47936 -108.005067)
			(xy 14.471622 -107.922417) (xy 14.471142 -107.880912) (xy 14.471646 -107.838564) (xy 14.479697 -107.75425)
			(xy 14.495726 -107.671084) (xy 14.519587 -107.589817) (xy 14.551066 -107.511187) (xy 14.589877 -107.435906)
			(xy 14.635667 -107.364654) (xy 14.688023 -107.298078) (xy 14.746471 -107.23678) (xy 14.810481 -107.181315)
			(xy 14.879473 -107.132186) (xy 14.952823 -107.089837) (xy 15.029866 -107.054653) (xy 15.109905 -107.026951)
			(xy 15.192214 -107.006983) (xy 15.276049 -106.99493) (xy 15.36065 -106.9909) (xy 15.445251 -106.99493)
			(xy 15.529086 -107.006983) (xy 15.611395 -107.026951) (xy 15.691434 -107.054653) (xy 15.768477 -107.089837)
			(xy 15.841827 -107.132186) (xy 15.910819 -107.181315) (xy 15.974829 -107.23678) (xy 16.033277 -107.298078)
			(xy 16.085633 -107.364654) (xy 16.131423 -107.435906) (xy 16.170234 -107.511187) (xy 16.201713 -107.589817)
			(xy 16.225574 -107.671084) (xy 16.241603 -107.75425) (xy 16.249654 -107.838564) (xy 16.250158 -107.880912)
			(xy 16.249656 -107.922417) (xy 16.24192 -108.005066) (xy 16.226515 -108.086634) (xy 16.203577 -108.166412)
			(xy 16.173304 -108.243705) (xy 16.13596 -108.31784) (xy 16.09187 -108.388174) (xy 16.067024 -108.421424)
			(xy 16.060669 -108.430616) (xy 16.055841 -108.45241) (xy 16.060678 -108.474201) (xy 16.067024 -108.4834)
			(xy 16.093134 -108.518366) (xy 16.139145 -108.592524) (xy 16.177676 -108.670829) (xy 16.193516 -108.711492)
			(xy 16.198342 -108.724192) (xy 16.218154 -108.740956) (xy 16.329406 -108.7628) (xy 16.354298 -108.754672)
			(xy 16.363442 -108.744766) (xy 16.391443 -108.714984) (xy 16.452077 -108.660152) (xy 16.517488 -108.611115)
			(xy 16.587122 -108.568288) (xy 16.660393 -108.532032) (xy 16.736683 -108.502653) (xy 16.815346 -108.4804)
			(xy 16.895719 -108.465458) (xy 16.977125 -108.457956) (xy 17.018 -108.457492) (xy 17.044924 -108.458)
			(xy 17.05483 -108.458254) (xy 17.07261 -108.451904) (xy 17.139412 -108.39323) (xy 17.148302 -108.376466)
			(xy 17.149064 -108.366814) (xy 17.154113 -108.322968) (xy 17.171839 -108.2365) (xy 17.198042 -108.152213)
			(xy 17.232462 -108.070934) (xy 17.274761 -107.993464) (xy 17.324525 -107.920563) (xy 17.381263 -107.852949)
			(xy 17.412462 -107.82173) (xy 17.422622 -107.81157) (xy 17.429734 -107.784392) (xy 17.395952 -107.670854)
			(xy 17.37487 -107.651804) (xy 17.3609 -107.649264) (xy 17.320848 -107.641002) (xy 17.242339 -107.618087)
			(xy 17.166265 -107.588063) (xy 17.093267 -107.551183) (xy 17.023963 -107.50776) (xy 16.958936 -107.458159)
			(xy 16.898736 -107.402799) (xy 16.843871 -107.342147) (xy 16.794804 -107.276716) (xy 16.75195 -107.207058)
			(xy 16.715669 -107.133761) (xy 16.68627 -107.057443) (xy 16.663998 -106.978749) (xy 16.649044 -106.898343)
			(xy 16.641532 -106.816904) (xy 16.641064 -106.776012) (xy 16.641568 -106.733664) (xy 16.649619 -106.64935)
			(xy 16.665648 -106.566184) (xy 16.689509 -106.484917) (xy 16.720988 -106.406287) (xy 16.759799 -106.331006)
			(xy 16.805589 -106.259754) (xy 16.857945 -106.193178) (xy 16.916393 -106.13188) (xy 16.980403 -106.076415)
			(xy 17.049395 -106.027286) (xy 17.122745 -105.984937) (xy 17.199788 -105.949753) (xy 17.279827 -105.922051)
			(xy 17.362136 -105.902083) (xy 17.445971 -105.89003) (xy 17.530572 -105.886) (xy 17.615173 -105.89003)
			(xy 17.699008 -105.902083) (xy 17.781317 -105.922051) (xy 17.861356 -105.949753) (xy 17.938399 -105.984937)
			(xy 18.011749 -106.027286) (xy 18.080741 -106.076415) (xy 18.144751 -106.13188) (xy 18.203199 -106.193178)
			(xy 18.255555 -106.259754) (xy 18.301345 -106.331006) (xy 18.340156 -106.406287) (xy 18.371635 -106.484917)
			(xy 18.395496 -106.566184) (xy 18.411525 -106.64935) (xy 18.418646 -106.723928) (xy 18.864439 -106.723928)
			(xy 18.869705 -106.640243) (xy 18.882822 -106.557425) (xy 18.903675 -106.476209) (xy 18.932078 -106.397316)
			(xy 18.96778 -106.321446) (xy 19.010464 -106.249272) (xy 19.05975 -106.181436) (xy 19.115201 -106.118539)
			(xy 19.176326 -106.061139) (xy 19.242581 -106.009747) (xy 19.313378 -105.964818) (xy 19.38809 -105.926751)
			(xy 19.466052 -105.895883) (xy 19.546573 -105.87249) (xy 19.628938 -105.856778) (xy 19.712417 -105.848887)
			(xy 19.754342 -105.848404) (xy 19.787103 -105.848718) (xy 19.852447 -105.853546) (xy 19.884898 -105.858056)
			(xy 19.89836 -105.860088) (xy 19.923252 -105.850182) (xy 19.995388 -105.761028) (xy 19.999706 -105.734612)
			(xy 19.99488 -105.721912) (xy 19.981326 -105.684445) (xy 19.960196 -105.607616) (xy 19.946024 -105.529205)
			(xy 19.938923 -105.449841) (xy 19.938492 -105.41) (xy 19.939022 -105.367411) (xy 19.947206 -105.282626)
			(xy 19.96346 -105.199012) (xy 19.975068 -105.158032) (xy 19.97837 -105.146602) (xy 19.97456 -105.123996)
			(xy 19.915632 -105.039668) (xy 19.895566 -105.028492) (xy 19.883882 -105.02773) (xy 19.842045 -105.024649)
			(xy 19.759171 -105.0116) (xy 19.677894 -104.990804) (xy 19.598937 -104.962447) (xy 19.523001 -104.92678)
			(xy 19.450761 -104.88412) (xy 19.38286 -104.834847) (xy 19.3199 -104.779399) (xy 19.262442 -104.718268)
			(xy 19.210996 -104.651998) (xy 19.16602 -104.581178) (xy 19.127913 -104.506437) (xy 19.097013 -104.428439)
			(xy 19.073597 -104.347878) (xy 19.05787 -104.26547) (xy 19.049974 -104.181948) (xy 19.049492 -104.14)
			(xy 19.049995 -104.097685) (xy 19.058026 -104.013437) (xy 19.074024 -103.930334) (xy 19.097845 -103.849125)
			(xy 19.129272 -103.770548) (xy 19.168023 -103.695311) (xy 19.190462 -103.659432) (xy 19.195345 -103.651043)
			(xy 19.199017 -103.632) (xy 19.195345 -103.612957) (xy 19.190462 -103.604568) (xy 19.168016 -103.568694)
			(xy 19.129273 -103.493453) (xy 19.097849 -103.414874) (xy 19.07403 -103.333665) (xy 19.05803 -103.250562)
			(xy 19.049994 -103.166315) (xy 19.049492 -103.124) (xy 19.049967 -103.082898) (xy 19.057552 -103.001043)
			(xy 19.072657 -102.920238) (xy 19.095153 -102.841171) (xy 19.124849 -102.764517) (xy 19.161491 -102.69093)
			(xy 19.204766 -102.621038) (xy 19.254306 -102.555437) (xy 19.309687 -102.494687) (xy 19.370437 -102.439306)
			(xy 19.436038 -102.389766) (xy 19.50593 -102.346491) (xy 19.579517 -102.309849) (xy 19.656171 -102.280153)
			(xy 19.735238 -102.257657) (xy 19.816043 -102.242552) (xy 19.897898 -102.234967) (xy 19.939 -102.234492)
			(xy 19.978602 -102.234901) (xy 20.057493 -102.241947) (xy 20.135446 -102.255975) (xy 20.211844 -102.276872)
			(xy 20.286083 -102.304475) (xy 20.357577 -102.338565) (xy 20.425758 -102.378872) (xy 20.458176 -102.401624)
			(xy 20.468082 -102.408736) (xy 20.492212 -102.412546) (xy 20.593558 -102.378764) (xy 20.610576 -102.361238)
			(xy 20.614386 -102.349554) (xy 20.629125 -102.304609) (xy 20.666834 -102.217859) (xy 20.713544 -102.135605)
			(xy 20.740624 -102.096824) (xy 20.747736 -102.086918) (xy 20.751546 -102.062788) (xy 20.717764 -101.961442)
			(xy 20.700238 -101.944424) (xy 20.688554 -101.940614) (xy 20.64736 -101.927136) (xy 20.567574 -101.893258)
			(xy 20.491463 -101.851778) (xy 20.419749 -101.803091) (xy 20.353111 -101.747657) (xy 20.292182 -101.686004)
			(xy 20.237541 -101.618715) (xy 20.189705 -101.54643) (xy 20.149128 -101.469834) (xy 20.116196 -101.389653)
			(xy 20.09122 -101.306649) (xy 20.074439 -101.221609) (xy 20.06601 -101.13534) (xy 20.065492 -101.092)
			(xy 20.065996 -101.049652) (xy 20.074047 -100.965338) (xy 20.090076 -100.882172) (xy 20.113937 -100.800905)
			(xy 20.145416 -100.722275) (xy 20.184227 -100.646994) (xy 20.230017 -100.575742) (xy 20.282373 -100.509166)
			(xy 20.340821 -100.447868) (xy 20.404831 -100.392403) (xy 20.473823 -100.343274) (xy 20.547173 -100.300925)
			(xy 20.624216 -100.265741) (xy 20.704255 -100.238039) (xy 20.786564 -100.218071) (xy 20.870399 -100.206018)
			(xy 20.955 -100.201988) (xy 21.039601 -100.206018) (xy 21.123436 -100.218071) (xy 21.205745 -100.238039)
			(xy 21.285784 -100.265741) (xy 21.362827 -100.300925) (xy 21.436177 -100.343274) (xy 21.505169 -100.392403)
			(xy 21.569179 -100.447868) (xy 21.627627 -100.509166) (xy 21.679983 -100.575742) (xy 21.725773 -100.646994)
			(xy 21.764584 -100.722275) (xy 21.796063 -100.800905) (xy 21.819924 -100.882172) (xy 21.835953 -100.965338)
			(xy 21.844004 -101.049652) (xy 21.844508 -101.092) (xy 21.844099 -101.131602) (xy 21.837053 -101.210493)
			(xy 21.823025 -101.288446) (xy 21.802128 -101.364844) (xy 21.774525 -101.439083) (xy 21.740435 -101.510577)
			(xy 21.700128 -101.578758) (xy 21.677376 -101.611176) (xy 21.670264 -101.621082) (xy 21.666454 -101.645212)
			(xy 21.700236 -101.746558) (xy 21.704088 -101.750298) (xy 26.288996 -101.750298) (xy 26.288996 -101.665602)
			(xy 26.297047 -101.581288) (xy 26.313076 -101.498122) (xy 26.336937 -101.416855) (xy 26.368416 -101.338225)
			(xy 26.407227 -101.262944) (xy 26.453017 -101.191692) (xy 26.505373 -101.125116) (xy 26.563821 -101.063818)
			(xy 26.627831 -101.008353) (xy 26.696823 -100.959224) (xy 26.770173 -100.916875) (xy 26.847216 -100.881691)
			(xy 26.927255 -100.853989) (xy 27.009564 -100.834021) (xy 27.093399 -100.821968) (xy 27.178 -100.817938)
			(xy 27.262601 -100.821968) (xy 27.346436 -100.834021) (xy 27.428745 -100.853989) (xy 27.508784 -100.881691)
			(xy 27.585827 -100.916875) (xy 27.659177 -100.959224) (xy 27.728169 -101.008353) (xy 27.792179 -101.063818)
			(xy 27.850627 -101.125116) (xy 27.902983 -101.191692) (xy 27.948773 -101.262944) (xy 27.987584 -101.338225)
			(xy 28.019063 -101.416855) (xy 28.042924 -101.498122) (xy 28.058953 -101.581288) (xy 28.067004 -101.665602)
			(xy 28.067508 -101.70795) (xy 28.067004 -101.750298) (xy 28.058953 -101.834612) (xy 28.042924 -101.917778)
			(xy 28.019063 -101.999045) (xy 27.987584 -102.077675) (xy 27.948773 -102.152956) (xy 27.902983 -102.224208)
			(xy 27.850627 -102.290784) (xy 27.792179 -102.352082) (xy 27.728169 -102.407547) (xy 27.659177 -102.456676)
			(xy 27.585827 -102.499025) (xy 27.508784 -102.534209) (xy 27.428745 -102.561911) (xy 27.346436 -102.581879)
			(xy 27.262601 -102.593932) (xy 27.178 -102.597963) (xy 27.093399 -102.593932) (xy 27.009564 -102.581879)
			(xy 26.927255 -102.561911) (xy 26.847216 -102.534209) (xy 26.770173 -102.499025) (xy 26.696823 -102.456676)
			(xy 26.627831 -102.407547) (xy 26.563821 -102.352082) (xy 26.505373 -102.290784) (xy 26.453017 -102.224208)
			(xy 26.407227 -102.152956) (xy 26.368416 -102.077675) (xy 26.336937 -101.999045) (xy 26.313076 -101.917778)
			(xy 26.297047 -101.834612) (xy 26.288996 -101.750298) (xy 21.704088 -101.750298) (xy 21.717762 -101.763576)
			(xy 21.729446 -101.767386) (xy 21.77064 -101.780864) (xy 21.850426 -101.814742) (xy 21.926537 -101.856222)
			(xy 21.998251 -101.904909) (xy 22.064889 -101.960343) (xy 22.125818 -102.021996) (xy 22.180459 -102.089285)
			(xy 22.228295 -102.16157) (xy 22.268872 -102.238166) (xy 22.301804 -102.318347) (xy 22.32678 -102.401351)
			(xy 22.343561 -102.486391) (xy 22.35199 -102.57266) (xy 22.352508 -102.616) (xy 22.352033 -102.657102)
			(xy 22.344448 -102.738957) (xy 22.329343 -102.819762) (xy 22.306847 -102.898829) (xy 22.277151 -102.975483)
			(xy 22.240509 -103.04907) (xy 22.197234 -103.118962) (xy 22.147694 -103.184563) (xy 22.092313 -103.245313)
			(xy 22.031563 -103.300694) (xy 21.965962 -103.350234) (xy 21.89607 -103.393509) (xy 21.822483 -103.430151)
			(xy 21.745829 -103.459847) (xy 21.666762 -103.482343) (xy 21.585957 -103.497448) (xy 21.504102 -103.505033)
			(xy 21.463 -103.505508) (xy 21.423398 -103.505099) (xy 21.344507 -103.498053) (xy 21.266554 -103.484025)
			(xy 21.190156 -103.463128) (xy 21.115917 -103.435525) (xy 21.044423 -103.401435) (xy 20.976242 -103.361128)
			(xy 20.943824 -103.338376) (xy 20.933918 -103.331264) (xy 20.909788 -103.327454) (xy 20.808442 -103.361236)
			(xy 20.791424 -103.378762) (xy 20.787614 -103.390446) (xy 20.77539 -103.428027) (xy 20.745135 -103.501039)
			(xy 20.70852 -103.571079) (xy 20.687538 -103.604568) (xy 20.682655 -103.612957) (xy 20.678983 -103.632)
			(xy 20.682655 -103.651043) (xy 20.687538 -103.659432) (xy 20.709984 -103.695306) (xy 20.733198 -103.740388)
			(xy 26.53436 -103.740388) (xy 26.53436 -103.655692) (xy 26.542411 -103.571378) (xy 26.55844 -103.488212)
			(xy 26.582301 -103.406945) (xy 26.61378 -103.328315) (xy 26.652591 -103.253034) (xy 26.698381 -103.181782)
			(xy 26.750737 -103.115206) (xy 26.809185 -103.053908) (xy 26.873195 -102.998443) (xy 26.942187 -102.949314)
			(xy 27.015537 -102.906965) (xy 27.09258 -102.871781) (xy 27.172619 -102.844079) (xy 27.254928 -102.824111)
			(xy 27.338763 -102.812058) (xy 27.423364 -102.808028) (xy 27.507965 -102.812058) (xy 27.5918 -102.824111)
			(xy 27.674109 -102.844079) (xy 27.754148 -102.871781) (xy 27.831191 -102.906965) (xy 27.904541 -102.949314)
			(xy 27.973533 -102.998443) (xy 28.037543 -103.053908) (xy 28.095991 -103.115206) (xy 28.148347 -103.181782)
			(xy 28.194137 -103.253034) (xy 28.232948 -103.328315) (xy 28.264427 -103.406945) (xy 28.288288 -103.488212)
			(xy 28.304317 -103.571378) (xy 28.312368 -103.655692) (xy 28.312872 -103.69804) (xy 28.312368 -103.740388)
			(xy 28.304317 -103.824702) (xy 28.288288 -103.907868) (xy 28.267644 -103.978177) (xy 30.702085 -103.978177)
			(xy 30.704719 -103.894366) (xy 30.715229 -103.811175) (xy 30.733522 -103.729342) (xy 30.759434 -103.649593)
			(xy 30.792737 -103.572637) (xy 30.833133 -103.499157) (xy 30.880266 -103.429804) (xy 30.933717 -103.365195)
			(xy 30.99301 -103.305903) (xy 31.05762 -103.252454) (xy 31.126974 -103.205323) (xy 31.200455 -103.164928)
			(xy 31.277412 -103.131627) (xy 31.357161 -103.105716) (xy 31.438994 -103.087426) (xy 31.522186 -103.076918)
			(xy 31.605997 -103.074286) (xy 31.689684 -103.079552) (xy 31.772505 -103.092672) (xy 31.853722 -103.113527)
			(xy 31.932617 -103.141933) (xy 32.008488 -103.177637) (xy 32.080663 -103.220323) (xy 32.1485 -103.269613)
			(xy 32.211397 -103.325067) (xy 32.268796 -103.386195) (xy 32.320188 -103.452453) (xy 32.336565 -103.47826)
			(xy 33.463226 -103.47826) (xy 33.463226 -103.393564) (xy 33.471277 -103.30925) (xy 33.487306 -103.226084)
			(xy 33.511167 -103.144817) (xy 33.542646 -103.066187) (xy 33.581457 -102.990906) (xy 33.627247 -102.919654)
			(xy 33.679603 -102.853078) (xy 33.738051 -102.79178) (xy 33.802061 -102.736315) (xy 33.871053 -102.687186)
			(xy 33.944403 -102.644837) (xy 34.021446 -102.609653) (xy 34.101485 -102.581951) (xy 34.183794 -102.561983)
			(xy 34.267629 -102.54993) (xy 34.35223 -102.5459) (xy 34.436831 -102.54993) (xy 34.520666 -102.561983)
			(xy 34.602975 -102.581951) (xy 34.683014 -102.609653) (xy 34.760057 -102.644837) (xy 34.833407 -102.687186)
			(xy 34.902399 -102.736315) (xy 34.966409 -102.79178) (xy 35.024857 -102.853078) (xy 35.077213 -102.919654)
			(xy 35.123003 -102.990906) (xy 35.161814 -103.066187) (xy 35.193293 -103.144817) (xy 35.217154 -103.226084)
			(xy 35.233183 -103.30925) (xy 35.241234 -103.393564) (xy 35.241738 -103.435912) (xy 35.241234 -103.47826)
			(xy 35.233183 -103.562574) (xy 35.217154 -103.64574) (xy 35.193293 -103.727007) (xy 35.161814 -103.805637)
			(xy 35.123003 -103.880918) (xy 35.077213 -103.95217) (xy 35.024857 -104.018746) (xy 34.966409 -104.080044)
			(xy 34.902399 -104.135509) (xy 34.833407 -104.184638) (xy 34.760057 -104.226987) (xy 34.683014 -104.262171)
			(xy 34.602975 -104.289873) (xy 34.520666 -104.309841) (xy 34.436831 -104.321894) (xy 34.35223 -104.325925)
			(xy 34.267629 -104.321894) (xy 34.183794 -104.309841) (xy 34.101485 -104.289873) (xy 34.021446 -104.262171)
			(xy 33.944403 -104.226987) (xy 33.871053 -104.184638) (xy 33.802061 -104.135509) (xy 33.738051 -104.080044)
			(xy 33.679603 -104.018746) (xy 33.627247 -103.95217) (xy 33.581457 -103.880918) (xy 33.542646 -103.805637)
			(xy 33.511167 -103.727007) (xy 33.487306 -103.64574) (xy 33.471277 -103.562574) (xy 33.463226 -103.47826)
			(xy 32.336565 -103.47826) (xy 32.365117 -103.523253) (xy 32.403183 -103.597968) (xy 32.434049 -103.675933)
			(xy 32.45744 -103.756457) (xy 32.47315 -103.838825) (xy 32.481038 -103.922306) (xy 32.48152 -103.964232)
			(xy 32.480903 -104.010697) (xy 32.471221 -104.10312) (xy 32.451968 -104.194033) (xy 32.423351 -104.282446)
			(xy 32.405066 -104.325166) (xy 32.399528 -104.33906) (xy 32.395764 -104.368712) (xy 32.400752 -104.398182)
			(xy 32.414064 -104.424944) (xy 32.434558 -104.446701) (xy 32.460476 -104.461588) (xy 32.489596 -104.468327)
			(xy 32.51942 -104.466341) (xy 32.53359 -104.461564) (xy 32.571088 -104.447987) (xy 32.647973 -104.426785)
			(xy 32.726446 -104.412546) (xy 32.805879 -104.405382) (xy 32.845756 -104.404922) (xy 32.887684 -104.40533)
			(xy 32.971167 -104.413217) (xy 33.053537 -104.428926) (xy 33.134064 -104.452317) (xy 33.212032 -104.483182)
			(xy 33.286749 -104.521248) (xy 33.357553 -104.566176) (xy 33.423814 -104.617568) (xy 33.484944 -104.674968)
			(xy 33.540401 -104.737866) (xy 33.589693 -104.805704) (xy 33.632382 -104.87788) (xy 33.668089 -104.953753)
			(xy 33.696498 -105.032649) (xy 33.717356 -105.113869) (xy 33.730477 -105.196691) (xy 33.735746 -105.28038)
			(xy 33.733116 -105.364194) (xy 33.72261 -105.447388) (xy 33.704321 -105.529225) (xy 33.678412 -105.608977)
			(xy 33.645112 -105.685937) (xy 33.604718 -105.759421) (xy 33.557587 -105.828778) (xy 33.504138 -105.893392)
			(xy 33.444846 -105.952689) (xy 33.380237 -106.006143) (xy 33.310884 -106.053279) (xy 33.237403 -106.093679)
			(xy 33.160446 -106.126985) (xy 33.080696 -106.152901) (xy 32.998861 -106.171197) (xy 32.915668 -106.18171)
			(xy 32.831854 -106.184347) (xy 32.748164 -106.179085) (xy 32.665341 -106.165971) (xy 32.58412 -106.14512)
			(xy 32.505221 -106.116718) (xy 32.429345 -106.081017) (xy 32.357166 -106.038334) (xy 32.289324 -105.989048)
			(xy 32.226422 -105.933596) (xy 32.169017 -105.87247) (xy 32.117619 -105.806213) (xy 32.072685 -105.735414)
			(xy 32.034612 -105.6607) (xy 32.003741 -105.582734) (xy 31.980343 -105.502209) (xy 31.964627 -105.41984)
			(xy 31.956733 -105.336358) (xy 31.956248 -105.29443) (xy 31.956846 -105.247965) (xy 31.966532 -105.155541)
			(xy 31.985791 -105.064628) (xy 32.014414 -104.976215) (xy 32.032702 -104.933496) (xy 32.038323 -104.919632)
			(xy 32.042082 -104.889966) (xy 32.037087 -104.860484) (xy 32.023764 -104.833713) (xy 32.003257 -104.81195)
			(xy 31.977324 -104.797062) (xy 31.94819 -104.790324) (xy 31.918354 -104.792316) (xy 31.904178 -104.797098)
			(xy 31.866683 -104.810683) (xy 31.789797 -104.831883) (xy 31.711323 -104.84612) (xy 31.63189 -104.853281)
			(xy 31.592012 -104.85374) (xy 31.550086 -104.853237) (xy 31.466605 -104.845347) (xy 31.384237 -104.829635)
			(xy 31.303714 -104.806242) (xy 31.225749 -104.775375) (xy 31.151036 -104.737307) (xy 31.080236 -104.692377)
			(xy 31.013979 -104.640983) (xy 30.952853 -104.583583) (xy 30.8974 -104.520684) (xy 30.848112 -104.452846)
			(xy 30.805428 -104.380671) (xy 30.769725 -104.304799) (xy 30.741321 -104.225903) (xy 30.720468 -104.144685)
			(xy 30.70735 -104.061865) (xy 30.702085 -103.978177) (xy 28.267644 -103.978177) (xy 28.264427 -103.989135)
			(xy 28.232948 -104.067765) (xy 28.194137 -104.143046) (xy 28.148347 -104.214298) (xy 28.095991 -104.280874)
			(xy 28.037543 -104.342172) (xy 27.973533 -104.397637) (xy 27.904541 -104.446766) (xy 27.831191 -104.489115)
			(xy 27.754148 -104.524299) (xy 27.674109 -104.552001) (xy 27.5918 -104.571969) (xy 27.507965 -104.584022)
			(xy 27.423364 -104.588053) (xy 27.338763 -104.584022) (xy 27.254928 -104.571969) (xy 27.172619 -104.552001)
			(xy 27.09258 -104.524299) (xy 27.015537 -104.489115) (xy 26.942187 -104.446766) (xy 26.873195 -104.397637)
			(xy 26.809185 -104.342172) (xy 26.750737 -104.280874) (xy 26.698381 -104.214298) (xy 26.652591 -104.143046)
			(xy 26.61378 -104.067765) (xy 26.582301 -103.989135) (xy 26.55844 -103.907868) (xy 26.542411 -103.824702)
			(xy 26.53436 -103.740388) (xy 20.733198 -103.740388) (xy 20.748727 -103.770547) (xy 20.780151 -103.849126)
			(xy 20.80397 -103.930335) (xy 20.81997 -104.013438) (xy 20.828006 -104.097685) (xy 20.828508 -104.14)
			(xy 20.827978 -104.182589) (xy 20.819794 -104.267374) (xy 20.80354 -104.350988) (xy 20.791932 -104.391968)
			(xy 20.78863 -104.403398) (xy 20.79244 -104.426004) (xy 20.851368 -104.510332) (xy 20.871434 -104.521508)
			(xy 20.883118 -104.52227) (xy 20.924955 -104.525351) (xy 21.007829 -104.5384) (xy 21.089106 -104.559196)
			(xy 21.168063 -104.587553) (xy 21.243999 -104.62322) (xy 21.316239 -104.66588) (xy 21.38414 -104.715153)
			(xy 21.4471 -104.770601) (xy 21.504558 -104.831732) (xy 21.556004 -104.898002) (xy 21.60098 -104.968822)
			(xy 21.639087 -105.043563) (xy 21.669987 -105.121561) (xy 21.693403 -105.202122) (xy 21.70913 -105.28453)
			(xy 21.717026 -105.368052) (xy 21.717508 -105.41) (xy 21.717033 -105.451102) (xy 21.709448 -105.532957)
			(xy 21.694343 -105.613762) (xy 21.671847 -105.692829) (xy 21.642151 -105.769483) (xy 21.605509 -105.84307)
			(xy 21.562234 -105.912962) (xy 21.512694 -105.978563) (xy 21.457313 -106.039313) (xy 21.396563 -106.094694)
			(xy 21.330962 -106.144234) (xy 21.26107 -106.187509) (xy 21.187483 -106.224151) (xy 21.110829 -106.253847)
			(xy 21.031762 -106.276343) (xy 20.950957 -106.291448) (xy 20.869102 -106.299033) (xy 20.828 -106.299508)
			(xy 20.795239 -106.299201) (xy 20.729895 -106.294368) (xy 20.697444 -106.289856) (xy 20.683982 -106.287824)
			(xy 20.65909 -106.29773) (xy 20.637362 -106.324584) (xy 27.67101 -106.324584) (xy 27.67101 -106.239888)
			(xy 27.679061 -106.155574) (xy 27.69509 -106.072408) (xy 27.718951 -105.991141) (xy 27.75043 -105.912511)
			(xy 27.789241 -105.83723) (xy 27.835031 -105.765978) (xy 27.887387 -105.699402) (xy 27.945835 -105.638104)
			(xy 28.009845 -105.582639) (xy 28.078837 -105.53351) (xy 28.152187 -105.491161) (xy 28.22923 -105.455977)
			(xy 28.309269 -105.428275) (xy 28.391578 -105.408307) (xy 28.475413 -105.396254) (xy 28.560014 -105.392224)
			(xy 28.644615 -105.396254) (xy 28.72845 -105.408307) (xy 28.810759 -105.428275) (xy 28.890798 -105.455977)
			(xy 28.967841 -105.491161) (xy 29.041191 -105.53351) (xy 29.110183 -105.582639) (xy 29.174193 -105.638104)
			(xy 29.232641 -105.699402) (xy 29.284997 -105.765978) (xy 29.330787 -105.83723) (xy 29.369598 -105.912511)
			(xy 29.401077 -105.991141) (xy 29.424938 -106.072408) (xy 29.440967 -106.155574) (xy 29.449018 -106.239888)
			(xy 29.449522 -106.282236) (xy 29.449018 -106.324584) (xy 29.440967 -106.408898) (xy 29.424938 -106.492064)
			(xy 29.401077 -106.573331) (xy 29.369598 -106.651961) (xy 29.330787 -106.727242) (xy 29.284997 -106.798494)
			(xy 29.232641 -106.86507) (xy 29.174193 -106.926368) (xy 29.110183 -106.981833) (xy 29.041191 -107.030962)
			(xy 28.967841 -107.073311) (xy 28.890798 -107.108495) (xy 28.810759 -107.136197) (xy 28.767877 -107.1466)
			(xy 32.853886 -107.1466) (xy 32.857916 -107.061999) (xy 32.869969 -106.978164) (xy 32.889937 -106.895854)
			(xy 32.917639 -106.815815) (xy 32.952824 -106.738772) (xy 32.995172 -106.665422) (xy 33.044301 -106.59643)
			(xy 33.099766 -106.53242) (xy 33.161064 -106.473972) (xy 33.227641 -106.421616) (xy 33.298893 -106.375825)
			(xy 33.374175 -106.337014) (xy 33.452805 -106.305536) (xy 33.534071 -106.281674) (xy 33.617238 -106.265645)
			(xy 33.701551 -106.257594) (xy 33.7439 -106.25709) (xy 33.784586 -106.257545) (xy 33.865617 -106.264973)
			(xy 33.945633 -106.279769) (xy 34.023963 -106.301807) (xy 34.099954 -106.330905) (xy 34.172971 -106.366818)
			(xy 34.242405 -106.409248) (xy 34.307676 -106.457839) (xy 34.33826 -106.484674) (xy 34.347658 -106.49331)
			(xy 34.37255 -106.499406) (xy 34.479484 -106.471466) (xy 34.498026 -106.454194) (xy 34.50209 -106.442002)
			(xy 34.516329 -106.401945) (xy 34.551322 -106.324464) (xy 34.593547 -106.250674) (xy 34.642619 -106.181249)
			(xy 34.69809 -106.116821) (xy 34.759453 -106.057979) (xy 34.82615 -106.005259) (xy 34.897572 -105.959141)
			(xy 34.973068 -105.920047) (xy 35.051949 -105.888334) (xy 35.133495 -105.86429) (xy 35.216963 -105.848134)
			(xy 35.301591 -105.840014) (xy 35.3441 -105.839514) (xy 35.384443 -105.83994) (xy 35.464797 -105.847252)
			(xy 35.54416 -105.861806) (xy 35.621879 -105.883483) (xy 35.697318 -105.912106) (xy 35.769856 -105.947439)
			(xy 35.838899 -105.989191) (xy 35.871658 -106.012742) (xy 35.884104 -106.02214) (xy 35.914584 -106.02341)
			(xy 36.021518 -105.959402) (xy 36.034726 -105.93197) (xy 36.03244 -105.91673) (xy 36.028269 -105.885465)
			(xy 36.023818 -105.822541) (xy 36.02355 -105.791) (xy 36.024076 -105.749074) (xy 36.031967 -105.665595)
			(xy 36.047679 -105.583229) (xy 36.071073 -105.502707) (xy 36.101941 -105.424744) (xy 36.140009 -105.350032)
			(xy 36.18494 -105.279234) (xy 36.236333 -105.212978) (xy 36.293734 -105.151854) (xy 36.356632 -105.096402)
			(xy 36.42447 -105.047116) (xy 36.496645 -105.004433) (xy 36.572517 -104.968732) (xy 36.651411 -104.940329)
			(xy 36.732629 -104.919477) (xy 36.815448 -104.906361) (xy 36.899134 -104.901097) (xy 36.982944 -104.903732)
			(xy 37.066134 -104.914243) (xy 37.147966 -104.932536) (xy 37.227713 -104.958449) (xy 37.304668 -104.991752)
			(xy 37.378146 -105.032149) (xy 37.447497 -105.079283) (xy 37.512105 -105.132733) (xy 37.571395 -105.192026)
			(xy 37.624843 -105.256636) (xy 37.671972 -105.325989) (xy 37.712366 -105.39947) (xy 37.745666 -105.476426)
			(xy 37.771575 -105.556174) (xy 37.789864 -105.638007) (xy 37.800371 -105.721198) (xy 37.803002 -105.805008)
			(xy 37.797734 -105.888694) (xy 37.784614 -105.971512) (xy 37.763759 -106.052729) (xy 37.735352 -106.131622)
			(xy 37.699647 -106.207492) (xy 37.656961 -106.279665) (xy 37.607672 -106.3475) (xy 37.552217 -106.410396)
			(xy 37.49109 -106.467794) (xy 37.424832 -106.519184) (xy 37.354032 -106.564111) (xy 37.279318 -106.602176)
			(xy 37.201354 -106.63304) (xy 37.12083 -106.656431) (xy 37.038464 -106.672139) (xy 36.954984 -106.680026)
			(xy 36.913058 -106.680508) (xy 36.872716 -106.680046) (xy 36.792363 -106.67274) (xy 36.713001 -106.658191)
			(xy 36.635282 -106.636519) (xy 36.559843 -106.607902) (xy 36.487304 -106.572575) (xy 36.41826 -106.530828)
			(xy 36.3855 -106.50728) (xy 36.373054 -106.497882) (xy 36.342574 -106.496612) (xy 36.23564 -106.56062)
			(xy 36.222432 -106.588052) (xy 36.224718 -106.603292) (xy 36.228891 -106.634557) (xy 36.233341 -106.697481)
			(xy 36.233608 -106.729022) (xy 36.233154 -106.770125) (xy 36.225567 -106.85198) (xy 36.21046 -106.932785)
			(xy 36.187962 -107.011853) (xy 36.158265 -107.088507) (xy 36.121621 -107.162093) (xy 36.078344 -107.231985)
			(xy 36.028803 -107.297586) (xy 35.973421 -107.358336) (xy 35.912669 -107.413717) (xy 35.847067 -107.463257)
			(xy 35.777174 -107.506532) (xy 35.703586 -107.543173) (xy 35.626932 -107.572869) (xy 35.547864 -107.595365)
			(xy 35.467058 -107.610471) (xy 35.385203 -107.618055) (xy 35.3441 -107.61853) (xy 35.303414 -107.61807)
			(xy 35.222383 -107.610642) (xy 35.142368 -107.595847) (xy 35.064038 -107.573809) (xy 34.988047 -107.544712)
			(xy 34.915029 -107.508799) (xy 34.845595 -107.466371) (xy 34.780325 -107.417781) (xy 34.74974 -107.390946)
			(xy 34.740342 -107.38231) (xy 34.71545 -107.376214) (xy 34.608516 -107.404154) (xy 34.589974 -107.421426)
			(xy 34.58591 -107.433618) (xy 34.571683 -107.473679) (xy 34.536688 -107.55116) (xy 34.494461 -107.62495)
			(xy 34.445388 -107.694375) (xy 34.389916 -107.758802) (xy 34.328552 -107.817644) (xy 34.261854 -107.870363)
			(xy 34.190431 -107.91648) (xy 34.114934 -107.955573) (xy 34.036053 -107.987287) (xy 33.954506 -108.011331)
			(xy 33.871038 -108.027486) (xy 33.786409 -108.035606) (xy 33.7439 -108.036106) (xy 33.701551 -108.035606)
			(xy 33.617238 -108.027555) (xy 33.534071 -108.011526) (xy 33.452805 -107.987664) (xy 33.374175 -107.956186)
			(xy 33.298893 -107.917375) (xy 33.227641 -107.871584) (xy 33.161064 -107.819228) (xy 33.099766 -107.76078)
			(xy 33.044301 -107.69677) (xy 32.995172 -107.627778) (xy 32.952824 -107.554428) (xy 32.917639 -107.477385)
			(xy 32.889937 -107.397346) (xy 32.869969 -107.315036) (xy 32.857916 -107.231201) (xy 32.853886 -107.1466)
			(xy 28.767877 -107.1466) (xy 28.72845 -107.156165) (xy 28.644615 -107.168218) (xy 28.560014 -107.172249)
			(xy 28.475413 -107.168218) (xy 28.391578 -107.156165) (xy 28.309269 -107.136197) (xy 28.22923 -107.108495)
			(xy 28.152187 -107.073311) (xy 28.078837 -107.030962) (xy 28.009845 -106.981833) (xy 27.945835 -106.926368)
			(xy 27.887387 -106.86507) (xy 27.835031 -106.798494) (xy 27.789241 -106.727242) (xy 27.75043 -106.651961)
			(xy 27.718951 -106.573331) (xy 27.69509 -106.492064) (xy 27.679061 -106.408898) (xy 27.67101 -106.324584)
			(xy 20.637362 -106.324584) (xy 20.586954 -106.386884) (xy 20.582636 -106.4133) (xy 20.587462 -106.426)
			(xy 20.601022 -106.463465) (xy 20.62215 -106.540294) (xy 20.63632 -106.618706) (xy 20.64342 -106.698071)
			(xy 20.64385 -106.737912) (xy 20.643362 -106.779837) (xy 20.635471 -106.863316) (xy 20.619759 -106.945681)
			(xy 20.596365 -107.026202) (xy 20.565498 -107.104164) (xy 20.52743 -107.178875) (xy 20.482501 -107.249672)
			(xy 20.431108 -107.315927) (xy 20.373708 -107.377051) (xy 20.310811 -107.432503) (xy 20.242974 -107.481788)
			(xy 20.170801 -107.524472) (xy 20.09493 -107.560173) (xy 20.016037 -107.588576) (xy 19.934821 -107.609429)
			(xy 19.852003 -107.622546) (xy 19.768318 -107.627811) (xy 19.684509 -107.625177) (xy 19.601319 -107.614667)
			(xy 19.519488 -107.596376) (xy 19.439742 -107.570464) (xy 19.362788 -107.537163) (xy 19.289309 -107.496768)
			(xy 19.219958 -107.449637) (xy 19.15535 -107.396188) (xy 19.096059 -107.336897) (xy 19.042611 -107.272289)
			(xy 18.99548 -107.202938) (xy 18.955085 -107.129459) (xy 18.921784 -107.052504) (xy 18.895873 -106.972758)
			(xy 18.877582 -106.890927) (xy 18.867073 -106.807737) (xy 18.864439 -106.723928) (xy 18.418646 -106.723928)
			(xy 18.419576 -106.733664) (xy 18.42008 -106.776012) (xy 18.419557 -106.820337) (xy 18.410743 -106.908547)
			(xy 18.393194 -106.995442) (xy 18.367085 -107.080159) (xy 18.332674 -107.161857) (xy 18.290304 -107.239725)
			(xy 18.240394 -107.312989) (xy 18.183441 -107.380923) (xy 18.15211 -107.412282) (xy 18.14195 -107.422442)
			(xy 18.134838 -107.44962) (xy 18.16862 -107.563158) (xy 18.189702 -107.582208) (xy 18.203672 -107.584748)
			(xy 18.243723 -107.593014) (xy 18.322232 -107.615929) (xy 18.398306 -107.645952) (xy 18.471304 -107.682831)
			(xy 18.540609 -107.726254) (xy 18.605636 -107.775855) (xy 18.665836 -107.831214) (xy 18.720701 -107.891866)
			(xy 18.769768 -107.957296) (xy 18.812623 -108.026954) (xy 18.848903 -108.100251) (xy 18.878303 -108.176569)
			(xy 18.900574 -108.255263) (xy 18.915529 -108.335669) (xy 18.92304 -108.417108) (xy 18.923508 -108.458)
			(xy 18.923033 -108.499102) (xy 18.915448 -108.580957) (xy 18.900343 -108.661762) (xy 18.877847 -108.740829)
			(xy 18.848151 -108.817483) (xy 18.811509 -108.89107) (xy 18.768234 -108.960962) (xy 18.718694 -109.026563)
			(xy 18.663313 -109.087313) (xy 18.602563 -109.142694) (xy 18.536962 -109.192234) (xy 18.46707 -109.235509)
			(xy 18.432554 -109.252696) (xy 19.294598 -109.252696) (xy 19.294598 -109.168) (xy 19.302649 -109.083686)
			(xy 19.318678 -109.00052) (xy 19.342539 -108.919253) (xy 19.374018 -108.840623) (xy 19.412829 -108.765342)
			(xy 19.458619 -108.69409) (xy 19.510975 -108.627514) (xy 19.569423 -108.566216) (xy 19.633433 -108.510751)
			(xy 19.702425 -108.461622) (xy 19.775775 -108.419273) (xy 19.852818 -108.384089) (xy 19.932857 -108.356387)
			(xy 20.015166 -108.336419) (xy 20.099001 -108.324366) (xy 20.183602 -108.320336) (xy 20.268203 -108.324366)
			(xy 20.352038 -108.336419) (xy 20.434347 -108.356387) (xy 20.514386 -108.384089) (xy 20.591429 -108.419273)
			(xy 20.664779 -108.461622) (xy 20.733771 -108.510751) (xy 20.797781 -108.566216) (xy 20.856229 -108.627514)
			(xy 20.908585 -108.69409) (xy 20.954375 -108.765342) (xy 20.993186 -108.840623) (xy 21.024665 -108.919253)
			(xy 21.048526 -109.00052) (xy 21.064555 -109.083686) (xy 21.072606 -109.168) (xy 21.07311 -109.210348)
			(xy 21.072606 -109.252696) (xy 21.064555 -109.33701) (xy 21.048526 -109.420176) (xy 21.024665 -109.501443)
			(xy 20.993186 -109.580073) (xy 20.954375 -109.655354) (xy 20.908585 -109.726606) (xy 20.856229 -109.793182)
			(xy 20.797781 -109.85448) (xy 20.733771 -109.909945) (xy 20.664779 -109.959074) (xy 20.591429 -110.001423)
			(xy 20.514386 -110.036607) (xy 20.434347 -110.064309) (xy 20.352038 -110.084277) (xy 20.268203 -110.09633)
			(xy 20.183602 -110.100361) (xy 20.099001 -110.09633) (xy 20.015166 -110.084277) (xy 19.932857 -110.064309)
			(xy 19.852818 -110.036607) (xy 19.775775 -110.001423) (xy 19.702425 -109.959074) (xy 19.633433 -109.909945)
			(xy 19.569423 -109.85448) (xy 19.510975 -109.793182) (xy 19.458619 -109.726606) (xy 19.412829 -109.655354)
			(xy 19.374018 -109.580073) (xy 19.342539 -109.501443) (xy 19.318678 -109.420176) (xy 19.302649 -109.33701)
			(xy 19.294598 -109.252696) (xy 18.432554 -109.252696) (xy 18.393483 -109.272151) (xy 18.316829 -109.301847)
			(xy 18.237762 -109.324343) (xy 18.156957 -109.339448) (xy 18.075102 -109.347033) (xy 18.034 -109.347508)
			(xy 18.007076 -109.347) (xy 17.99717 -109.346746) (xy 17.97939 -109.353096) (xy 17.912588 -109.41177)
			(xy 17.903698 -109.428534) (xy 17.902936 -109.438186) (xy 17.897905 -109.481437) (xy 17.880541 -109.566767)
			(xy 17.854925 -109.649991) (xy 17.8213 -109.730316) (xy 17.779988 -109.80697) (xy 17.731385 -109.879223)
			(xy 17.675956 -109.946381) (xy 17.614231 -110.007802) (xy 17.546801 -110.0629) (xy 17.47431 -110.111146)
			(xy 17.397453 -110.15208) (xy 17.316964 -110.185308) (xy 17.233614 -110.210515) (xy 17.1482 -110.227457)
			(xy 17.061539 -110.235974) (xy 17.059419 -110.236) (xy 22.351492 -110.236) (xy 22.351996 -110.193652)
			(xy 22.360047 -110.109338) (xy 22.376076 -110.026172) (xy 22.399937 -109.944905) (xy 22.431416 -109.866275)
			(xy 22.470227 -109.790994) (xy 22.516017 -109.719742) (xy 22.568373 -109.653166) (xy 22.626821 -109.591868)
			(xy 22.690831 -109.536403) (xy 22.759823 -109.487274) (xy 22.833173 -109.444925) (xy 22.910216 -109.409741)
			(xy 22.990255 -109.382039) (xy 23.072564 -109.362071) (xy 23.156399 -109.350018) (xy 23.241 -109.345988)
			(xy 23.325601 -109.350018) (xy 23.409436 -109.362071) (xy 23.491745 -109.382039) (xy 23.571784 -109.409741)
			(xy 23.648827 -109.444925) (xy 23.722177 -109.487274) (xy 23.791169 -109.536403) (xy 23.855179 -109.591868)
			(xy 23.913627 -109.653166) (xy 23.965983 -109.719742) (xy 24.011773 -109.790994) (xy 24.044771 -109.855)
			(xy 32.256988 -109.855) (xy 32.261018 -109.770399) (xy 32.273071 -109.686564) (xy 32.293039 -109.604255)
			(xy 32.320741 -109.524216) (xy 32.355925 -109.447173) (xy 32.398274 -109.373823) (xy 32.447403 -109.304831)
			(xy 32.502868 -109.240821) (xy 32.564166 -109.182373) (xy 32.630742 -109.130017) (xy 32.701994 -109.084227)
			(xy 32.777275 -109.045416) (xy 32.855905 -109.013937) (xy 32.937172 -108.990076) (xy 33.020338 -108.974047)
			(xy 33.104652 -108.965996) (xy 33.147 -108.965492) (xy 33.187477 -108.965965) (xy 33.268097 -108.973315)
			(xy 33.347716 -108.987953) (xy 33.425678 -109.00976) (xy 33.501338 -109.038555) (xy 33.537906 -109.055916)
			(xy 33.54832 -109.060996) (xy 33.57118 -109.06125) (xy 33.663636 -109.018324) (xy 33.678114 -109.000544)
			(xy 33.681162 -108.989368) (xy 33.6919 -108.948631) (xy 33.719954 -108.869189) (xy 33.755394 -108.792756)
			(xy 33.797904 -108.720017) (xy 33.847103 -108.651624) (xy 33.902548 -108.588191) (xy 33.963744 -108.530284)
			(xy 34.030142 -108.478425) (xy 34.101146 -108.433077) (xy 34.17612 -108.394647) (xy 34.254393 -108.363479)
			(xy 34.335262 -108.339853) (xy 34.418004 -108.323981) (xy 34.501875 -108.316004) (xy 34.544 -108.315506)
			(xy 34.582863 -108.315936) (xy 34.66029 -108.322737) (xy 34.736828 -108.336268) (xy 34.811894 -108.356426)
			(xy 34.848546 -108.369354) (xy 34.859324 -108.37266) (xy 34.881743 -108.370533) (xy 34.891726 -108.36529)
			(xy 34.926 -108.345536) (xy 34.997411 -108.311484) (xy 35.071565 -108.283914) (xy 35.147877 -108.263046)
			(xy 35.225742 -108.249044) (xy 35.304543 -108.24202) (xy 35.3441 -108.241592) (xy 35.372757 -108.241815)
			(xy 35.429952 -108.245501) (xy 35.4584 -108.248958) (xy 35.467893 -108.249821) (xy 35.486369 -108.245171)
			(xy 35.501883 -108.234112) (xy 35.507422 -108.226352) (xy 35.532032 -108.189652) (xy 35.587379 -108.120766)
			(xy 35.649285 -108.057707) (xy 35.717138 -108.001097) (xy 35.79027 -107.951495) (xy 35.867961 -107.909389)
			(xy 35.949443 -107.875194) (xy 36.033915 -107.849247) (xy 36.120544 -107.831804) (xy 36.208475 -107.823038)
			(xy 36.252658 -107.822492) (xy 36.295007 -107.82298) (xy 36.379322 -107.831031) (xy 36.46249 -107.84706)
			(xy 36.543758 -107.870922) (xy 36.62239 -107.902401) (xy 36.697673 -107.941212) (xy 36.768926 -107.987004)
			(xy 36.835504 -108.039361) (xy 36.896803 -108.09781) (xy 36.952269 -108.161821) (xy 37.001399 -108.230814)
			(xy 37.043748 -108.304165) (xy 37.078933 -108.38121) (xy 37.106636 -108.46125) (xy 37.126604 -108.543561)
			(xy 37.138658 -108.627397) (xy 37.142688 -108.712) (xy 37.138658 -108.796603) (xy 37.126604 -108.880439)
			(xy 37.106636 -108.96275) (xy 37.078933 -109.04279) (xy 37.043748 -109.119835) (xy 37.001399 -109.193186)
			(xy 36.952269 -109.262179) (xy 36.896803 -109.32619) (xy 36.835504 -109.384639) (xy 36.768926 -109.436996)
			(xy 36.697673 -109.482788) (xy 36.62239 -109.521599) (xy 36.543758 -109.553078) (xy 36.46249 -109.57694)
			(xy 36.379322 -109.592969) (xy 36.295007 -109.60102) (xy 36.252658 -109.601508) (xy 36.224001 -109.601289)
			(xy 36.166806 -109.5976) (xy 36.138358 -109.594142) (xy 36.128864 -109.593325) (xy 36.110392 -109.597954)
			(xy 36.094877 -109.608995) (xy 36.089336 -109.616748) (xy 36.064754 -109.653467) (xy 36.009403 -109.722354)
			(xy 35.947495 -109.785412) (xy 35.879638 -109.842021) (xy 35.806503 -109.891622) (xy 35.728809 -109.933726)
			(xy 35.647323 -109.967918) (xy 35.562849 -109.993862) (xy 35.476218 -110.011301) (xy 35.388284 -110.020064)
			(xy 35.3441 -110.020608) (xy 35.305237 -110.020177) (xy 35.22781 -110.013377) (xy 35.151272 -109.999846)
			(xy 35.076206 -109.979687) (xy 35.039554 -109.96676) (xy 35.028776 -109.963453) (xy 35.006356 -109.96558)
			(xy 34.996374 -109.970824) (xy 34.9621 -109.990579) (xy 34.89069 -110.024631) (xy 34.816535 -110.0522)
			(xy 34.740223 -110.073068) (xy 34.662358 -110.08707) (xy 34.583557 -110.094094) (xy 34.544 -110.094522)
			(xy 34.503523 -110.094048) (xy 34.422903 -110.086698) (xy 34.343284 -110.07206) (xy 34.265322 -110.050253)
			(xy 34.189662 -110.021459) (xy 34.153094 -110.004098) (xy 34.14268 -109.999018) (xy 34.11982 -109.998764)
			(xy 34.027364 -110.04169) (xy 34.012886 -110.05947) (xy 34.009838 -110.070646) (xy 33.99911 -110.111386)
			(xy 33.971055 -110.190828) (xy 33.935613 -110.26726) (xy 33.893102 -110.339999) (xy 33.843903 -110.408392)
			(xy 33.788456 -110.471825) (xy 33.72726 -110.529731) (xy 33.660861 -110.58159) (xy 33.589857 -110.626938)
			(xy 33.514882 -110.665368) (xy 33.436608 -110.696535) (xy 33.355738 -110.720161) (xy 33.272997 -110.736034)
			(xy 33.189125 -110.74401) (xy 33.147 -110.744508) (xy 33.104652 -110.744004) (xy 33.020338 -110.735953)
			(xy 32.937172 -110.719924) (xy 32.855905 -110.696063) (xy 32.777275 -110.664584) (xy 32.701994 -110.625773)
			(xy 32.630742 -110.579983) (xy 32.564166 -110.527627) (xy 32.502868 -110.469179) (xy 32.447403 -110.405169)
			(xy 32.398274 -110.336177) (xy 32.355925 -110.262827) (xy 32.320741 -110.185784) (xy 32.293039 -110.105745)
			(xy 32.273071 -110.023436) (xy 32.261018 -109.939601) (xy 32.256988 -109.855) (xy 24.044771 -109.855)
			(xy 24.050584 -109.866275) (xy 24.082063 -109.944905) (xy 24.105924 -110.026172) (xy 24.121953 -110.109338)
			(xy 24.130004 -110.193652) (xy 24.130508 -110.236) (xy 24.129991 -110.280598) (xy 24.121076 -110.369349)
			(xy 24.103325 -110.456761) (xy 24.076916 -110.541959) (xy 24.042116 -110.624087) (xy 23.999272 -110.70232)
			(xy 23.948815 -110.775874) (xy 23.92045 -110.810294) (xy 23.914787 -110.817483) (xy 23.908545 -110.834674)
			(xy 23.908258 -110.843822) (xy 23.90902 -110.873794) (xy 23.909553 -110.882966) (xy 23.916324 -110.900029)
			(xy 23.922228 -110.907068) (xy 23.949566 -110.93773) (xy 23.999047 -111.003311) (xy 24.042271 -111.073175)
			(xy 24.078868 -111.146727) (xy 24.108527 -111.22334) (xy 24.130995 -111.302362) (xy 24.146081 -111.383119)
			(xy 24.153657 -111.464923) (xy 24.15413 -111.506) (xy 24.153626 -111.548348) (xy 24.145575 -111.632662)
			(xy 24.129546 -111.715828) (xy 24.105685 -111.797095) (xy 24.074206 -111.875725) (xy 24.035395 -111.951006)
			(xy 23.989605 -112.022258) (xy 23.937249 -112.088834) (xy 23.878801 -112.150132) (xy 23.861199 -112.165384)
			(xy 26.250392 -112.165384) (xy 26.250851 -112.124281) (xy 26.258438 -112.042427) (xy 26.273544 -111.961621)
			(xy 26.296042 -111.882554) (xy 26.325739 -111.8059) (xy 26.362382 -111.732313) (xy 26.405659 -111.662421)
			(xy 26.455199 -111.59682) (xy 26.510581 -111.53607) (xy 26.571332 -111.480689) (xy 26.636934 -111.43115)
			(xy 26.706827 -111.387874) (xy 26.780415 -111.351233) (xy 26.857069 -111.321537) (xy 26.936137 -111.299041)
			(xy 27.016942 -111.283936) (xy 27.098797 -111.276351) (xy 27.1399 -111.275876) (xy 27.181334 -111.27637)
			(xy 27.263845 -111.28406) (xy 27.345282 -111.299392) (xy 27.42494 -111.322233) (xy 27.502128 -111.352384)
			(xy 27.576177 -111.389585) (xy 27.646444 -111.433513) (xy 27.71232 -111.483787) (xy 27.773234 -111.53997)
			(xy 27.828658 -111.601576) (xy 27.878111 -111.668071) (xy 27.921164 -111.738877) (xy 27.957443 -111.813382)
			(xy 27.986635 -111.890938) (xy 28.008486 -111.970873) (xy 28.022807 -112.052495) (xy 28.026614 -112.093756)
			(xy 28.027753 -112.10313) (xy 28.03592 -112.120138) (xy 28.049703 -112.133022) (xy 28.067222 -112.140025)
			(xy 28.076652 -112.140492) (xy 28.120017 -112.141442) (xy 28.206253 -112.150831) (xy 28.291165 -112.16857)
			(xy 28.373948 -112.194489) (xy 28.453815 -112.228343) (xy 28.530007 -112.26981) (xy 28.601801 -112.318496)
			(xy 28.668516 -112.373939) (xy 28.729517 -112.435613) (xy 28.784225 -112.502931) (xy 28.832122 -112.575255)
			(xy 28.872751 -112.651897) (xy 28.905727 -112.73213) (xy 28.930737 -112.815192) (xy 28.947544 -112.900294)
			(xy 28.955987 -112.986627) (xy 28.956508 -113.03) (xy 28.956033 -113.071102) (xy 28.948448 -113.152957)
			(xy 28.933343 -113.233762) (xy 28.910847 -113.312829) (xy 28.881151 -113.389483) (xy 28.844509 -113.46307)
			(xy 28.801234 -113.532962) (xy 28.751694 -113.598563) (xy 28.696313 -113.659313) (xy 28.635563 -113.714694)
			(xy 28.569962 -113.764234) (xy 28.50007 -113.807509) (xy 28.426483 -113.844151) (xy 28.349829 -113.873847)
			(xy 28.270762 -113.896343) (xy 28.189957 -113.911448) (xy 28.108102 -113.919033) (xy 28.067 -113.919508)
			(xy 28.025565 -113.919029) (xy 27.943054 -113.911338) (xy 27.861616 -113.896006) (xy 27.781957 -113.873165)
			(xy 27.704768 -113.843013) (xy 27.630719 -113.805811) (xy 27.560451 -113.761882) (xy 27.494575 -113.711608)
			(xy 27.433661 -113.655423) (xy 27.378237 -113.593816) (xy 27.328784 -113.52732) (xy 27.285732 -113.456512)
			(xy 27.249453 -113.382006) (xy 27.220262 -113.304449) (xy 27.198412 -113.224512) (xy 27.184092 -113.14289)
			(xy 27.180286 -113.101628) (xy 27.179159 -113.092252) (xy 27.170987 -113.075244) (xy 27.157201 -113.062361)
			(xy 27.139679 -113.055358) (xy 27.130248 -113.054892) (xy 27.086885 -113.053899) (xy 27.000651 -113.044511)
			(xy 26.915741 -113.026774) (xy 26.83296 -113.000857) (xy 26.753095 -112.967006) (xy 26.676904 -112.925541)
			(xy 26.605111 -112.876858) (xy 26.538397 -112.821418) (xy 26.477396 -112.759748) (xy 26.422687 -112.692433)
			(xy 26.37479 -112.620112) (xy 26.33416 -112.543473) (xy 26.301182 -112.463244) (xy 26.27617 -112.380185)
			(xy 26.259361 -112.295086) (xy 26.250914 -112.208755) (xy 26.250392 -112.165384) (xy 23.861199 -112.165384)
			(xy 23.814791 -112.205597) (xy 23.745799 -112.254726) (xy 23.672449 -112.297075) (xy 23.595406 -112.332259)
			(xy 23.515367 -112.359961) (xy 23.433058 -112.379929) (xy 23.349223 -112.391982) (xy 23.264622 -112.396013)
			(xy 23.180021 -112.391982) (xy 23.096186 -112.379929) (xy 23.013877 -112.359961) (xy 22.933838 -112.332259)
			(xy 22.856795 -112.297075) (xy 22.783445 -112.254726) (xy 22.714453 -112.205597) (xy 22.650443 -112.150132)
			(xy 22.591995 -112.088834) (xy 22.539639 -112.022258) (xy 22.493849 -111.951006) (xy 22.455038 -111.875725)
			(xy 22.423559 -111.797095) (xy 22.399698 -111.715828) (xy 22.383669 -111.632662) (xy 22.375618 -111.548348)
			(xy 22.375114 -111.506) (xy 22.375626 -111.461401) (xy 22.384542 -111.372651) (xy 22.402293 -111.285238)
			(xy 22.428702 -111.20004) (xy 22.463504 -111.117913) (xy 22.506349 -111.039679) (xy 22.556807 -110.966126)
			(xy 22.585172 -110.931706) (xy 22.590826 -110.92451) (xy 22.597075 -110.907325) (xy 22.597364 -110.898178)
			(xy 22.596602 -110.868206) (xy 22.596064 -110.859035) (xy 22.589296 -110.841972) (xy 22.583394 -110.834932)
			(xy 22.55606 -110.804267) (xy 22.506578 -110.738687) (xy 22.463354 -110.668823) (xy 22.426756 -110.595272)
			(xy 22.397096 -110.518659) (xy 22.374627 -110.439637) (xy 22.359541 -110.358881) (xy 22.351965 -110.277077)
			(xy 22.351492 -110.236) (xy 17.059419 -110.236) (xy 17.018 -110.236508) (xy 16.976531 -110.235969)
			(xy 16.893951 -110.228257) (xy 16.812448 -110.21289) (xy 16.73273 -110.190003) (xy 16.655488 -110.159794)
			(xy 16.581395 -110.122525) (xy 16.511092 -110.078521) (xy 16.445192 -110.028162) (xy 16.384266 -109.971887)
			(xy 16.328843 -109.910185) (xy 16.279406 -109.843591) (xy 16.236382 -109.772684) (xy 16.200147 -109.698079)
			(xy 16.185134 -109.65942) (xy 16.180308 -109.64672) (xy 16.160496 -109.629956) (xy 16.049244 -109.608112)
			(xy 16.024352 -109.61624) (xy 16.015208 -109.626146) (xy 15.987185 -109.655906) (xy 15.926553 -109.710739)
			(xy 15.861145 -109.759777) (xy 15.791514 -109.802605) (xy 15.718246 -109.838864) (xy 15.64196 -109.868245)
			(xy 15.563299 -109.890502) (xy 15.482928 -109.905447) (xy 15.401524 -109.912953) (xy 15.36065 -109.91342)
			(xy 15.319547 -109.912981) (xy 15.237692 -109.905392) (xy 15.156887 -109.890283) (xy 15.07782 -109.867782)
			(xy 15.001166 -109.838083) (xy 14.92758 -109.801438) (xy 14.857688 -109.75816) (xy 14.792088 -109.708618)
			(xy 14.731338 -109.653235) (xy 14.675958 -109.592483) (xy 14.626418 -109.52688) (xy 14.583143 -109.456987)
			(xy 14.546501 -109.383399) (xy 14.516805 -109.306744) (xy 14.494309 -109.227676) (xy 14.479203 -109.14687)
			(xy 14.471617 -109.065015) (xy 14.471142 -109.023912) (xy 9.983 -109.023912) (xy 9.972968 -109.066046)
			(xy 9.94139 -109.164068) (xy 9.902278 -109.259334) (xy 9.855869 -109.351267) (xy 9.802446 -109.439309)
			(xy 9.742332 -109.522925) (xy 9.675892 -109.601609) (xy 9.640062 -109.638592) (xy 9.632696 -109.645704)
			(xy 9.62533 -109.663992) (xy 9.62533 -109.75594) (xy 9.632696 -109.774228) (xy 9.640062 -109.78134)
			(xy 9.675897 -109.81832) (xy 9.742337 -109.897004) (xy 9.802451 -109.98062) (xy 9.855874 -110.068662)
			(xy 9.902282 -110.160596) (xy 9.941394 -110.255862) (xy 9.972972 -110.353884) (xy 9.996825 -110.454066)
			(xy 10.012807 -110.555801) (xy 10.020823 -110.658471) (xy 10.020823 -110.761454) (xy 10.012807 -110.864125)
			(xy 9.996824 -110.965859) (xy 9.972971 -111.066042) (xy 9.941392 -111.164063) (xy 9.90228 -111.25933)
			(xy 9.855871 -111.351263) (xy 9.802447 -111.439304) (xy 9.742333 -111.522921) (xy 9.675893 -111.601605)
			(xy 9.640062 -111.638588) (xy 9.632696 -111.6457) (xy 9.62533 -111.663988) (xy 9.62533 -111.755936)
			(xy 9.632696 -111.774224) (xy 9.640062 -111.781336) (xy 9.675893 -111.818319) (xy 9.742333 -111.897003)
			(xy 9.802447 -111.980619) (xy 9.822702 -112.014) (xy 13.969492 -112.014) (xy 13.969967 -111.972898)
			(xy 13.977552 -111.891043) (xy 13.992657 -111.810238) (xy 14.015153 -111.731171) (xy 14.044849 -111.654517)
			(xy 14.081491 -111.58093) (xy 14.124766 -111.511038) (xy 14.174306 -111.445437) (xy 14.229687 -111.384687)
			(xy 14.290437 -111.329306) (xy 14.356038 -111.279766) (xy 14.42593 -111.236491) (xy 14.499517 -111.199849)
			(xy 14.576171 -111.170153) (xy 14.655238 -111.147657) (xy 14.736043 -111.132552) (xy 14.817898 -111.124967)
			(xy 14.859 -111.124492) (xy 14.899815 -111.124938) (xy 14.9811 -111.132417) (xy 15.061359 -111.147312)
			(xy 15.139915 -111.169498) (xy 15.173306 -111.182334) (xy 18.155662 -111.182334) (xy 18.155662 -111.097638)
			(xy 18.163713 -111.013324) (xy 18.179742 -110.930158) (xy 18.203603 -110.848891) (xy 18.235082 -110.770261)
			(xy 18.273893 -110.69498) (xy 18.319683 -110.623728) (xy 18.372039 -110.557152) (xy 18.430487 -110.495854)
			(xy 18.494497 -110.440389) (xy 18.563489 -110.39126) (xy 18.636839 -110.348911) (xy 18.713882 -110.313727)
			(xy 18.793921 -110.286025) (xy 18.87623 -110.266057) (xy 18.960065 -110.254004) (xy 19.044666 -110.249974)
			(xy 19.129267 -110.254004) (xy 19.213102 -110.266057) (xy 19.295411 -110.286025) (xy 19.37545 -110.313727)
			(xy 19.452493 -110.348911) (xy 19.525843 -110.39126) (xy 19.594835 -110.440389) (xy 19.658845 -110.495854)
			(xy 19.717293 -110.557152) (xy 19.769649 -110.623728) (xy 19.815439 -110.69498) (xy 19.85425 -110.770261)
			(xy 19.885729 -110.848891) (xy 19.90959 -110.930158) (xy 19.925619 -111.013324) (xy 19.93367 -111.097638)
			(xy 19.934174 -111.139986) (xy 19.93367 -111.182334) (xy 19.925619 -111.266648) (xy 19.90959 -111.349814)
			(xy 19.885729 -111.431081) (xy 19.85425 -111.509711) (xy 19.815439 -111.584992) (xy 19.769649 -111.656244)
			(xy 19.717293 -111.72282) (xy 19.658845 -111.784118) (xy 19.594835 -111.839583) (xy 19.525843 -111.888712)
			(xy 19.452493 -111.931061) (xy 19.37545 -111.966245) (xy 19.295411 -111.993947) (xy 19.213102 -112.013915)
			(xy 19.129267 -112.025968) (xy 19.044666 -112.029999) (xy 18.960065 -112.025968) (xy 18.87623 -112.013915)
			(xy 18.793921 -111.993947) (xy 18.713882 -111.966245) (xy 18.636839 -111.931061) (xy 18.563489 -111.888712)
			(xy 18.494497 -111.839583) (xy 18.430487 -111.784118) (xy 18.372039 -111.72282) (xy 18.319683 -111.656244)
			(xy 18.273893 -111.584992) (xy 18.235082 -111.509711) (xy 18.203603 -111.431081) (xy 18.179742 -111.349814)
			(xy 18.163713 -111.266648) (xy 18.155662 -111.182334) (xy 15.173306 -111.182334) (xy 15.216108 -111.198788)
			(xy 15.289298 -111.234936) (xy 15.358867 -111.277637) (xy 15.424231 -111.326533) (xy 15.484841 -111.381212)
			(xy 15.540186 -111.441215) (xy 15.5898 -111.506035) (xy 15.633267 -111.575129) (xy 15.67022 -111.647915)
			(xy 15.70035 -111.72378) (xy 15.723401 -111.802087) (xy 15.731744 -111.842042) (xy 15.733638 -111.850365)
			(xy 15.742205 -111.86512) (xy 15.755159 -111.876224) (xy 15.762986 -111.879634) (xy 15.803349 -111.896148)
			(xy 15.880941 -111.935969) (xy 15.954264 -111.983192) (xy 16.022612 -112.037366) (xy 16.085331 -112.097969)
			(xy 16.141816 -112.164419) (xy 16.191527 -112.236079) (xy 16.233986 -112.31226) (xy 16.268784 -112.392231)
			(xy 16.295589 -112.475224) (xy 16.314142 -112.560442) (xy 16.324265 -112.647066) (xy 16.325596 -112.690656)
			(xy 16.32585 -112.701832) (xy 16.335502 -112.721898) (xy 16.412464 -112.785144) (xy 16.4338 -112.790986)
			(xy 16.444976 -112.788954) (xy 16.483147 -112.782667) (xy 16.560217 -112.775922) (xy 16.5989 -112.775492)
			(xy 16.647668 -112.776153) (xy 16.744616 -112.786857) (xy 16.839811 -112.808103) (xy 16.886174 -112.823244)
			(xy 16.898366 -112.827308) (xy 16.923512 -112.823244) (xy 17.010888 -112.755172) (xy 17.021302 -112.731804)
			(xy 17.020286 -112.719104) (xy 17.018981 -112.701607) (xy 17.017582 -112.666545) (xy 17.017492 -112.649)
			(xy 17.017976 -112.607075) (xy 17.025867 -112.523596) (xy 17.041579 -112.441231) (xy 17.064972 -112.360709)
			(xy 17.09584 -112.282747) (xy 17.133907 -112.208036) (xy 17.178837 -112.137238) (xy 17.230229 -112.070983)
			(xy 17.287629 -112.009859) (xy 17.350526 -111.954407) (xy 17.418363 -111.905121) (xy 17.490537 -111.862438)
			(xy 17.566407 -111.826736) (xy 17.6453 -111.798332) (xy 17.726517 -111.777479) (xy 17.809335 -111.764362)
			(xy 17.89302 -111.759097) (xy 17.97683 -111.761731) (xy 18.060019 -111.77224) (xy 18.14185 -111.790532)
			(xy 18.221597 -111.816443) (xy 18.298551 -111.849744) (xy 18.37203 -111.89014) (xy 18.441382 -111.937271)
			(xy 18.50599 -111.990719) (xy 18.565281 -112.05001) (xy 18.618729 -112.114618) (xy 18.66586 -112.18397)
			(xy 18.706256 -112.257449) (xy 18.739557 -112.334403) (xy 18.765468 -112.41415) (xy 18.78376 -112.495981)
			(xy 18.794269 -112.57917) (xy 18.796903 -112.66298) (xy 18.791638 -112.746665) (xy 18.778521 -112.829483)
			(xy 18.757668 -112.9107) (xy 18.729264 -112.989593) (xy 18.693562 -113.065463) (xy 18.650879 -113.137637)
			(xy 18.601593 -113.205474) (xy 18.546141 -113.268371) (xy 18.485017 -113.325771) (xy 18.418762 -113.377163)
			(xy 18.347964 -113.422093) (xy 18.273253 -113.46016) (xy 18.195291 -113.491028) (xy 18.114769 -113.514421)
			(xy 18.032404 -113.530133) (xy 17.948925 -113.538024) (xy 17.907 -113.538508) (xy 17.858232 -113.537847)
			(xy 17.761284 -113.527143) (xy 17.666089 -113.505897) (xy 17.619726 -113.490756) (xy 17.607534 -113.486692)
			(xy 17.582388 -113.490756) (xy 17.495012 -113.558828) (xy 17.484598 -113.582196) (xy 17.485614 -113.594896)
			(xy 17.486919 -113.612393) (xy 17.488318 -113.647455) (xy 17.488408 -113.665) (xy 17.487933 -113.706102)
			(xy 17.480348 -113.787957) (xy 17.465243 -113.868762) (xy 17.442747 -113.947829) (xy 17.413051 -114.024483)
			(xy 17.376409 -114.09807) (xy 17.333134 -114.167962) (xy 17.283594 -114.233563) (xy 17.228213 -114.294313)
			(xy 17.196418 -114.323298) (xy 19.303996 -114.323298) (xy 19.303996 -114.238602) (xy 19.312047 -114.154288)
			(xy 19.328076 -114.071122) (xy 19.351937 -113.989855) (xy 19.383416 -113.911225) (xy 19.422227 -113.835944)
			(xy 19.468017 -113.764692) (xy 19.520373 -113.698116) (xy 19.578821 -113.636818) (xy 19.642831 -113.581353)
			(xy 19.711823 -113.532224) (xy 19.785173 -113.489875) (xy 19.862216 -113.454691) (xy 19.942255 -113.426989)
			(xy 20.024564 -113.407021) (xy 20.108399 -113.394968) (xy 20.193 -113.390938) (xy 20.277601 -113.394968)
			(xy 20.361436 -113.407021) (xy 20.443745 -113.426989) (xy 20.519904 -113.453348) (xy 24.723086 -113.453348)
			(xy 24.723086 -113.368652) (xy 24.731137 -113.284338) (xy 24.747166 -113.201172) (xy 24.771027 -113.119905)
			(xy 24.802506 -113.041275) (xy 24.841317 -112.965994) (xy 24.887107 -112.894742) (xy 24.939463 -112.828166)
			(xy 24.997911 -112.766868) (xy 25.061921 -112.711403) (xy 25.130913 -112.662274) (xy 25.204263 -112.619925)
			(xy 25.281306 -112.584741) (xy 25.361345 -112.557039) (xy 25.443654 -112.537071) (xy 25.527489 -112.525018)
			(xy 25.61209 -112.520988) (xy 25.696691 -112.525018) (xy 25.780526 -112.537071) (xy 25.862835 -112.557039)
			(xy 25.942874 -112.584741) (xy 26.019917 -112.619925) (xy 26.093267 -112.662274) (xy 26.162259 -112.711403)
			(xy 26.226269 -112.766868) (xy 26.284717 -112.828166) (xy 26.337073 -112.894742) (xy 26.382863 -112.965994)
			(xy 26.421674 -113.041275) (xy 26.453153 -113.119905) (xy 26.477014 -113.201172) (xy 26.493043 -113.284338)
			(xy 26.501094 -113.368652) (xy 26.501598 -113.411) (xy 26.501094 -113.453348) (xy 26.493043 -113.537662)
			(xy 26.477014 -113.620828) (xy 26.453153 -113.702095) (xy 26.421674 -113.780725) (xy 26.382863 -113.856006)
			(xy 26.337073 -113.927258) (xy 26.284717 -113.993834) (xy 26.226269 -114.055132) (xy 26.162259 -114.110597)
			(xy 26.093267 -114.159726) (xy 26.019917 -114.202075) (xy 25.942874 -114.237259) (xy 25.862835 -114.264961)
			(xy 25.780526 -114.284929) (xy 25.696691 -114.296982) (xy 25.61209 -114.301013) (xy 25.527489 -114.296982)
			(xy 25.443654 -114.284929) (xy 25.361345 -114.264961) (xy 25.281306 -114.237259) (xy 25.204263 -114.202075)
			(xy 25.130913 -114.159726) (xy 25.061921 -114.110597) (xy 24.997911 -114.055132) (xy 24.939463 -113.993834)
			(xy 24.887107 -113.927258) (xy 24.841317 -113.856006) (xy 24.802506 -113.780725) (xy 24.771027 -113.702095)
			(xy 24.747166 -113.620828) (xy 24.731137 -113.537662) (xy 24.723086 -113.453348) (xy 20.519904 -113.453348)
			(xy 20.523784 -113.454691) (xy 20.600827 -113.489875) (xy 20.674177 -113.532224) (xy 20.743169 -113.581353)
			(xy 20.807179 -113.636818) (xy 20.865627 -113.698116) (xy 20.917983 -113.764692) (xy 20.963773 -113.835944)
			(xy 21.002584 -113.911225) (xy 21.034063 -113.989855) (xy 21.057924 -114.071122) (xy 21.073953 -114.154288)
			(xy 21.082004 -114.238602) (xy 21.082508 -114.28095) (xy 21.082004 -114.323298) (xy 21.073953 -114.407612)
			(xy 21.057924 -114.490778) (xy 21.034063 -114.572045) (xy 21.002584 -114.650675) (xy 20.963773 -114.725956)
			(xy 20.917983 -114.797208) (xy 20.865627 -114.863784) (xy 20.807179 -114.925082) (xy 20.743169 -114.980547)
			(xy 20.674177 -115.029676) (xy 20.650427 -115.043388) (xy 22.239982 -115.043388) (xy 22.239982 -114.958692)
			(xy 22.248033 -114.874378) (xy 22.264062 -114.791212) (xy 22.287923 -114.709945) (xy 22.319402 -114.631315)
			(xy 22.358213 -114.556034) (xy 22.404003 -114.484782) (xy 22.456359 -114.418206) (xy 22.514807 -114.356908)
			(xy 22.578817 -114.301443) (xy 22.647809 -114.252314) (xy 22.721159 -114.209965) (xy 22.798202 -114.174781)
			(xy 22.878241 -114.147079) (xy 22.96055 -114.127111) (xy 23.044385 -114.115058) (xy 23.128986 -114.111028)
			(xy 23.213587 -114.115058) (xy 23.297422 -114.127111) (xy 23.379731 -114.147079) (xy 23.45977 -114.174781)
			(xy 23.536813 -114.209965) (xy 23.610163 -114.252314) (xy 23.679155 -114.301443) (xy 23.743165 -114.356908)
			(xy 23.801613 -114.418206) (xy 23.853969 -114.484782) (xy 23.899759 -114.556034) (xy 23.93857 -114.631315)
			(xy 23.970049 -114.709945) (xy 23.99391 -114.791212) (xy 24.009939 -114.874378) (xy 24.01799 -114.958692)
			(xy 24.018494 -115.00104) (xy 24.01799 -115.043388) (xy 24.009939 -115.127702) (xy 23.99391 -115.210868)
			(xy 23.970049 -115.292135) (xy 23.963879 -115.307548) (xy 30.911796 -115.307548) (xy 30.911796 -115.222852)
			(xy 30.919847 -115.138538) (xy 30.935876 -115.055372) (xy 30.959737 -114.974105) (xy 30.991216 -114.895475)
			(xy 31.030027 -114.820194) (xy 31.075817 -114.748942) (xy 31.128173 -114.682366) (xy 31.186621 -114.621068)
			(xy 31.250631 -114.565603) (xy 31.319623 -114.516474) (xy 31.392973 -114.474125) (xy 31.470016 -114.438941)
			(xy 31.550055 -114.411239) (xy 31.632364 -114.391271) (xy 31.716199 -114.379218) (xy 31.8008 -114.375188)
			(xy 31.885401 -114.379218) (xy 31.969236 -114.391271) (xy 32.051545 -114.411239) (xy 32.131584 -114.438941)
			(xy 32.208627 -114.474125) (xy 32.281977 -114.516474) (xy 32.350969 -114.565603) (xy 32.414979 -114.621068)
			(xy 32.473427 -114.682366) (xy 32.525783 -114.748942) (xy 32.571573 -114.820194) (xy 32.610384 -114.895475)
			(xy 32.641863 -114.974105) (xy 32.665724 -115.055372) (xy 32.681753 -115.138538) (xy 32.689804 -115.222852)
			(xy 32.690308 -115.2652) (xy 32.689804 -115.307548) (xy 32.681753 -115.391862) (xy 32.665724 -115.475028)
			(xy 32.641863 -115.556295) (xy 32.610384 -115.634925) (xy 32.571573 -115.710206) (xy 32.525783 -115.781458)
			(xy 32.473427 -115.848034) (xy 32.414979 -115.909332) (xy 32.350969 -115.964797) (xy 32.281977 -116.013926)
			(xy 32.208627 -116.056275) (xy 32.131584 -116.091459) (xy 32.051545 -116.119161) (xy 31.969236 -116.139129)
			(xy 31.885401 -116.151182) (xy 31.8008 -116.155213) (xy 31.716199 -116.151182) (xy 31.632364 -116.139129)
			(xy 31.550055 -116.119161) (xy 31.470016 -116.091459) (xy 31.392973 -116.056275) (xy 31.319623 -116.013926)
			(xy 31.250631 -115.964797) (xy 31.186621 -115.909332) (xy 31.128173 -115.848034) (xy 31.075817 -115.781458)
			(xy 31.030027 -115.710206) (xy 30.991216 -115.634925) (xy 30.959737 -115.556295) (xy 30.935876 -115.475028)
			(xy 30.919847 -115.391862) (xy 30.911796 -115.307548) (xy 23.963879 -115.307548) (xy 23.93857 -115.370765)
			(xy 23.899759 -115.446046) (xy 23.853969 -115.517298) (xy 23.801613 -115.583874) (xy 23.743165 -115.645172)
			(xy 23.679155 -115.700637) (xy 23.610163 -115.749766) (xy 23.536813 -115.792115) (xy 23.45977 -115.827299)
			(xy 23.379731 -115.855001) (xy 23.297422 -115.874969) (xy 23.213587 -115.887022) (xy 23.128986 -115.891053)
			(xy 23.044385 -115.887022) (xy 22.96055 -115.874969) (xy 22.878241 -115.855001) (xy 22.798202 -115.827299)
			(xy 22.721159 -115.792115) (xy 22.647809 -115.749766) (xy 22.578817 -115.700637) (xy 22.514807 -115.645172)
			(xy 22.456359 -115.583874) (xy 22.404003 -115.517298) (xy 22.358213 -115.446046) (xy 22.319402 -115.370765)
			(xy 22.287923 -115.292135) (xy 22.264062 -115.210868) (xy 22.248033 -115.127702) (xy 22.239982 -115.043388)
			(xy 20.650427 -115.043388) (xy 20.600827 -115.072025) (xy 20.523784 -115.107209) (xy 20.443745 -115.134911)
			(xy 20.361436 -115.154879) (xy 20.277601 -115.166932) (xy 20.193 -115.170963) (xy 20.108399 -115.166932)
			(xy 20.024564 -115.154879) (xy 19.942255 -115.134911) (xy 19.862216 -115.107209) (xy 19.785173 -115.072025)
			(xy 19.711823 -115.029676) (xy 19.642831 -114.980547) (xy 19.578821 -114.925082) (xy 19.520373 -114.863784)
			(xy 19.468017 -114.797208) (xy 19.422227 -114.725956) (xy 19.383416 -114.650675) (xy 19.351937 -114.572045)
			(xy 19.328076 -114.490778) (xy 19.312047 -114.407612) (xy 19.303996 -114.323298) (xy 17.196418 -114.323298)
			(xy 17.167463 -114.349694) (xy 17.101862 -114.399234) (xy 17.03197 -114.442509) (xy 16.958383 -114.479151)
			(xy 16.881729 -114.508847) (xy 16.802662 -114.531343) (xy 16.721857 -114.546448) (xy 16.640002 -114.554033)
			(xy 16.5989 -114.554508) (xy 16.55574 -114.553984) (xy 16.469828 -114.545604) (xy 16.385131 -114.528942)
			(xy 16.302447 -114.504154) (xy 16.222552 -114.471474) (xy 16.146198 -114.43121) (xy 16.074103 -114.383739)
			(xy 16.006945 -114.329508) (xy 15.945356 -114.269027) (xy 15.889914 -114.202865) (xy 15.841142 -114.131644)
			(xy 15.799497 -114.056034) (xy 15.765372 -113.976746) (xy 15.739087 -113.894525) (xy 15.720889 -113.810145)
			(xy 15.71095 -113.724399) (xy 15.709646 -113.681256) (xy 15.709392 -113.67008) (xy 15.69974 -113.650014)
			(xy 15.622778 -113.586768) (xy 15.601442 -113.580926) (xy 15.590266 -113.582958) (xy 15.552096 -113.589253)
			(xy 15.475025 -113.595992) (xy 15.436342 -113.59642) (xy 15.395528 -113.595925) (xy 15.314244 -113.58845)
			(xy 15.233987 -113.573559) (xy 15.155432 -113.551377) (xy 15.07924 -113.52209) (xy 15.006051 -113.485946)
			(xy 14.936482 -113.443249) (xy 14.871117 -113.394356) (xy 14.810508 -113.339681) (xy 14.755162 -113.279682)
			(xy 14.705547 -113.214864) (xy 14.662079 -113.145774) (xy 14.625125 -113.072991) (xy 14.594994 -112.997128)
			(xy 14.571941 -112.918824) (xy 14.563598 -112.87887) (xy 14.561674 -112.870556) (xy 14.553119 -112.855801)
			(xy 14.540177 -112.844693) (xy 14.532356 -112.841278) (xy 14.4945 -112.825838) (xy 14.42152 -112.788972)
			(xy 14.352233 -112.745562) (xy 14.287224 -112.695976) (xy 14.22704 -112.640631) (xy 14.172192 -112.579995)
			(xy 14.123141 -112.51458) (xy 14.080302 -112.444939) (xy 14.044036 -112.371659) (xy 14.014651 -112.295359)
			(xy 13.992394 -112.216685) (xy 13.977453 -112.136299) (xy 13.969953 -112.054881) (xy 13.969492 -112.014)
			(xy 9.822702 -112.014) (xy 9.85587 -112.068661) (xy 9.902278 -112.160594) (xy 9.94139 -112.25586)
			(xy 9.972969 -112.353882) (xy 9.996822 -112.454064) (xy 10.012804 -112.555799) (xy 10.02082 -112.658469)
			(xy 10.02082 -112.761451) (xy 10.012804 -112.864121) (xy 9.996822 -112.965856) (xy 9.972969 -113.066038)
			(xy 9.94139 -113.16406) (xy 9.902278 -113.259326) (xy 9.85587 -113.351259) (xy 9.802447 -113.439301)
			(xy 9.742333 -113.522917) (xy 9.675893 -113.601601) (xy 9.640062 -113.638584) (xy 9.632696 -113.645696)
			(xy 9.62533 -113.663984) (xy 9.62533 -113.755932) (xy 9.632696 -113.77422) (xy 9.640062 -113.781332)
			(xy 9.675889 -113.818319) (xy 9.742329 -113.897003) (xy 9.802443 -113.980619) (xy 9.855866 -114.06866)
			(xy 9.902275 -114.160593) (xy 9.941387 -114.255859) (xy 9.972965 -114.35388) (xy 9.996818 -114.454062)
			(xy 10.012801 -114.555796) (xy 10.020817 -114.658466) (xy 10.020817 -114.761448) (xy 10.012802 -114.864118)
			(xy 9.996819 -114.965853) (xy 9.972967 -115.066035) (xy 9.941389 -115.164056) (xy 9.902277 -115.259322)
			(xy 9.855869 -115.351255) (xy 9.802446 -115.439297) (xy 9.799784 -115.443) (xy 13.969492 -115.443)
			(xy 13.969967 -115.401898) (xy 13.977552 -115.320043) (xy 13.992657 -115.239238) (xy 14.015153 -115.160171)
			(xy 14.044849 -115.083517) (xy 14.081491 -115.00993) (xy 14.124766 -114.940038) (xy 14.174306 -114.874437)
			(xy 14.229687 -114.813687) (xy 14.290437 -114.758306) (xy 14.356038 -114.708766) (xy 14.42593 -114.665491)
			(xy 14.499517 -114.628849) (xy 14.576171 -114.599153) (xy 14.655238 -114.576657) (xy 14.736043 -114.561552)
			(xy 14.817898 -114.553967) (xy 14.859 -114.553492) (xy 14.899815 -114.553938) (xy 14.9811 -114.561417)
			(xy 15.061359 -114.576312) (xy 15.139915 -114.598498) (xy 15.216108 -114.627788) (xy 15.289298 -114.663936)
			(xy 15.358867 -114.706637) (xy 15.424231 -114.755533) (xy 15.484841 -114.810212) (xy 15.540186 -114.870215)
			(xy 15.5898 -114.935035) (xy 15.633267 -115.004129) (xy 15.67022 -115.076915) (xy 15.70035 -115.15278)
			(xy 15.723401 -115.231087) (xy 15.731744 -115.271042) (xy 15.733638 -115.279365) (xy 15.742205 -115.29412)
			(xy 15.755159 -115.305224) (xy 15.762986 -115.308634) (xy 15.800844 -115.324071) (xy 15.873823 -115.360937)
			(xy 15.94311 -115.404347) (xy 16.008119 -115.453934) (xy 16.068303 -115.50928) (xy 16.123151 -115.569916)
			(xy 16.172202 -115.635331) (xy 16.215041 -115.704972) (xy 16.251306 -115.778252) (xy 16.280691 -115.854552)
			(xy 16.302949 -115.933227) (xy 16.31789 -116.013613) (xy 16.325389 -116.095031) (xy 16.32585 -116.135912)
			(xy 16.325345 -116.177013) (xy 16.317759 -116.258866) (xy 16.302654 -116.339669) (xy 16.280158 -116.418734)
			(xy 16.250463 -116.495386) (xy 16.213822 -116.568971) (xy 16.170549 -116.638861) (xy 16.121011 -116.704461)
			(xy 16.065632 -116.765211) (xy 16.004884 -116.820592) (xy 15.939286 -116.870132) (xy 15.869397 -116.913408)
			(xy 15.795813 -116.950051) (xy 15.719162 -116.979748) (xy 15.640098 -117.002247) (xy 15.559295 -117.017355)
			(xy 15.477443 -117.024943) (xy 15.436342 -117.02542) (xy 15.395528 -117.024925) (xy 15.314244 -117.01745)
			(xy 15.233987 -117.002559) (xy 15.155432 -116.980377) (xy 15.07924 -116.95109) (xy 15.006051 -116.914946)
			(xy 14.936482 -116.872249) (xy 14.871117 -116.823356) (xy 14.810508 -116.768681) (xy 14.755162 -116.708682)
			(xy 14.705547 -116.643864) (xy 14.662079 -116.574774) (xy 14.625125 -116.501991) (xy 14.594994 -116.426128)
			(xy 14.571941 -116.347824) (xy 14.563598 -116.30787) (xy 14.561674 -116.299556) (xy 14.553119 -116.284801)
			(xy 14.540177 -116.273693) (xy 14.532356 -116.270278) (xy 14.4945 -116.254838) (xy 14.42152 -116.217972)
			(xy 14.352233 -116.174562) (xy 14.287224 -116.124976) (xy 14.22704 -116.069631) (xy 14.172192 -116.008995)
			(xy 14.123141 -115.94358) (xy 14.080302 -115.873939) (xy 14.044036 -115.800659) (xy 14.014651 -115.724359)
			(xy 13.992394 -115.645685) (xy 13.977453 -115.565299) (xy 13.969953 -115.483881) (xy 13.969492 -115.443)
			(xy 9.799784 -115.443) (xy 9.742332 -115.522913) (xy 9.675892 -115.601597) (xy 9.640062 -115.63858)
			(xy 9.632696 -115.645692) (xy 9.62533 -115.66398) (xy 9.62533 -115.755928) (xy 9.632696 -115.774216)
			(xy 9.640062 -115.781328) (xy 9.675895 -115.818309) (xy 9.742335 -115.896993) (xy 9.802449 -115.98061)
			(xy 9.855872 -116.068652) (xy 9.90228 -116.160585) (xy 9.941392 -116.255851) (xy 9.97297 -116.353873)
			(xy 9.996823 -116.454055) (xy 10.012806 -116.55579) (xy 10.020822 -116.65846) (xy 10.020821 -116.761443)
			(xy 10.012806 -116.864113) (xy 9.996823 -116.965848) (xy 9.97297 -117.06603) (xy 9.941391 -117.164051)
			(xy 9.902279 -117.259318) (xy 9.85587 -117.351251) (xy 9.802447 -117.439293) (xy 9.742333 -117.522909)
			(xy 9.675893 -117.601593) (xy 9.640062 -117.638576) (xy 9.632696 -117.645688) (xy 9.62533 -117.663976)
			(xy 9.62533 -117.755924) (xy 9.632696 -117.774212) (xy 9.640062 -117.781324) (xy 9.67589 -117.81831)
			(xy 9.742331 -117.896993) (xy 9.802446 -117.980609) (xy 9.85587 -118.06865) (xy 9.902279 -118.160583)
			(xy 9.941392 -118.255849) (xy 9.97297 -118.35387) (xy 9.996824 -118.454052) (xy 10.012807 -118.555787)
			(xy 10.020823 -118.658457) (xy 10.021316 -118.709948) (xy 10.020845 -118.761843) (xy 10.012698 -118.865312)
			(xy 9.996459 -118.967823) (xy 9.972226 -119.068745) (xy 9.940151 -119.167454) (xy 9.90043 -119.263342)
			(xy 9.853308 -119.355818) (xy 9.799076 -119.444312) (xy 9.776044 -119.476012) (xy 15.683992 -119.476012)
			(xy 15.684436 -119.433467) (xy 15.69257 -119.348767) (xy 15.708754 -119.26523) (xy 15.732841 -119.183621)
			(xy 15.76461 -119.104685) (xy 15.803772 -119.029142) (xy 15.849968 -118.957685) (xy 15.902777 -118.890965)
			(xy 15.961715 -118.829593) (xy 16.026245 -118.774129) (xy 16.095775 -118.72508) (xy 16.169671 -118.682895)
			(xy 16.247258 -118.647958) (xy 16.327827 -118.62059) (xy 16.41064 -118.601041) (xy 16.494942 -118.589488)
			(xy 16.537432 -118.587266) (xy 16.552418 -118.586758) (xy 16.576294 -118.569994) (xy 16.623792 -118.45798)
			(xy 16.618966 -118.429024) (xy 16.60906 -118.418102) (xy 16.582335 -118.387558) (xy 16.533957 -118.322386)
			(xy 16.491717 -118.253077) (xy 16.455966 -118.180209) (xy 16.427002 -118.104387) (xy 16.405065 -118.026242)
			(xy 16.390338 -117.946423) (xy 16.382943 -117.865595) (xy 16.382492 -117.825012) (xy 16.383064 -117.782258)
			(xy 16.39126 -117.697144) (xy 16.407586 -117.613209) (xy 16.431892 -117.531228) (xy 16.463953 -117.451958)
			(xy 16.503474 -117.376131) (xy 16.55009 -117.304447) (xy 16.60337 -117.237568) (xy 16.662823 -117.17611)
			(xy 16.727899 -117.120642) (xy 16.797998 -117.071676) (xy 16.872473 -117.029662) (xy 16.950636 -116.99499)
			(xy 17.031766 -116.96798) (xy 17.115113 -116.94888) (xy 17.157446 -116.94287) (xy 17.166766 -116.941348)
			(xy 17.183342 -116.932325) (xy 17.189704 -116.925344) (xy 17.209008 -116.902484) (xy 17.214811 -116.895078)
			(xy 17.221058 -116.877348) (xy 17.2212 -116.86794) (xy 17.220692 -116.84) (xy 17.221196 -116.797652)
			(xy 17.229247 -116.713338) (xy 17.245276 -116.630172) (xy 17.269137 -116.548905) (xy 17.300616 -116.470275)
			(xy 17.339427 -116.394994) (xy 17.385217 -116.323742) (xy 17.437573 -116.257166) (xy 17.496021 -116.195868)
			(xy 17.560031 -116.140403) (xy 17.629023 -116.091274) (xy 17.702373 -116.048925) (xy 17.779416 -116.013741)
			(xy 17.859455 -115.986039) (xy 17.941764 -115.966071) (xy 18.025599 -115.954018) (xy 18.1102 -115.949988)
			(xy 18.194801 -115.954018) (xy 18.278636 -115.966071) (xy 18.360945 -115.986039) (xy 18.440984 -116.013741)
			(xy 18.518027 -116.048925) (xy 18.591377 -116.091274) (xy 18.660369 -116.140403) (xy 18.724379 -116.195868)
			(xy 18.782827 -116.257166) (xy 18.835183 -116.323742) (xy 18.880973 -116.394994) (xy 18.919784 -116.470275)
			(xy 18.951263 -116.548905) (xy 18.975124 -116.630172) (xy 18.991153 -116.713338) (xy 18.999204 -116.797652)
			(xy 18.999708 -116.84) (xy 18.999147 -116.882754) (xy 18.99095 -116.967869) (xy 18.974623 -117.051804)
			(xy 18.950316 -117.133785) (xy 18.918254 -117.213055) (xy 18.878732 -117.288882) (xy 18.832115 -117.360566)
			(xy 18.778834 -117.427445) (xy 18.719381 -117.488902) (xy 18.654304 -117.54437) (xy 18.605719 -117.578308)
			(xy 23.240996 -117.578308) (xy 23.240996 -117.493612) (xy 23.249047 -117.409298) (xy 23.265076 -117.326132)
			(xy 23.288937 -117.244865) (xy 23.320416 -117.166235) (xy 23.359227 -117.090954) (xy 23.405017 -117.019702)
			(xy 23.457373 -116.953126) (xy 23.515821 -116.891828) (xy 23.579831 -116.836363) (xy 23.648823 -116.787234)
			(xy 23.722173 -116.744885) (xy 23.799216 -116.709701) (xy 23.879255 -116.681999) (xy 23.961564 -116.662031)
			(xy 24.045399 -116.649978) (xy 24.13 -116.645948) (xy 24.214601 -116.649978) (xy 24.298436 -116.662031)
			(xy 24.380745 -116.681999) (xy 24.460784 -116.709701) (xy 24.537827 -116.744885) (xy 24.611177 -116.787234)
			(xy 24.680169 -116.836363) (xy 24.744179 -116.891828) (xy 24.802627 -116.953126) (xy 24.854983 -117.019702)
			(xy 24.900773 -117.090954) (xy 24.939584 -117.166235) (xy 24.971063 -117.244865) (xy 24.994924 -117.326132)
			(xy 25.010953 -117.409298) (xy 25.019004 -117.493612) (xy 25.019508 -117.53596) (xy 25.019004 -117.578308)
			(xy 25.012698 -117.644348) (xy 30.098996 -117.644348) (xy 30.098996 -117.559652) (xy 30.107047 -117.475338)
			(xy 30.123076 -117.392172) (xy 30.146937 -117.310905) (xy 30.178416 -117.232275) (xy 30.217227 -117.156994)
			(xy 30.263017 -117.085742) (xy 30.315373 -117.019166) (xy 30.373821 -116.957868) (xy 30.437831 -116.902403)
			(xy 30.506823 -116.853274) (xy 30.580173 -116.810925) (xy 30.657216 -116.775741) (xy 30.737255 -116.748039)
			(xy 30.819564 -116.728071) (xy 30.903399 -116.716018) (xy 30.988 -116.711988) (xy 31.072601 -116.716018)
			(xy 31.156436 -116.728071) (xy 31.238745 -116.748039) (xy 31.318784 -116.775741) (xy 31.395827 -116.810925)
			(xy 31.469177 -116.853274) (xy 31.538169 -116.902403) (xy 31.602179 -116.957868) (xy 31.660627 -117.019166)
			(xy 31.712983 -117.085742) (xy 31.758773 -117.156994) (xy 31.797584 -117.232275) (xy 31.829063 -117.310905)
			(xy 31.852924 -117.392172) (xy 31.868953 -117.475338) (xy 31.877004 -117.559652) (xy 31.877508 -117.602)
			(xy 31.877004 -117.644348) (xy 31.868953 -117.728662) (xy 31.852924 -117.811828) (xy 31.829063 -117.893095)
			(xy 31.797584 -117.971725) (xy 31.758773 -118.047006) (xy 31.712983 -118.118258) (xy 31.660627 -118.184834)
			(xy 31.602179 -118.246132) (xy 31.538169 -118.301597) (xy 31.469177 -118.350726) (xy 31.395827 -118.393075)
			(xy 31.318784 -118.428259) (xy 31.238745 -118.455961) (xy 31.156436 -118.475929) (xy 31.072601 -118.487982)
			(xy 30.988 -118.492013) (xy 30.903399 -118.487982) (xy 30.819564 -118.475929) (xy 30.737255 -118.455961)
			(xy 30.657216 -118.428259) (xy 30.580173 -118.393075) (xy 30.506823 -118.350726) (xy 30.437831 -118.301597)
			(xy 30.373821 -118.246132) (xy 30.315373 -118.184834) (xy 30.263017 -118.118258) (xy 30.217227 -118.047006)
			(xy 30.178416 -117.971725) (xy 30.146937 -117.893095) (xy 30.123076 -117.811828) (xy 30.107047 -117.728662)
			(xy 30.098996 -117.644348) (xy 25.012698 -117.644348) (xy 25.010953 -117.662622) (xy 24.994924 -117.745788)
			(xy 24.971063 -117.827055) (xy 24.939584 -117.905685) (xy 24.900773 -117.980966) (xy 24.854983 -118.052218)
			(xy 24.802627 -118.118794) (xy 24.744179 -118.180092) (xy 24.680169 -118.235557) (xy 24.611177 -118.284686)
			(xy 24.537827 -118.327035) (xy 24.460784 -118.362219) (xy 24.380745 -118.389921) (xy 24.298436 -118.409889)
			(xy 24.214601 -118.421942) (xy 24.13 -118.425973) (xy 24.045399 -118.421942) (xy 23.961564 -118.409889)
			(xy 23.879255 -118.389921) (xy 23.799216 -118.362219) (xy 23.722173 -118.327035) (xy 23.648823 -118.284686)
			(xy 23.579831 -118.235557) (xy 23.515821 -118.180092) (xy 23.457373 -118.118794) (xy 23.405017 -118.052218)
			(xy 23.359227 -117.980966) (xy 23.320416 -117.905685) (xy 23.288937 -117.827055) (xy 23.265076 -117.745788)
			(xy 23.249047 -117.662622) (xy 23.240996 -117.578308) (xy 18.605719 -117.578308) (xy 18.584204 -117.593337)
			(xy 18.509729 -117.63535) (xy 18.431565 -117.670022) (xy 18.350435 -117.697032) (xy 18.267087 -117.716132)
			(xy 18.224754 -117.722142) (xy 18.215433 -117.72366) (xy 18.198857 -117.732686) (xy 18.192496 -117.739668)
			(xy 18.173192 -117.762528) (xy 18.167384 -117.76993) (xy 18.16114 -117.787663) (xy 18.161 -117.797072)
			(xy 18.161508 -117.825012) (xy 18.160992 -117.867556) (xy 18.152865 -117.952254) (xy 18.136688 -118.035789)
			(xy 18.112607 -118.117397) (xy 18.080844 -118.196333) (xy 18.041688 -118.271875) (xy 17.995497 -118.343333)
			(xy 17.942693 -118.410054) (xy 17.88376 -118.471426) (xy 17.819235 -118.526891) (xy 17.749708 -118.575941)
			(xy 17.675815 -118.618127) (xy 17.598232 -118.653064) (xy 17.517666 -118.680433) (xy 17.434856 -118.699983)
			(xy 17.350556 -118.711536) (xy 17.308068 -118.713758) (xy 17.293082 -118.714266) (xy 17.269206 -118.73103)
			(xy 17.221708 -118.843044) (xy 17.226534 -118.872) (xy 17.23644 -118.882922) (xy 17.263177 -118.913456)
			(xy 17.311554 -118.97863) (xy 17.353793 -119.04794) (xy 17.389542 -119.12081) (xy 17.418505 -119.196633)
			(xy 17.44044 -119.27478) (xy 17.455165 -119.3546) (xy 17.462558 -119.435429) (xy 17.463008 -119.476012)
			(xy 17.462504 -119.51836) (xy 17.454453 -119.602674) (xy 17.438424 -119.68584) (xy 17.414563 -119.767107)
			(xy 17.383084 -119.845737) (xy 17.344273 -119.921018) (xy 17.298483 -119.99227) (xy 17.246127 -120.058846)
			(xy 17.187679 -120.120144) (xy 17.123669 -120.175609) (xy 17.054677 -120.224738) (xy 16.981327 -120.267087)
			(xy 16.904284 -120.302271) (xy 16.824245 -120.329973) (xy 16.741936 -120.349941) (xy 16.658101 -120.361994)
			(xy 16.5735 -120.366025) (xy 16.488899 -120.361994) (xy 16.405064 -120.349941) (xy 16.322755 -120.329973)
			(xy 16.242716 -120.302271) (xy 16.165673 -120.267087) (xy 16.092323 -120.224738) (xy 16.023331 -120.175609)
			(xy 15.959321 -120.120144) (xy 15.900873 -120.058846) (xy 15.848517 -119.99227) (xy 15.802727 -119.921018)
			(xy 15.763916 -119.845737) (xy 15.732437 -119.767107) (xy 15.708576 -119.68584) (xy 15.692547 -119.602674)
			(xy 15.684496 -119.51836) (xy 15.683992 -119.476012) (xy 9.776044 -119.476012) (xy 9.738069 -119.528278)
			(xy 9.670661 -119.607199) (xy 9.59727 -119.680589) (xy 9.518347 -119.747994) (xy 9.434379 -119.808999)
			(xy 9.345883 -119.863228) (xy 9.253405 -119.910347) (xy 9.157516 -119.950065) (xy 9.058806 -119.982137)
			(xy 8.957884 -120.006367) (xy 8.855372 -120.022603) (xy 8.751903 -120.030747) (xy 8.700008 -120.031256)
			(xy 8.648517 -120.030758) (xy 8.545847 -120.022742) (xy 8.444112 -120.00676) (xy 8.34393 -119.982908)
			(xy 8.245908 -119.95133) (xy 8.150642 -119.912218) (xy 8.058709 -119.86581) (xy 7.970667 -119.812387)
			(xy 7.887051 -119.752273) (xy 7.808367 -119.685833) (xy 7.771384 -119.650002) (xy 7.764272 -119.642636)
			(xy 7.745984 -119.63527) (xy 7.654036 -119.63527) (xy 7.635748 -119.642636) (xy 7.628636 -119.650002)
			(xy 7.591647 -119.685827) (xy 7.512964 -119.752268) (xy 7.429349 -119.812383) (xy 7.341308 -119.865807)
			(xy 7.249376 -119.912216) (xy 7.15411 -119.951329) (xy 7.056089 -119.982908) (xy 6.955907 -120.006762)
			(xy 6.854173 -120.022746) (xy 6.751503 -120.030762) (xy 6.700012 -120.031256) (xy 6.648117 -120.030759)
			(xy 6.544647 -120.022616) (xy 6.442136 -120.00638) (xy 6.341214 -119.982151) (xy 6.242504 -119.950078)
			(xy 6.146614 -119.91036) (xy 6.054137 -119.86324) (xy 5.965642 -119.809011) (xy 5.881674 -119.748004)
			(xy 5.802752 -119.680598) (xy 5.729362 -119.607208) (xy 5.661956 -119.528286) (xy 5.600949 -119.444318)
			(xy 5.54672 -119.355823) (xy 5.4996 -119.263346) (xy 5.459882 -119.167456) (xy 5.427809 -119.068746)
			(xy 5.40358 -118.967824) (xy 5.387344 -118.865313) (xy 5.379201 -118.761843) (xy 5.378704 -118.709948)
			(xy 1.651254 -118.709948) (xy 1.651254 -119.500904) (xy 1.652778 -119.55145) (xy 1.651254 -119.601996)
			(xy 1.651254 -120.48991) (xy 11.732002 -120.48991) (xy 11.732002 -120.405214) (xy 11.740053 -120.3209)
			(xy 11.756082 -120.237734) (xy 11.779943 -120.156467) (xy 11.811422 -120.077837) (xy 11.850233 -120.002556)
			(xy 11.896023 -119.931304) (xy 11.948379 -119.864728) (xy 12.006827 -119.80343) (xy 12.070837 -119.747965)
			(xy 12.139829 -119.698836) (xy 12.213179 -119.656487) (xy 12.290222 -119.621303) (xy 12.370261 -119.593601)
			(xy 12.45257 -119.573633) (xy 12.536405 -119.56158) (xy 12.621006 -119.55755) (xy 12.705607 -119.56158)
			(xy 12.789442 -119.573633) (xy 12.871751 -119.593601) (xy 12.95179 -119.621303) (xy 13.028833 -119.656487)
			(xy 13.102183 -119.698836) (xy 13.171175 -119.747965) (xy 13.235185 -119.80343) (xy 13.293633 -119.864728)
			(xy 13.345989 -119.931304) (xy 13.391779 -120.002556) (xy 13.43059 -120.077837) (xy 13.462069 -120.156467)
			(xy 13.48593 -120.237734) (xy 13.501959 -120.3209) (xy 13.51001 -120.405214) (xy 13.510514 -120.447562)
			(xy 13.51001 -120.48991) (xy 13.501959 -120.574224) (xy 13.48593 -120.65739) (xy 13.475666 -120.692348)
			(xy 18.033996 -120.692348) (xy 18.033996 -120.607652) (xy 18.042047 -120.523338) (xy 18.058076 -120.440172)
			(xy 18.081937 -120.358905) (xy 18.113416 -120.280275) (xy 18.152227 -120.204994) (xy 18.198017 -120.133742)
			(xy 18.250373 -120.067166) (xy 18.308821 -120.005868) (xy 18.372831 -119.950403) (xy 18.441823 -119.901274)
			(xy 18.515173 -119.858925) (xy 18.592216 -119.823741) (xy 18.672255 -119.796039) (xy 18.754564 -119.776071)
			(xy 18.838399 -119.764018) (xy 18.923 -119.759988) (xy 19.007601 -119.764018) (xy 19.091436 -119.776071)
			(xy 19.173745 -119.796039) (xy 19.253784 -119.823741) (xy 19.330827 -119.858925) (xy 19.404177 -119.901274)
			(xy 19.473169 -119.950403) (xy 19.537179 -120.005868) (xy 19.595627 -120.067166) (xy 19.647983 -120.133742)
			(xy 19.676424 -120.177998) (xy 20.827996 -120.177998) (xy 20.827996 -120.093302) (xy 20.836047 -120.008988)
			(xy 20.852076 -119.925822) (xy 20.875937 -119.844555) (xy 20.907416 -119.765925) (xy 20.946227 -119.690644)
			(xy 20.992017 -119.619392) (xy 21.044373 -119.552816) (xy 21.102821 -119.491518) (xy 21.166831 -119.436053)
			(xy 21.235823 -119.386924) (xy 21.309173 -119.344575) (xy 21.386216 -119.309391) (xy 21.466255 -119.281689)
			(xy 21.548564 -119.261721) (xy 21.632399 -119.249668) (xy 21.717 -119.245638) (xy 21.801601 -119.249668)
			(xy 21.885436 -119.261721) (xy 21.954188 -119.2784) (xy 30.986988 -119.2784) (xy 30.991018 -119.193799)
			(xy 31.003071 -119.109964) (xy 31.023039 -119.027655) (xy 31.050741 -118.947616) (xy 31.085925 -118.870573)
			(xy 31.128274 -118.797223) (xy 31.177403 -118.728231) (xy 31.232868 -118.664221) (xy 31.294166 -118.605773)
			(xy 31.360742 -118.553417) (xy 31.431994 -118.507627) (xy 31.507275 -118.468816) (xy 31.585905 -118.437337)
			(xy 31.667172 -118.413476) (xy 31.750338 -118.397447) (xy 31.834652 -118.389396) (xy 31.877 -118.388892)
			(xy 31.903224 -118.389064) (xy 31.955582 -118.392115) (xy 31.981648 -118.394988) (xy 31.990897 -118.395623)
			(xy 32.00886 -118.391109) (xy 32.024075 -118.380547) (xy 32.029654 -118.373144) (xy 32.054411 -118.337511)
			(xy 32.109834 -118.270743) (xy 32.171496 -118.209691) (xy 32.238811 -118.154935) (xy 32.311139 -118.106996)
			(xy 32.387793 -118.06633) (xy 32.468043 -118.033322) (xy 32.551126 -118.008288) (xy 32.636253 -117.991465)
			(xy 32.722614 -117.983014) (xy 32.766 -117.982492) (xy 32.808867 -117.983006) (xy 32.894203 -117.991255)
			(xy 32.978349 -118.007676) (xy 33.060525 -118.032118) (xy 33.139969 -118.064352) (xy 33.215942 -118.104081)
			(xy 33.28774 -118.150935) (xy 33.354697 -118.204479) (xy 33.416191 -118.264218) (xy 33.471653 -118.329596)
			(xy 33.520566 -118.400007) (xy 33.54197 -118.437152) (xy 33.548066 -118.448074) (xy 33.56864 -118.461536)
			(xy 33.676082 -118.472458) (xy 33.699196 -118.463568) (xy 33.707324 -118.45417) (xy 33.727898 -118.431056)
			(xy 33.735264 -118.423182) (xy 33.742122 -118.403878) (xy 33.73628 -118.309136) (xy 33.727136 -118.290848)
			(xy 33.719008 -118.28399) (xy 33.686242 -118.255854) (xy 33.625699 -118.194254) (xy 33.571412 -118.127076)
			(xy 33.523891 -118.054953) (xy 33.483586 -117.978563) (xy 33.450874 -117.898626) (xy 33.426064 -117.815895)
			(xy 33.40939 -117.731149) (xy 33.401009 -117.645185) (xy 33.400492 -117.602) (xy 33.400996 -117.559652)
			(xy 33.409047 -117.475338) (xy 33.425076 -117.392172) (xy 33.448937 -117.310905) (xy 33.480416 -117.232275)
			(xy 33.519227 -117.156994) (xy 33.565017 -117.085742) (xy 33.617373 -117.019166) (xy 33.675821 -116.957868)
			(xy 33.739831 -116.902403) (xy 33.808823 -116.853274) (xy 33.882173 -116.810925) (xy 33.959216 -116.775741)
			(xy 34.039255 -116.748039) (xy 34.121564 -116.728071) (xy 34.205399 -116.716018) (xy 34.29 -116.711988)
			(xy 34.374601 -116.716018) (xy 34.458436 -116.728071) (xy 34.540745 -116.748039) (xy 34.620784 -116.775741)
			(xy 34.697827 -116.810925) (xy 34.771177 -116.853274) (xy 34.840169 -116.902403) (xy 34.904179 -116.957868)
			(xy 34.962627 -117.019166) (xy 35.014983 -117.085742) (xy 35.060773 -117.156994) (xy 35.099584 -117.232275)
			(xy 35.131063 -117.310905) (xy 35.154924 -117.392172) (xy 35.170953 -117.475338) (xy 35.179004 -117.559652)
			(xy 35.179508 -117.602) (xy 35.179015 -117.64372) (xy 35.171211 -117.726793) (xy 35.155663 -117.808771)
			(xy 35.132506 -117.888932) (xy 35.101945 -117.966573) (xy 35.064248 -118.041011) (xy 35.019747 -118.111592)
			(xy 34.968831 -118.177696) (xy 34.940748 -118.208552) (xy 34.933382 -118.216426) (xy 34.926524 -118.23573)
			(xy 34.932366 -118.330472) (xy 34.94151 -118.34876) (xy 34.949638 -118.355618) (xy 34.982397 -118.383763)
			(xy 35.042942 -118.44536) (xy 35.097231 -118.512536) (xy 35.144752 -118.584658) (xy 35.185059 -118.661047)
			(xy 35.205071 -118.709948) (xy 41.678606 -118.709948) (xy 41.679075 -118.658456) (xy 41.687095 -118.555786)
			(xy 41.703081 -118.45405) (xy 41.726938 -118.353868) (xy 41.758519 -118.255847) (xy 41.797634 -118.160581)
			(xy 41.844045 -118.068648) (xy 41.897471 -117.980607) (xy 41.957587 -117.896991) (xy 42.024029 -117.818307)
			(xy 42.05986 -117.781324) (xy 42.067226 -117.774212) (xy 42.074592 -117.755924) (xy 42.074592 -117.663976)
			(xy 42.067226 -117.645688) (xy 42.05986 -117.638576) (xy 42.024031 -117.601591) (xy 41.957591 -117.522907)
			(xy 41.897477 -117.439291) (xy 41.844054 -117.351249) (xy 41.797645 -117.259317) (xy 41.758533 -117.164051)
			(xy 41.726955 -117.066029) (xy 41.703102 -116.965847) (xy 41.687119 -116.864113) (xy 41.679103 -116.761443)
			(xy 41.679103 -116.65846) (xy 41.687118 -116.55579) (xy 41.703101 -116.454055) (xy 41.726954 -116.353874)
			(xy 41.758532 -116.255852) (xy 41.797644 -116.160586) (xy 41.844052 -116.068653) (xy 41.897476 -115.980611)
			(xy 41.95759 -115.896995) (xy 42.024029 -115.818311) (xy 42.05986 -115.781328) (xy 42.067226 -115.774216)
			(xy 42.074592 -115.755928) (xy 42.074592 -115.66398) (xy 42.067226 -115.645692) (xy 42.05986 -115.63858)
			(xy 42.024025 -115.601601) (xy 41.957585 -115.522917) (xy 41.897471 -115.4393) (xy 41.844048 -115.351258)
			(xy 41.797639 -115.259325) (xy 41.758528 -115.164058) (xy 41.726949 -115.066036) (xy 41.703097 -114.965854)
			(xy 41.687114 -114.864119) (xy 41.679098 -114.761449) (xy 41.679099 -114.658466) (xy 41.687115 -114.555795)
			(xy 41.703098 -114.45406) (xy 41.726951 -114.353878) (xy 41.758529 -114.255857) (xy 41.797642 -114.16059)
			(xy 41.844051 -114.068657) (xy 41.897474 -113.980615) (xy 41.957589 -113.896999) (xy 42.024029 -113.818315)
			(xy 42.05986 -113.781332) (xy 42.067226 -113.77422) (xy 42.074592 -113.755932) (xy 42.074592 -113.663984)
			(xy 42.067226 -113.645696) (xy 42.05986 -113.638584) (xy 42.024029 -113.601601) (xy 41.957589 -113.522917)
			(xy 41.897475 -113.439301) (xy 41.844052 -113.351259) (xy 41.797643 -113.259326) (xy 41.758531 -113.16406)
			(xy 41.726953 -113.066038) (xy 41.7031 -112.965856) (xy 41.687117 -112.864121) (xy 41.679101 -112.761451)
			(xy 41.679101 -112.658469) (xy 41.687117 -112.555799) (xy 41.7031 -112.454064) (xy 41.726953 -112.353882)
			(xy 41.758531 -112.25586) (xy 41.797643 -112.160594) (xy 41.844052 -112.068661) (xy 41.897475 -111.980619)
			(xy 41.957589 -111.897003) (xy 42.024029 -111.818319) (xy 42.05986 -111.781336) (xy 42.067226 -111.774224)
			(xy 42.074592 -111.755936) (xy 42.074592 -111.663988) (xy 42.067226 -111.6457) (xy 42.05986 -111.638588)
			(xy 42.024033 -111.601601) (xy 41.957593 -111.522918) (xy 41.897479 -111.439301) (xy 41.844056 -111.35126)
			(xy 41.797647 -111.259327) (xy 41.758535 -111.164061) (xy 41.726956 -111.06604) (xy 41.703103 -110.965858)
			(xy 41.68712 -110.864124) (xy 41.679104 -110.761454) (xy 41.679104 -110.658472) (xy 41.68712 -110.555802)
			(xy 41.703102 -110.454067) (xy 41.726955 -110.353885) (xy 41.758533 -110.255864) (xy 41.797645 -110.160598)
			(xy 41.844053 -110.068665) (xy 41.897476 -109.980623) (xy 41.95759 -109.897007) (xy 42.02403 -109.818323)
			(xy 42.05986 -109.78134) (xy 42.067226 -109.774228) (xy 42.074592 -109.75594) (xy 42.074592 -109.663992)
			(xy 42.067226 -109.645704) (xy 42.05986 -109.638592) (xy 42.024027 -109.601611) (xy 41.957587 -109.522927)
			(xy 41.897473 -109.43931) (xy 41.84405 -109.351268) (xy 41.797641 -109.259335) (xy 41.758529 -109.164069)
			(xy 41.726951 -109.066047) (xy 41.703098 -108.965865) (xy 41.687116 -108.86413) (xy 41.6791 -108.76146)
			(xy 41.6791 -108.658477) (xy 41.687116 -108.555807) (xy 41.703099 -108.454072) (xy 41.726952 -108.35389)
			(xy 41.75853 -108.255868) (xy 41.797643 -108.160602) (xy 41.844051 -108.068669) (xy 41.897475 -107.980627)
			(xy 41.957589 -107.897011) (xy 42.024029 -107.818327) (xy 42.05986 -107.781344) (xy 42.067226 -107.774232)
			(xy 42.074592 -107.755944) (xy 42.074592 -107.663996) (xy 42.067226 -107.645708) (xy 42.05986 -107.638596)
			(xy 42.024031 -107.601611) (xy 41.957591 -107.522927) (xy 41.897477 -107.439311) (xy 41.844054 -107.351269)
			(xy 41.797645 -107.259337) (xy 41.758533 -107.164071) (xy 41.726955 -107.066049) (xy 41.703102 -106.965867)
			(xy 41.687119 -106.864133) (xy 41.679103 -106.761463) (xy 41.679103 -106.65848) (xy 41.687118 -106.55581)
			(xy 41.703101 -106.454075) (xy 41.726954 -106.353894) (xy 41.758532 -106.255872) (xy 41.797644 -106.160606)
			(xy 41.844052 -106.068673) (xy 41.897476 -105.980631) (xy 41.95759 -105.897015) (xy 42.024029 -105.818331)
			(xy 42.05986 -105.781348) (xy 42.067226 -105.774236) (xy 42.074592 -105.755948) (xy 42.074592 -105.664)
			(xy 42.067226 -105.645712) (xy 42.05986 -105.6386) (xy 42.02401 -105.601635) (xy 41.957572 -105.522948)
			(xy 41.897459 -105.43933) (xy 41.844037 -105.351286) (xy 41.797631 -105.25935) (xy 41.75852 -105.164082)
			(xy 41.726944 -105.066059) (xy 41.703093 -104.965875) (xy 41.687112 -104.864139) (xy 41.679098 -104.761468)
			(xy 41.678606 -104.709976) (xy 41.679079 -104.658081) (xy 41.687224 -104.554611) (xy 41.703462 -104.452099)
			(xy 41.727693 -104.351177) (xy 41.759767 -104.252468) (xy 41.799488 -104.156579) (xy 41.846609 -104.064102)
			(xy 41.90084 -103.975607) (xy 41.961848 -103.89164) (xy 42.029255 -103.812719) (xy 42.102647 -103.739329)
			(xy 42.18157 -103.671924) (xy 42.265539 -103.610919) (xy 42.354035 -103.55669) (xy 42.446513 -103.509572)
			(xy 42.542403 -103.469854) (xy 42.641114 -103.437782) (xy 42.742036 -103.413554) (xy 42.844549 -103.397319)
			(xy 42.948019 -103.389177) (xy 42.999914 -103.388668) (xy 43.051406 -103.389145) (xy 43.154077 -103.397162)
			(xy 43.255812 -103.413146) (xy 43.355994 -103.437001) (xy 43.454016 -103.468581) (xy 43.549283 -103.507695)
			(xy 43.641215 -103.554106) (xy 43.729257 -103.607531) (xy 43.812872 -103.667648) (xy 43.891555 -103.73409)
			(xy 43.928538 -103.769922) (xy 43.93565 -103.777288) (xy 43.953938 -103.784654) (xy 44.045886 -103.784654)
			(xy 44.064174 -103.777288) (xy 44.071286 -103.769922) (xy 44.108269 -103.734091) (xy 44.186952 -103.66765)
			(xy 44.270568 -103.607535) (xy 44.35861 -103.554111) (xy 44.450543 -103.507702) (xy 44.545809 -103.46859)
			(xy 44.643831 -103.437011) (xy 44.744013 -103.413158) (xy 44.845748 -103.397176) (xy 44.948419 -103.389161)
			(xy 44.99991 -103.388668) (xy 45.051804 -103.389192) (xy 45.155272 -103.397336) (xy 45.257781 -103.413572)
			(xy 45.358701 -103.437801) (xy 45.457409 -103.469874) (xy 45.553297 -103.509592) (xy 45.645772 -103.55671)
			(xy 45.734266 -103.610939) (xy 45.818232 -103.671944) (xy 45.897153 -103.739348) (xy 45.970542 -103.812737)
			(xy 46.037948 -103.891657) (xy 46.098953 -103.975623) (xy 46.153183 -104.064116) (xy 46.200302 -104.156591)
			(xy 46.240021 -104.252478) (xy 46.272095 -104.351185) (xy 46.296325 -104.452105) (xy 46.312563 -104.554615)
			(xy 46.320708 -104.658082) (xy 46.321218 -104.709976) (xy 46.320691 -104.761467) (xy 46.312678 -104.864135)
			(xy 46.296697 -104.965869) (xy 46.272847 -105.06605) (xy 46.241272 -105.164072) (xy 46.202163 -105.259338)
			(xy 46.155759 -105.351271) (xy 46.102339 -105.439313) (xy 46.042229 -105.522931) (xy 45.975793 -105.601616)
			(xy 45.939964 -105.6386) (xy 45.932598 -105.645712) (xy 45.925232 -105.664) (xy 45.925232 -105.755948)
			(xy 45.932598 -105.774236) (xy 45.939964 -105.781348) (xy 45.975797 -105.818329) (xy 46.042236 -105.897013)
			(xy 46.10235 -105.98063) (xy 46.155774 -106.068672) (xy 46.202182 -106.160605) (xy 46.241294 -106.255871)
			(xy 46.272872 -106.353893) (xy 46.296725 -106.454075) (xy 46.312707 -106.55581) (xy 46.320723 -106.65848)
			(xy 46.320723 -106.761463) (xy 46.312707 -106.864133) (xy 46.296724 -106.965868) (xy 46.272871 -107.06605)
			(xy 46.241293 -107.164071) (xy 46.202181 -107.259338) (xy 46.155772 -107.351271) (xy 46.102349 -107.439312)
			(xy 46.042235 -107.522929) (xy 45.975795 -107.601613) (xy 45.939964 -107.638596) (xy 45.932598 -107.645708)
			(xy 45.925232 -107.663996) (xy 45.925232 -107.755944) (xy 45.932598 -107.774232) (xy 45.939964 -107.781344)
			(xy 45.975793 -107.818329) (xy 46.042232 -107.897013) (xy 46.102346 -107.980629) (xy 46.15577 -108.068671)
			(xy 46.202178 -108.160604) (xy 46.24129 -108.25587) (xy 46.272868 -108.353891) (xy 46.296721 -108.454073)
			(xy 46.312704 -108.555807) (xy 46.32072 -108.658477) (xy 46.32072 -108.76146) (xy 46.312705 -108.86413)
			(xy 46.296722 -108.965864) (xy 46.272869 -109.066046) (xy 46.241291 -109.164068) (xy 46.202179 -109.259334)
			(xy 46.155771 -109.351267) (xy 46.102348 -109.439308) (xy 46.042234 -109.522925) (xy 45.975794 -109.601609)
			(xy 45.939964 -109.638592) (xy 45.932598 -109.645704) (xy 45.925232 -109.663992) (xy 45.925232 -109.75594)
			(xy 45.932598 -109.774228) (xy 45.939964 -109.78134) (xy 45.975799 -109.81832) (xy 46.042238 -109.897004)
			(xy 46.102352 -109.98062) (xy 46.155775 -110.068662) (xy 46.202184 -110.160596) (xy 46.241296 -110.255862)
			(xy 46.272874 -110.353884) (xy 46.296726 -110.454066) (xy 46.312709 -110.555801) (xy 46.320724 -110.658471)
			(xy 46.320724 -110.761454) (xy 46.312708 -110.864124) (xy 46.296725 -110.965859) (xy 46.272872 -111.066042)
			(xy 46.241294 -111.164063) (xy 46.202181 -111.25933) (xy 46.155773 -111.351263) (xy 46.102349 -111.439304)
			(xy 46.042235 -111.522921) (xy 45.975795 -111.601605) (xy 45.939964 -111.638588) (xy 45.932598 -111.6457)
			(xy 45.925232 -111.663988) (xy 45.925232 -111.755936) (xy 45.932598 -111.774224) (xy 45.939964 -111.781336)
			(xy 45.975795 -111.818319) (xy 46.042234 -111.897003) (xy 46.102348 -111.98062) (xy 46.155772 -112.068661)
			(xy 46.20218 -112.160594) (xy 46.241292 -112.25586) (xy 46.27287 -112.353882) (xy 46.296723 -112.454064)
			(xy 46.312706 -112.555799) (xy 46.320721 -112.658469) (xy 46.320721 -112.761451) (xy 46.312706 -112.864121)
			(xy 46.296723 -112.965856) (xy 46.27287 -113.066038) (xy 46.241292 -113.16406) (xy 46.20218 -113.259326)
			(xy 46.155772 -113.351259) (xy 46.102348 -113.4393) (xy 46.042234 -113.522917) (xy 45.975795 -113.601601)
			(xy 45.939964 -113.638584) (xy 45.932598 -113.645696) (xy 45.925232 -113.663984) (xy 45.925232 -113.755932)
			(xy 45.932598 -113.77422) (xy 45.939964 -113.781332) (xy 45.975791 -113.818319) (xy 46.04223 -113.897003)
			(xy 46.102344 -113.980619) (xy 46.155768 -114.06866) (xy 46.202176 -114.160593) (xy 46.241288 -114.255859)
			(xy 46.272867 -114.35388) (xy 46.29672 -114.454062) (xy 46.312703 -114.555796) (xy 46.320719 -114.658466)
			(xy 46.320719 -114.761448) (xy 46.312703 -114.864118) (xy 46.296721 -114.965853) (xy 46.272868 -115.066035)
			(xy 46.24129 -115.164056) (xy 46.202179 -115.259322) (xy 46.155771 -115.351255) (xy 46.102348 -115.439297)
			(xy 46.042234 -115.522913) (xy 45.975794 -115.601597) (xy 45.939964 -115.63858) (xy 45.932598 -115.645692)
			(xy 45.925232 -115.66398) (xy 45.925232 -115.755928) (xy 45.932598 -115.774216) (xy 45.939964 -115.781328)
			(xy 45.975797 -115.818309) (xy 46.042236 -115.896993) (xy 46.10235 -115.98061) (xy 46.155774 -116.068652)
			(xy 46.202182 -116.160585) (xy 46.241294 -116.255851) (xy 46.272872 -116.353873) (xy 46.296725 -116.454055)
			(xy 46.312707 -116.55579) (xy 46.320723 -116.65846) (xy 46.320723 -116.761443) (xy 46.312707 -116.864113)
			(xy 46.296724 -116.965848) (xy 46.272871 -117.06603) (xy 46.241293 -117.164051) (xy 46.202181 -117.259318)
			(xy 46.155772 -117.351251) (xy 46.102349 -117.439292) (xy 46.042235 -117.522909) (xy 45.975795 -117.601593)
			(xy 45.939964 -117.638576) (xy 45.932598 -117.645688) (xy 45.925232 -117.663976) (xy 45.925232 -117.755924)
			(xy 45.932598 -117.774212) (xy 45.939964 -117.781324) (xy 45.975811 -117.818292) (xy 46.042252 -117.896977)
			(xy 46.102366 -117.980595) (xy 46.155789 -118.068638) (xy 46.202196 -118.160573) (xy 46.241307 -118.255841)
			(xy 46.272884 -118.353864) (xy 46.296734 -118.454048) (xy 46.312714 -118.555784) (xy 46.320727 -118.658456)
			(xy 46.321218 -118.709948) (xy 46.320706 -118.760767) (xy 46.3129 -118.862103) (xy 46.297331 -118.962541)
			(xy 46.274091 -119.061485) (xy 46.243317 -119.158352) (xy 46.205191 -119.252567) (xy 46.159938 -119.343574)
			(xy 46.107827 -119.430835) (xy 46.049165 -119.513834) (xy 45.984298 -119.59208) (xy 45.913612 -119.665111)
			(xy 45.837522 -119.732494) (xy 45.75648 -119.793832) (xy 45.670965 -119.848761) (xy 45.581482 -119.896957)
			(xy 45.48856 -119.938135) (xy 45.392749 -119.972052) (xy 45.294615 -119.998506) (xy 45.244766 -120.008396)
			(xy 45.233336 -120.010428) (xy 45.215048 -120.023636) (xy 45.16628 -120.112536) (xy 45.164756 -120.135142)
			(xy 45.169074 -120.14581) (xy 45.187081 -120.192491) (xy 45.21649 -120.288134) (xy 45.238206 -120.385811)
			(xy 45.252093 -120.484905) (xy 45.258064 -120.584789) (xy 45.256079 -120.684832) (xy 45.246151 -120.7844)
			(xy 45.228345 -120.882865) (xy 45.202771 -120.979604) (xy 45.169592 -121.074006) (xy 45.129017 -121.165472)
			(xy 45.081303 -121.253426) (xy 45.026752 -121.337311) (xy 44.965709 -121.416596) (xy 44.898559 -121.490781)
			(xy 44.825728 -121.559396) (xy 44.747674 -121.622007) (xy 44.664894 -121.678219) (xy 44.577908 -121.727676)
			(xy 44.487268 -121.770065) (xy 44.393547 -121.805119) (xy 44.297337 -121.832616) (xy 44.199246 -121.852382)
			(xy 44.099895 -121.864291) (xy 43.999912 -121.868269) (xy 43.899929 -121.864291) (xy 43.800578 -121.852382)
			(xy 43.702487 -121.832616) (xy 43.606277 -121.805119) (xy 43.512556 -121.770065) (xy 43.421916 -121.727676)
			(xy 43.33493 -121.678219) (xy 43.25215 -121.622007) (xy 43.174096 -121.559396) (xy 43.101265 -121.490781)
			(xy 43.034115 -121.416596) (xy 42.973072 -121.337311) (xy 42.918521 -121.253426) (xy 42.870807 -121.165472)
			(xy 42.830232 -121.074006) (xy 42.797053 -120.979604) (xy 42.771479 -120.882865) (xy 42.753673 -120.7844)
			(xy 42.743745 -120.684832) (xy 42.74176 -120.584789) (xy 42.747731 -120.484905) (xy 42.761618 -120.385811)
			(xy 42.783334 -120.288134) (xy 42.812743 -120.192491) (xy 42.83075 -120.14581) (xy 42.835068 -120.135142)
			(xy 42.833544 -120.112536) (xy 42.784776 -120.023636) (xy 42.766488 -120.010428) (xy 42.755058 -120.008396)
			(xy 42.70521 -119.998502) (xy 42.607077 -119.972044) (xy 42.511267 -119.938125) (xy 42.418346 -119.896945)
			(xy 42.328864 -119.848747) (xy 42.24335 -119.793817) (xy 42.162308 -119.732479) (xy 42.086219 -119.665096)
			(xy 42.015532 -119.592066) (xy 41.950664 -119.513822) (xy 41.892 -119.430824) (xy 41.839886 -119.343565)
			(xy 41.79463 -119.25256) (xy 41.7565 -119.158346) (xy 41.725721 -119.061482) (xy 41.702476 -118.962539)
			(xy 41.686901 -118.862103) (xy 41.679088 -118.760766) (xy 41.678606 -118.709948) (xy 35.205071 -118.709948)
			(xy 35.217772 -118.740983) (xy 35.242582 -118.823714) (xy 35.259257 -118.90846) (xy 35.267638 -118.994423)
			(xy 35.268154 -119.037608) (xy 35.267641 -119.078709) (xy 35.260056 -119.160561) (xy 35.244951 -119.241364)
			(xy 35.222455 -119.320429) (xy 35.192761 -119.39708) (xy 35.156121 -119.470665) (xy 35.112847 -119.540556)
			(xy 35.06331 -119.606156) (xy 35.007932 -119.666905) (xy 34.947185 -119.722286) (xy 34.881587 -119.771826)
			(xy 34.811699 -119.815102) (xy 34.738115 -119.851745) (xy 34.661465 -119.881443) (xy 34.582401 -119.903942)
			(xy 34.501599 -119.919051) (xy 34.419747 -119.926639) (xy 34.378646 -119.927116) (xy 34.33578 -119.92656)
			(xy 34.250446 -119.918315) (xy 34.1663 -119.901899) (xy 34.084125 -119.877462) (xy 34.004682 -119.845232)
			(xy 33.928709 -119.805507) (xy 33.856911 -119.758657) (xy 33.789953 -119.705116) (xy 33.728458 -119.645381)
			(xy 33.672995 -119.580007) (xy 33.62408 -119.509599) (xy 33.602676 -119.472456) (xy 33.59658 -119.461534)
			(xy 33.576006 -119.448072) (xy 33.468564 -119.43715) (xy 33.44545 -119.44604) (xy 33.437322 -119.455438)
			(xy 33.409231 -119.487033) (xy 33.347972 -119.545308) (xy 33.281459 -119.597505) (xy 33.210292 -119.643154)
			(xy 33.135114 -119.681842) (xy 33.056603 -119.713221) (xy 32.975468 -119.737006) (xy 32.892442 -119.752982)
			(xy 32.808275 -119.761007) (xy 32.766 -119.761508) (xy 32.739776 -119.761336) (xy 32.687418 -119.758285)
			(xy 32.661352 -119.755412) (xy 32.652103 -119.754777) (xy 32.63414 -119.759291) (xy 32.618925 -119.769853)
			(xy 32.613346 -119.777256) (xy 32.588589 -119.812889) (xy 32.533166 -119.879657) (xy 32.471504 -119.940709)
			(xy 32.404189 -119.995465) (xy 32.331861 -120.043404) (xy 32.255207 -120.08407) (xy 32.174957 -120.117078)
			(xy 32.091874 -120.142112) (xy 32.006747 -120.158935) (xy 31.920386 -120.167386) (xy 31.877 -120.167908)
			(xy 31.834652 -120.167404) (xy 31.750338 -120.159353) (xy 31.667172 -120.143324) (xy 31.585905 -120.119463)
			(xy 31.507275 -120.087984) (xy 31.431994 -120.049173) (xy 31.360742 -120.003383) (xy 31.294166 -119.951027)
			(xy 31.232868 -119.892579) (xy 31.177403 -119.828569) (xy 31.128274 -119.759577) (xy 31.085925 -119.686227)
			(xy 31.050741 -119.609184) (xy 31.023039 -119.529145) (xy 31.003071 -119.446836) (xy 30.991018 -119.363001)
			(xy 30.986988 -119.2784) (xy 21.954188 -119.2784) (xy 21.967745 -119.281689) (xy 22.047784 -119.309391)
			(xy 22.124827 -119.344575) (xy 22.198177 -119.386924) (xy 22.267169 -119.436053) (xy 22.331179 -119.491518)
			(xy 22.389627 -119.552816) (xy 22.441983 -119.619392) (xy 22.487773 -119.690644) (xy 22.526584 -119.765925)
			(xy 22.558063 -119.844555) (xy 22.581924 -119.925822) (xy 22.597953 -120.008988) (xy 22.606004 -120.093302)
			(xy 22.606508 -120.13565) (xy 22.606004 -120.177998) (xy 22.597953 -120.262312) (xy 22.581924 -120.345478)
			(xy 22.558063 -120.426745) (xy 22.526584 -120.505375) (xy 22.487773 -120.580656) (xy 22.441983 -120.651908)
			(xy 22.389627 -120.718484) (xy 22.331179 -120.779782) (xy 22.267169 -120.835247) (xy 22.198177 -120.884376)
			(xy 22.124827 -120.926725) (xy 22.047784 -120.961909) (xy 21.967745 -120.989611) (xy 21.885436 -121.009579)
			(xy 21.801601 -121.021632) (xy 21.717 -121.025663) (xy 21.632399 -121.021632) (xy 21.548564 -121.009579)
			(xy 21.466255 -120.989611) (xy 21.386216 -120.961909) (xy 21.309173 -120.926725) (xy 21.235823 -120.884376)
			(xy 21.166831 -120.835247) (xy 21.102821 -120.779782) (xy 21.044373 -120.718484) (xy 20.992017 -120.651908)
			(xy 20.946227 -120.580656) (xy 20.907416 -120.505375) (xy 20.875937 -120.426745) (xy 20.852076 -120.345478)
			(xy 20.836047 -120.262312) (xy 20.827996 -120.177998) (xy 19.676424 -120.177998) (xy 19.693773 -120.204994)
			(xy 19.732584 -120.280275) (xy 19.764063 -120.358905) (xy 19.787924 -120.440172) (xy 19.803953 -120.523338)
			(xy 19.812004 -120.607652) (xy 19.812508 -120.65) (xy 19.812004 -120.692348) (xy 19.803953 -120.776662)
			(xy 19.787924 -120.859828) (xy 19.764063 -120.941095) (xy 19.732584 -121.019725) (xy 19.693773 -121.095006)
			(xy 19.647983 -121.166258) (xy 19.595627 -121.232834) (xy 19.537179 -121.294132) (xy 19.473169 -121.349597)
			(xy 19.404177 -121.398726) (xy 19.330827 -121.441075) (xy 19.253784 -121.476259) (xy 19.173745 -121.503961)
			(xy 19.091436 -121.523929) (xy 19.007601 -121.535982) (xy 18.923 -121.540013) (xy 18.838399 -121.535982)
			(xy 18.754564 -121.523929) (xy 18.672255 -121.503961) (xy 18.592216 -121.476259) (xy 18.515173 -121.441075)
			(xy 18.441823 -121.398726) (xy 18.372831 -121.349597) (xy 18.308821 -121.294132) (xy 18.250373 -121.232834)
			(xy 18.198017 -121.166258) (xy 18.152227 -121.095006) (xy 18.113416 -121.019725) (xy 18.081937 -120.941095)
			(xy 18.058076 -120.859828) (xy 18.042047 -120.776662) (xy 18.033996 -120.692348) (xy 13.475666 -120.692348)
			(xy 13.462069 -120.738657) (xy 13.43059 -120.817287) (xy 13.391779 -120.892568) (xy 13.345989 -120.96382)
			(xy 13.293633 -121.030396) (xy 13.235185 -121.091694) (xy 13.171175 -121.147159) (xy 13.102183 -121.196288)
			(xy 13.028833 -121.238637) (xy 12.95179 -121.273821) (xy 12.871751 -121.301523) (xy 12.789442 -121.321491)
			(xy 12.705607 -121.333544) (xy 12.621006 -121.337575) (xy 12.536405 -121.333544) (xy 12.45257 -121.321491)
			(xy 12.370261 -121.301523) (xy 12.290222 -121.273821) (xy 12.213179 -121.238637) (xy 12.139829 -121.196288)
			(xy 12.070837 -121.147159) (xy 12.006827 -121.091694) (xy 11.948379 -121.030396) (xy 11.896023 -120.96382)
			(xy 11.850233 -120.892568) (xy 11.811422 -120.817287) (xy 11.779943 -120.738657) (xy 11.756082 -120.65739)
			(xy 11.740053 -120.574224) (xy 11.732002 -120.48991) (xy 1.651254 -120.48991) (xy 1.651254 -124.580904)
			(xy 1.652778 -124.63145) (xy 1.651254 -124.681996) (xy 1.651254 -124.841) (xy 3.682492 -124.841)
			(xy 3.682967 -124.799898) (xy 3.690552 -124.718043) (xy 3.705657 -124.637238) (xy 3.728153 -124.558171)
			(xy 3.757849 -124.481517) (xy 3.794491 -124.40793) (xy 3.837766 -124.338038) (xy 3.887306 -124.272437)
			(xy 3.942687 -124.211687) (xy 4.003437 -124.156306) (xy 4.069038 -124.106766) (xy 4.13893 -124.063491)
			(xy 4.212517 -124.026849) (xy 4.289171 -123.997153) (xy 4.368238 -123.974657) (xy 4.449043 -123.959552)
			(xy 4.530898 -123.951967) (xy 4.572 -123.951492) (xy 4.613095 -123.951966) (xy 4.694935 -123.959548)
			(xy 4.775726 -123.974648) (xy 4.854779 -123.997136) (xy 4.931421 -124.026822) (xy 5.004998 -124.063451)
			(xy 5.074882 -124.106711) (xy 5.140477 -124.156234) (xy 5.201223 -124.211597) (xy 5.256603 -124.272328)
			(xy 5.306145 -124.337909) (xy 5.349425 -124.40778) (xy 5.386076 -124.481346) (xy 5.415783 -124.55798)
			(xy 5.438294 -124.637027) (xy 5.453416 -124.717814) (xy 5.461022 -124.799651) (xy 5.461508 -124.840746)
			(xy 5.462091 -124.851271) (xy 5.470546 -124.870549) (xy 5.48602 -124.884822) (xy 5.495798 -124.888752)
			(xy 5.535777 -124.902986) (xy 5.613063 -124.938051) (xy 5.686658 -124.98032) (xy 5.75589 -125.029407)
			(xy 5.820132 -125.084867) (xy 5.878798 -125.146194) (xy 5.931354 -125.212832) (xy 5.977324 -125.284173)
			(xy 6.016288 -125.359569) (xy 6.047891 -125.438335) (xy 6.071848 -125.519752) (xy 6.087939 -125.603082)
			(xy 6.096018 -125.687565) (xy 6.096508 -125.73) (xy 6.096062 -125.768288) (xy 6.089444 -125.844578)
			(xy 6.0763 -125.920018) (xy 6.056726 -125.99405) (xy 6.044184 -126.030228) (xy 6.041543 -126.038666)
			(xy 6.041543 -126.056334) (xy 6.044184 -126.064772) (xy 6.05674 -126.100947) (xy 6.076337 -126.174976)
			(xy 6.089488 -126.250417) (xy 6.096097 -126.326711) (xy 6.096508 -126.365) (xy 6.096004 -126.407348)
			(xy 6.087953 -126.491662) (xy 6.071924 -126.574828) (xy 6.048063 -126.656095) (xy 6.016584 -126.734725)
			(xy 5.977773 -126.810006) (xy 5.931983 -126.881258) (xy 5.879627 -126.947834) (xy 5.821179 -127.009132)
			(xy 5.757169 -127.064597) (xy 5.688177 -127.113726) (xy 5.614827 -127.156075) (xy 5.537784 -127.191259)
			(xy 5.457745 -127.218961) (xy 5.375436 -127.238929) (xy 5.291601 -127.250982) (xy 5.207 -127.255013)
			(xy 5.122399 -127.250982) (xy 5.038564 -127.238929) (xy 4.956255 -127.218961) (xy 4.876216 -127.191259)
			(xy 4.799173 -127.156075) (xy 4.725823 -127.113726) (xy 4.656831 -127.064597) (xy 4.592821 -127.009132)
			(xy 4.534373 -126.947834) (xy 4.482017 -126.881258) (xy 4.436227 -126.810006) (xy 4.397416 -126.734725)
			(xy 4.365937 -126.656095) (xy 4.342076 -126.574828) (xy 4.326047 -126.491662) (xy 4.317996 -126.407348)
			(xy 4.317492 -126.365) (xy 4.317938 -126.326712) (xy 4.324556 -126.250422) (xy 4.3377 -126.174982)
			(xy 4.357274 -126.10095) (xy 4.369816 -126.064772) (xy 4.372457 -126.056334) (xy 4.372457 -126.038666)
			(xy 4.369816 -126.030228) (xy 4.357256 -125.994088) (xy 4.337674 -125.92012) (xy 4.324526 -125.844742)
			(xy 4.31791 -125.768512) (xy 4.317492 -125.730254) (xy 4.316909 -125.719729) (xy 4.308454 -125.700451)
			(xy 4.29298 -125.686178) (xy 4.283202 -125.682248) (xy 4.243223 -125.668014) (xy 4.165937 -125.632949)
			(xy 4.092342 -125.59068) (xy 4.02311 -125.541593) (xy 3.958868 -125.486133) (xy 3.900202 -125.424806)
			(xy 3.847646 -125.358168) (xy 3.801676 -125.286827) (xy 3.762712 -125.211431) (xy 3.731109 -125.132665)
			(xy 3.707152 -125.051248) (xy 3.691061 -124.967918) (xy 3.682982 -124.883435) (xy 3.682492 -124.841)
			(xy 1.651254 -124.841) (xy 1.651254 -129.660904) (xy 1.652778 -129.71145) (xy 1.651254 -129.761996)
			(xy 1.651254 -132.948172) (xy 1.90119 -132.948172) (xy 1.901711 -132.905152) (xy 1.910049 -132.819517)
			(xy 1.926614 -132.735087) (xy 1.951252 -132.65265) (xy 1.983733 -132.572977) (xy 2.003298 -132.53466)
			(xy 2.008535 -132.523491) (xy 2.00852 -132.498848) (xy 2.003298 -132.48767) (xy 1.98433 -132.449797)
			(xy 1.952858 -132.37115) (xy 1.929008 -132.289867) (xy 1.912996 -132.206684) (xy 1.904967 -132.122355)
			(xy 1.904492 -132.08) (xy 1.90497 -132.038494) (xy 1.912709 -131.955845) (xy 1.928117 -131.874276)
			(xy 1.951059 -131.794498) (xy 1.981336 -131.717205) (xy 2.018684 -131.64307) (xy 2.062778 -131.572738)
			(xy 2.087626 -131.539488) (xy 2.093965 -131.530288) (xy 2.098791 -131.5085) (xy 2.093965 -131.486712)
			(xy 2.087626 -131.477512) (xy 2.062779 -131.444262) (xy 2.018685 -131.373931) (xy 1.981338 -131.299795)
			(xy 1.951062 -131.222502) (xy 1.928122 -131.142724) (xy 1.912717 -131.061155) (xy 1.90498 -130.978505)
			(xy 1.90498 -130.895495) (xy 1.912717 -130.812845) (xy 1.928122 -130.731276) (xy 1.951062 -130.651498)
			(xy 1.981338 -130.574205) (xy 2.018685 -130.500069) (xy 2.062779 -130.429738) (xy 2.087626 -130.396488)
			(xy 2.093965 -130.387288) (xy 2.098791 -130.3655) (xy 2.093965 -130.343712) (xy 2.087626 -130.334512)
			(xy 2.062779 -130.301262) (xy 2.018685 -130.230931) (xy 1.981338 -130.156795) (xy 1.951062 -130.079502)
			(xy 1.928122 -129.999724) (xy 1.912717 -129.918155) (xy 1.90498 -129.835505) (xy 1.90498 -129.752495)
			(xy 1.912717 -129.669845) (xy 1.928122 -129.588276) (xy 1.951062 -129.508498) (xy 1.981338 -129.431205)
			(xy 2.018685 -129.357069) (xy 2.062779 -129.286738) (xy 2.087626 -129.253488) (xy 2.093965 -129.244288)
			(xy 2.098791 -129.2225) (xy 2.093965 -129.200712) (xy 2.087626 -129.191512) (xy 2.062779 -129.158262)
			(xy 2.018685 -129.087931) (xy 1.981338 -129.013795) (xy 1.951062 -128.936502) (xy 1.928122 -128.856724)
			(xy 1.912717 -128.775155) (xy 1.90498 -128.692505) (xy 1.90498 -128.609495) (xy 1.912717 -128.526845)
			(xy 1.928122 -128.445276) (xy 1.951062 -128.365498) (xy 1.981338 -128.288205) (xy 2.018685 -128.214069)
			(xy 2.062779 -128.143738) (xy 2.087626 -128.110488) (xy 2.093965 -128.101288) (xy 2.098791 -128.0795)
			(xy 2.093965 -128.057712) (xy 2.087626 -128.048512) (xy 2.062778 -128.015262) (xy 2.018682 -127.944931)
			(xy 1.981332 -127.870797) (xy 1.951055 -127.793504) (xy 1.928113 -127.713726) (xy 1.912707 -127.632156)
			(xy 1.904971 -127.549506) (xy 1.904492 -127.508) (xy 1.904996 -127.465652) (xy 1.913047 -127.381338)
			(xy 1.929076 -127.298172) (xy 1.952937 -127.216905) (xy 1.984416 -127.138275) (xy 2.023227 -127.062994)
			(xy 2.069017 -126.991742) (xy 2.121373 -126.925166) (xy 2.179821 -126.863868) (xy 2.243831 -126.808403)
			(xy 2.312823 -126.759274) (xy 2.386173 -126.716925) (xy 2.463216 -126.681741) (xy 2.543255 -126.654039)
			(xy 2.625564 -126.634071) (xy 2.709399 -126.622018) (xy 2.794 -126.617988) (xy 2.878601 -126.622018)
			(xy 2.962436 -126.634071) (xy 3.044745 -126.654039) (xy 3.124784 -126.681741) (xy 3.201827 -126.716925)
			(xy 3.275177 -126.759274) (xy 3.344169 -126.808403) (xy 3.408179 -126.863868) (xy 3.466627 -126.925166)
			(xy 3.518983 -126.991742) (xy 3.564773 -127.062994) (xy 3.603584 -127.138275) (xy 3.635063 -127.216905)
			(xy 3.658924 -127.298172) (xy 3.674953 -127.381338) (xy 3.683004 -127.465652) (xy 3.683508 -127.508)
			(xy 3.68301 -127.549505) (xy 3.675274 -127.632154) (xy 3.65987 -127.713723) (xy 3.636931 -127.793501)
			(xy 3.606657 -127.870794) (xy 3.569312 -127.944929) (xy 3.525221 -128.015262) (xy 3.500374 -128.048512)
			(xy 3.494035 -128.057712) (xy 3.489209 -128.0795) (xy 3.494035 -128.101288) (xy 3.500374 -128.110488)
			(xy 3.525221 -128.143738) (xy 3.569315 -128.214069) (xy 3.606662 -128.288205) (xy 3.636938 -128.365498)
			(xy 3.659878 -128.445276) (xy 3.675283 -128.526845) (xy 3.68302 -128.609495) (xy 3.68302 -128.692505)
			(xy 3.675283 -128.775155) (xy 3.659878 -128.856724) (xy 3.636938 -128.936502) (xy 3.606662 -129.013795)
			(xy 3.569315 -129.087931) (xy 3.525221 -129.158262) (xy 3.500374 -129.191512) (xy 3.494035 -129.200712)
			(xy 3.489209 -129.2225) (xy 3.494035 -129.244288) (xy 3.500374 -129.253488) (xy 3.525221 -129.286738)
			(xy 3.569315 -129.357069) (xy 3.606662 -129.431205) (xy 3.636938 -129.508498) (xy 3.659878 -129.588276)
			(xy 3.675283 -129.669845) (xy 3.68302 -129.752495) (xy 3.68302 -129.835505) (xy 3.675283 -129.918155)
			(xy 3.659878 -129.999724) (xy 3.636938 -130.079502) (xy 3.606662 -130.156795) (xy 3.569315 -130.230931)
			(xy 3.525221 -130.301262) (xy 3.500374 -130.334512) (xy 3.494035 -130.343712) (xy 3.489209 -130.3655)
			(xy 3.494035 -130.387288) (xy 3.500374 -130.396488) (xy 3.525221 -130.429738) (xy 3.558793 -130.483286)
			(xy 4.305804 -130.483286) (xy 4.305804 -130.39859) (xy 4.313855 -130.314276) (xy 4.329884 -130.23111)
			(xy 4.353745 -130.149843) (xy 4.385224 -130.071213) (xy 4.424035 -129.995932) (xy 4.469825 -129.92468)
			(xy 4.522181 -129.858104) (xy 4.580629 -129.796806) (xy 4.644639 -129.741341) (xy 4.713631 -129.692212)
			(xy 4.786981 -129.649863) (xy 4.864024 -129.614679) (xy 4.944063 -129.586977) (xy 5.026372 -129.567009)
			(xy 5.110207 -129.554956) (xy 5.194808 -129.550926) (xy 5.279409 -129.554956) (xy 5.363244 -129.567009)
			(xy 5.445553 -129.586977) (xy 5.525592 -129.614679) (xy 5.602635 -129.649863) (xy 5.675985 -129.692212)
			(xy 5.744977 -129.741341) (xy 5.808987 -129.796806) (xy 5.867435 -129.858104) (xy 5.919791 -129.92468)
			(xy 5.965581 -129.995932) (xy 6.004392 -130.071213) (xy 6.035871 -130.149843) (xy 6.055691 -130.217348)
			(xy 6.603996 -130.217348) (xy 6.603996 -130.132652) (xy 6.612047 -130.048338) (xy 6.628076 -129.965172)
			(xy 6.651937 -129.883905) (xy 6.683416 -129.805275) (xy 6.722227 -129.729994) (xy 6.768017 -129.658742)
			(xy 6.820373 -129.592166) (xy 6.878821 -129.530868) (xy 6.942831 -129.475403) (xy 7.011823 -129.426274)
			(xy 7.085173 -129.383925) (xy 7.162216 -129.348741) (xy 7.242255 -129.321039) (xy 7.324564 -129.301071)
			(xy 7.408399 -129.289018) (xy 7.493 -129.284988) (xy 7.577601 -129.289018) (xy 7.661436 -129.301071)
			(xy 7.743745 -129.321039) (xy 7.823784 -129.348741) (xy 7.900827 -129.383925) (xy 7.974177 -129.426274)
			(xy 8.043169 -129.475403) (xy 8.107179 -129.530868) (xy 8.165627 -129.592166) (xy 8.217983 -129.658742)
			(xy 8.263773 -129.729994) (xy 8.302584 -129.805275) (xy 8.334063 -129.883905) (xy 8.357924 -129.965172)
			(xy 8.373953 -130.048338) (xy 8.382004 -130.132652) (xy 8.382508 -130.175) (xy 8.382004 -130.217348)
			(xy 8.635996 -130.217348) (xy 8.635996 -130.132652) (xy 8.644047 -130.048338) (xy 8.660076 -129.965172)
			(xy 8.683937 -129.883905) (xy 8.715416 -129.805275) (xy 8.754227 -129.729994) (xy 8.800017 -129.658742)
			(xy 8.852373 -129.592166) (xy 8.910821 -129.530868) (xy 8.974831 -129.475403) (xy 9.043823 -129.426274)
			(xy 9.117173 -129.383925) (xy 9.194216 -129.348741) (xy 9.274255 -129.321039) (xy 9.356564 -129.301071)
			(xy 9.440399 -129.289018) (xy 9.525 -129.284988) (xy 9.609601 -129.289018) (xy 9.693436 -129.301071)
			(xy 9.775745 -129.321039) (xy 9.855784 -129.348741) (xy 9.932827 -129.383925) (xy 10.006177 -129.426274)
			(xy 10.075169 -129.475403) (xy 10.139179 -129.530868) (xy 10.197627 -129.592166) (xy 10.249983 -129.658742)
			(xy 10.295773 -129.729994) (xy 10.334584 -129.805275) (xy 10.366063 -129.883905) (xy 10.389924 -129.965172)
			(xy 10.405953 -130.048338) (xy 10.414004 -130.132652) (xy 10.414508 -130.175) (xy 10.414004 -130.217348)
			(xy 10.405953 -130.301662) (xy 10.389924 -130.384828) (xy 10.366063 -130.466095) (xy 10.334584 -130.544725)
			(xy 10.295773 -130.620006) (xy 10.249983 -130.691258) (xy 10.197627 -130.757834) (xy 10.139179 -130.819132)
			(xy 10.075169 -130.874597) (xy 10.006177 -130.923726) (xy 9.932827 -130.966075) (xy 9.855784 -131.001259)
			(xy 9.775745 -131.028961) (xy 9.693436 -131.048929) (xy 9.609601 -131.060982) (xy 9.525 -131.065013)
			(xy 9.440399 -131.060982) (xy 9.356564 -131.048929) (xy 9.274255 -131.028961) (xy 9.194216 -131.001259)
			(xy 9.117173 -130.966075) (xy 9.043823 -130.923726) (xy 8.974831 -130.874597) (xy 8.910821 -130.819132)
			(xy 8.852373 -130.757834) (xy 8.800017 -130.691258) (xy 8.754227 -130.620006) (xy 8.715416 -130.544725)
			(xy 8.683937 -130.466095) (xy 8.660076 -130.384828) (xy 8.644047 -130.301662) (xy 8.635996 -130.217348)
			(xy 8.382004 -130.217348) (xy 8.373953 -130.301662) (xy 8.357924 -130.384828) (xy 8.334063 -130.466095)
			(xy 8.302584 -130.544725) (xy 8.263773 -130.620006) (xy 8.217983 -130.691258) (xy 8.165627 -130.757834)
			(xy 8.107179 -130.819132) (xy 8.043169 -130.874597) (xy 7.974177 -130.923726) (xy 7.900827 -130.966075)
			(xy 7.823784 -131.001259) (xy 7.743745 -131.028961) (xy 7.661436 -131.048929) (xy 7.577601 -131.060982)
			(xy 7.493 -131.065013) (xy 7.408399 -131.060982) (xy 7.324564 -131.048929) (xy 7.242255 -131.028961)
			(xy 7.162216 -131.001259) (xy 7.085173 -130.966075) (xy 7.011823 -130.923726) (xy 6.942831 -130.874597)
			(xy 6.878821 -130.819132) (xy 6.820373 -130.757834) (xy 6.768017 -130.691258) (xy 6.722227 -130.620006)
			(xy 6.683416 -130.544725) (xy 6.651937 -130.466095) (xy 6.628076 -130.384828) (xy 6.612047 -130.301662)
			(xy 6.603996 -130.217348) (xy 6.055691 -130.217348) (xy 6.059732 -130.23111) (xy 6.075761 -130.314276)
			(xy 6.083812 -130.39859) (xy 6.084316 -130.440938) (xy 6.083812 -130.483286) (xy 6.075761 -130.5676)
			(xy 6.059732 -130.650766) (xy 6.035871 -130.732033) (xy 6.004392 -130.810663) (xy 5.965581 -130.885944)
			(xy 5.919791 -130.957196) (xy 5.867435 -131.023772) (xy 5.808987 -131.08507) (xy 5.744977 -131.140535)
			(xy 5.675985 -131.189664) (xy 5.602635 -131.232013) (xy 5.525592 -131.267197) (xy 5.445553 -131.294899)
			(xy 5.437519 -131.296848) (xy 11.620496 -131.296848) (xy 11.620496 -131.212152) (xy 11.628547 -131.127838)
			(xy 11.644576 -131.044672) (xy 11.668437 -130.963405) (xy 11.699916 -130.884775) (xy 11.738727 -130.809494)
			(xy 11.784517 -130.738242) (xy 11.836873 -130.671666) (xy 11.895321 -130.610368) (xy 11.959331 -130.554903)
			(xy 12.028323 -130.505774) (xy 12.101673 -130.463425) (xy 12.178716 -130.428241) (xy 12.258755 -130.400539)
			(xy 12.341064 -130.380571) (xy 12.424899 -130.368518) (xy 12.5095 -130.364488) (xy 12.594101 -130.368518)
			(xy 12.677936 -130.380571) (xy 12.760245 -130.400539) (xy 12.840284 -130.428241) (xy 12.917327 -130.463425)
			(xy 12.990677 -130.505774) (xy 13.059669 -130.554903) (xy 13.123679 -130.610368) (xy 13.182127 -130.671666)
			(xy 13.234483 -130.738242) (xy 13.280273 -130.809494) (xy 13.319084 -130.884775) (xy 13.350563 -130.963405)
			(xy 13.374424 -131.044672) (xy 13.390453 -131.127838) (xy 13.398504 -131.212152) (xy 13.399008 -131.2545)
			(xy 13.398504 -131.296848) (xy 13.390453 -131.381162) (xy 13.374424 -131.464328) (xy 13.350563 -131.545595)
			(xy 13.319084 -131.624225) (xy 13.280273 -131.699506) (xy 13.234483 -131.770758) (xy 13.182127 -131.837334)
			(xy 13.123679 -131.898632) (xy 13.059669 -131.954097) (xy 12.990677 -132.003226) (xy 12.917327 -132.045575)
			(xy 12.840284 -132.080759) (xy 12.760245 -132.108461) (xy 12.677936 -132.128429) (xy 12.594101 -132.140482)
			(xy 12.5095 -132.144513) (xy 12.424899 -132.140482) (xy 12.341064 -132.128429) (xy 12.258755 -132.108461)
			(xy 12.178716 -132.080759) (xy 12.101673 -132.045575) (xy 12.028323 -132.003226) (xy 11.959331 -131.954097)
			(xy 11.895321 -131.898632) (xy 11.836873 -131.837334) (xy 11.784517 -131.770758) (xy 11.738727 -131.699506)
			(xy 11.699916 -131.624225) (xy 11.668437 -131.545595) (xy 11.644576 -131.464328) (xy 11.628547 -131.381162)
			(xy 11.620496 -131.296848) (xy 5.437519 -131.296848) (xy 5.363244 -131.314867) (xy 5.279409 -131.32692)
			(xy 5.194808 -131.330951) (xy 5.110207 -131.32692) (xy 5.026372 -131.314867) (xy 4.944063 -131.294899)
			(xy 4.864024 -131.267197) (xy 4.786981 -131.232013) (xy 4.713631 -131.189664) (xy 4.644639 -131.140535)
			(xy 4.580629 -131.08507) (xy 4.522181 -131.023772) (xy 4.469825 -130.957196) (xy 4.424035 -130.885944)
			(xy 4.385224 -130.810663) (xy 4.353745 -130.732033) (xy 4.329884 -130.650766) (xy 4.313855 -130.5676)
			(xy 4.305804 -130.483286) (xy 3.558793 -130.483286) (xy 3.569315 -130.500069) (xy 3.606662 -130.574205)
			(xy 3.636938 -130.651498) (xy 3.659878 -130.731276) (xy 3.675283 -130.812845) (xy 3.68302 -130.895495)
			(xy 3.68302 -130.978505) (xy 3.675283 -131.061155) (xy 3.659878 -131.142724) (xy 3.636938 -131.222502)
			(xy 3.606662 -131.299795) (xy 3.569315 -131.373931) (xy 3.525221 -131.444262) (xy 3.500374 -131.477512)
			(xy 3.494035 -131.486712) (xy 3.489209 -131.5085) (xy 3.494035 -131.530288) (xy 3.500374 -131.539488)
			(xy 3.525222 -131.572738) (xy 3.569318 -131.643069) (xy 3.606668 -131.717203) (xy 3.636945 -131.794496)
			(xy 3.659887 -131.874274) (xy 3.675293 -131.955844) (xy 3.683029 -132.038494) (xy 3.683508 -132.08)
			(xy 3.682975 -132.123019) (xy 3.67464 -132.208654) (xy 3.666657 -132.249348) (xy 6.603996 -132.249348)
			(xy 6.603996 -132.164652) (xy 6.612047 -132.080338) (xy 6.628076 -131.997172) (xy 6.651937 -131.915905)
			(xy 6.683416 -131.837275) (xy 6.722227 -131.761994) (xy 6.768017 -131.690742) (xy 6.820373 -131.624166)
			(xy 6.878821 -131.562868) (xy 6.942831 -131.507403) (xy 7.011823 -131.458274) (xy 7.085173 -131.415925)
			(xy 7.162216 -131.380741) (xy 7.242255 -131.353039) (xy 7.324564 -131.333071) (xy 7.408399 -131.321018)
			(xy 7.493 -131.316988) (xy 7.577601 -131.321018) (xy 7.661436 -131.333071) (xy 7.743745 -131.353039)
			(xy 7.823784 -131.380741) (xy 7.900827 -131.415925) (xy 7.974177 -131.458274) (xy 8.043169 -131.507403)
			(xy 8.107179 -131.562868) (xy 8.165627 -131.624166) (xy 8.217983 -131.690742) (xy 8.263773 -131.761994)
			(xy 8.302584 -131.837275) (xy 8.334063 -131.915905) (xy 8.357924 -131.997172) (xy 8.373953 -132.080338)
			(xy 8.382004 -132.164652) (xy 8.382508 -132.207) (xy 8.382004 -132.249348) (xy 8.635996 -132.249348)
			(xy 8.635996 -132.164652) (xy 8.644047 -132.080338) (xy 8.660076 -131.997172) (xy 8.683937 -131.915905)
			(xy 8.715416 -131.837275) (xy 8.754227 -131.761994) (xy 8.800017 -131.690742) (xy 8.852373 -131.624166)
			(xy 8.910821 -131.562868) (xy 8.974831 -131.507403) (xy 9.043823 -131.458274) (xy 9.117173 -131.415925)
			(xy 9.194216 -131.380741) (xy 9.274255 -131.353039) (xy 9.356564 -131.333071) (xy 9.440399 -131.321018)
			(xy 9.525 -131.316988) (xy 9.609601 -131.321018) (xy 9.693436 -131.333071) (xy 9.775745 -131.353039)
			(xy 9.855784 -131.380741) (xy 9.932827 -131.415925) (xy 10.006177 -131.458274) (xy 10.075169 -131.507403)
			(xy 10.139179 -131.562868) (xy 10.197627 -131.624166) (xy 10.249983 -131.690742) (xy 10.295773 -131.761994)
			(xy 10.334584 -131.837275) (xy 10.366063 -131.915905) (xy 10.389924 -131.997172) (xy 10.405953 -132.080338)
			(xy 10.414004 -132.164652) (xy 10.414508 -132.207) (xy 10.414004 -132.249348) (xy 10.405953 -132.333662)
			(xy 10.389924 -132.416828) (xy 10.366063 -132.498095) (xy 10.334584 -132.576725) (xy 10.295773 -132.652006)
			(xy 10.249983 -132.723258) (xy 10.197627 -132.789834) (xy 10.139179 -132.851132) (xy 10.075169 -132.906597)
			(xy 10.006177 -132.955726) (xy 9.932827 -132.998075) (xy 9.855784 -133.033259) (xy 9.775745 -133.060961)
			(xy 9.693436 -133.080929) (xy 9.609601 -133.092982) (xy 9.525 -133.097013) (xy 9.440399 -133.092982)
			(xy 9.356564 -133.080929) (xy 9.274255 -133.060961) (xy 9.194216 -133.033259) (xy 9.117173 -132.998075)
			(xy 9.043823 -132.955726) (xy 8.974831 -132.906597) (xy 8.910821 -132.851132) (xy 8.852373 -132.789834)
			(xy 8.800017 -132.723258) (xy 8.754227 -132.652006) (xy 8.715416 -132.576725) (xy 8.683937 -132.498095)
			(xy 8.660076 -132.416828) (xy 8.644047 -132.333662) (xy 8.635996 -132.249348) (xy 8.382004 -132.249348)
			(xy 8.373953 -132.333662) (xy 8.357924 -132.416828) (xy 8.334063 -132.498095) (xy 8.302584 -132.576725)
			(xy 8.263773 -132.652006) (xy 8.217983 -132.723258) (xy 8.165627 -132.789834) (xy 8.107179 -132.851132)
			(xy 8.043169 -132.906597) (xy 7.974177 -132.955726) (xy 7.900827 -132.998075) (xy 7.823784 -133.033259)
			(xy 7.743745 -133.060961) (xy 7.661436 -133.080929) (xy 7.577601 -133.092982) (xy 7.493 -133.097013)
			(xy 7.408399 -133.092982) (xy 7.324564 -133.080929) (xy 7.242255 -133.060961) (xy 7.162216 -133.033259)
			(xy 7.085173 -132.998075) (xy 7.011823 -132.955726) (xy 6.942831 -132.906597) (xy 6.878821 -132.851132)
			(xy 6.820373 -132.789834) (xy 6.768017 -132.723258) (xy 6.722227 -132.652006) (xy 6.683416 -132.576725)
			(xy 6.651937 -132.498095) (xy 6.628076 -132.416828) (xy 6.612047 -132.333662) (xy 6.603996 -132.249348)
			(xy 3.666657 -132.249348) (xy 3.658078 -132.293084) (xy 3.633442 -132.375521) (xy 3.600963 -132.455195)
			(xy 3.5814 -132.493512) (xy 3.57639 -132.504735) (xy 3.576393 -132.529277) (xy 3.5814 -132.540502)
			(xy 3.600362 -132.578379) (xy 3.631835 -132.657024) (xy 3.655687 -132.738307) (xy 3.6717 -132.821489)
			(xy 3.67973 -132.905817) (xy 3.680206 -132.948172) (xy 3.679702 -132.99052) (xy 3.671651 -133.074834)
			(xy 3.655622 -133.158) (xy 3.631761 -133.239267) (xy 3.600282 -133.317897) (xy 3.561471 -133.393178)
			(xy 3.515681 -133.46443) (xy 3.463325 -133.531006) (xy 3.404877 -133.592304) (xy 3.340867 -133.647769)
			(xy 3.271875 -133.696898) (xy 3.198525 -133.739247) (xy 3.121482 -133.774431) (xy 3.041443 -133.802133)
			(xy 2.959134 -133.822101) (xy 2.875299 -133.834154) (xy 2.790698 -133.838185) (xy 2.706097 -133.834154)
			(xy 2.622262 -133.822101) (xy 2.539953 -133.802133) (xy 2.459914 -133.774431) (xy 2.382871 -133.739247)
			(xy 2.309521 -133.696898) (xy 2.240529 -133.647769) (xy 2.176519 -133.592304) (xy 2.118071 -133.531006)
			(xy 2.065715 -133.46443) (xy 2.019925 -133.393178) (xy 1.981114 -133.317897) (xy 1.949635 -133.239267)
			(xy 1.925774 -133.158) (xy 1.909745 -133.074834) (xy 1.901694 -132.99052) (xy 1.90119 -132.948172)
			(xy 1.651254 -132.948172) (xy 1.651254 -134.198614) (xy 6.115812 -134.198614) (xy 6.116316 -134.156266)
			(xy 6.124367 -134.071952) (xy 6.140396 -133.988786) (xy 6.164257 -133.907519) (xy 6.195736 -133.828889)
			(xy 6.234547 -133.753608) (xy 6.280337 -133.682356) (xy 6.332693 -133.61578) (xy 6.391141 -133.554482)
			(xy 6.455151 -133.499017) (xy 6.524143 -133.449888) (xy 6.597493 -133.407539) (xy 6.674536 -133.372355)
			(xy 6.754575 -133.344653) (xy 6.836884 -133.324685) (xy 6.920719 -133.312632) (xy 7.00532 -133.308602)
			(xy 7.089921 -133.312632) (xy 7.173756 -133.324685) (xy 7.256065 -133.344653) (xy 7.336104 -133.372355)
			(xy 7.413147 -133.407539) (xy 7.486497 -133.449888) (xy 7.555489 -133.499017) (xy 7.619499 -133.554482)
			(xy 7.677947 -133.61578) (xy 7.730303 -133.682356) (xy 7.776093 -133.753608) (xy 7.814904 -133.828889)
			(xy 7.846383 -133.907519) (xy 7.870244 -133.988786) (xy 7.886273 -134.071952) (xy 7.894324 -134.156266)
			(xy 7.894828 -134.198614) (xy 7.894368 -134.239) (xy 13.568939 -134.239) (xy 13.573041 -134.153651)
			(xy 13.585309 -134.069088) (xy 13.605629 -133.986092) (xy 13.633815 -133.905426) (xy 13.669607 -133.827836)
			(xy 13.712674 -133.754035) (xy 13.76262 -133.684704) (xy 13.790422 -133.65226) (xy 13.796101 -133.645135)
			(xy 13.80249 -133.628088) (xy 13.802868 -133.618986) (xy 13.802868 -133.589014) (xy 13.802473 -133.579913)
			(xy 13.7961 -133.562863) (xy 13.790422 -133.55574) (xy 13.764344 -133.525336) (xy 13.717125 -133.460626)
			(xy 13.675916 -133.391932) (xy 13.641053 -133.319811) (xy 13.612817 -133.244846) (xy 13.591437 -133.167645)
			(xy 13.577087 -133.088835) (xy 13.569882 -133.009053) (xy 13.569442 -132.969) (xy 13.569875 -132.928947)
			(xy 13.577086 -132.849166) (xy 13.59144 -132.770356) (xy 13.612821 -132.693155) (xy 13.641057 -132.61819)
			(xy 13.675917 -132.546067) (xy 13.71712 -132.477369) (xy 13.764333 -132.412654) (xy 13.790422 -132.38226)
			(xy 13.796101 -132.375135) (xy 13.80249 -132.358088) (xy 13.802868 -132.348986) (xy 13.802868 -132.319014)
			(xy 13.802473 -132.309913) (xy 13.7961 -132.292863) (xy 13.790422 -132.28574) (xy 13.76262 -132.253296)
			(xy 13.712674 -132.183965) (xy 13.669607 -132.110164) (xy 13.633815 -132.032574) (xy 13.605629 -131.951908)
			(xy 13.585309 -131.868912) (xy 13.573041 -131.784349) (xy 13.568939 -131.699) (xy 13.573041 -131.613651)
			(xy 13.585309 -131.529088) (xy 13.605629 -131.446092) (xy 13.633815 -131.365426) (xy 13.669607 -131.287836)
			(xy 13.712674 -131.214035) (xy 13.76262 -131.144704) (xy 13.790422 -131.11226) (xy 13.796101 -131.105135)
			(xy 13.80249 -131.088088) (xy 13.802868 -131.078986) (xy 13.802868 -131.049014) (xy 13.802473 -131.039913)
			(xy 13.7961 -131.022863) (xy 13.790422 -131.01574) (xy 13.76262 -130.983296) (xy 13.712674 -130.913965)
			(xy 13.669607 -130.840164) (xy 13.633815 -130.762574) (xy 13.605629 -130.681908) (xy 13.585309 -130.598912)
			(xy 13.573041 -130.514349) (xy 13.568939 -130.429) (xy 13.573041 -130.343651) (xy 13.585309 -130.259088)
			(xy 13.605629 -130.176092) (xy 13.633815 -130.095426) (xy 13.669607 -130.017836) (xy 13.712674 -129.944035)
			(xy 13.76262 -129.874704) (xy 13.790422 -129.84226) (xy 13.796101 -129.835135) (xy 13.80249 -129.818088)
			(xy 13.802868 -129.808986) (xy 13.802868 -129.779014) (xy 13.802473 -129.769913) (xy 13.7961 -129.752863)
			(xy 13.790422 -129.74574) (xy 13.764344 -129.715336) (xy 13.717125 -129.650626) (xy 13.675916 -129.581932)
			(xy 13.641053 -129.509811) (xy 13.612817 -129.434846) (xy 13.591437 -129.357645) (xy 13.577087 -129.278835)
			(xy 13.569882 -129.199053) (xy 13.569442 -129.159) (xy 13.569958 -129.115509) (xy 13.57846 -129.028943)
			(xy 13.595372 -128.943621) (xy 13.620533 -128.860357) (xy 13.653702 -128.779948) (xy 13.694563 -128.70316)
			(xy 13.742725 -128.630729) (xy 13.797728 -128.563345) (xy 13.828014 -128.532128) (xy 13.835126 -128.524762)
			(xy 13.842746 -128.506474) (xy 13.842746 -128.414526) (xy 13.835126 -128.396238) (xy 13.828014 -128.388872)
			(xy 13.797747 -128.357636) (xy 13.742736 -128.29026) (xy 13.694568 -128.217834) (xy 13.653703 -128.14105)
			(xy 13.620532 -128.060642) (xy 13.595372 -127.977379) (xy 13.578464 -127.892056) (xy 13.56997 -127.805491)
			(xy 13.569442 -127.762) (xy 13.569875 -127.721947) (xy 13.577086 -127.642166) (xy 13.59144 -127.563356)
			(xy 13.612821 -127.486155) (xy 13.641057 -127.41119) (xy 13.675917 -127.339067) (xy 13.71712 -127.270369)
			(xy 13.764333 -127.205654) (xy 13.790422 -127.17526) (xy 13.796101 -127.168135) (xy 13.80249 -127.151088)
			(xy 13.802868 -127.141986) (xy 13.802868 -127.112014) (xy 13.802473 -127.102913) (xy 13.7961 -127.085863)
			(xy 13.790422 -127.07874) (xy 13.76262 -127.046296) (xy 13.712674 -126.976965) (xy 13.669607 -126.903164)
			(xy 13.633815 -126.825574) (xy 13.605629 -126.744908) (xy 13.585309 -126.661912) (xy 13.573041 -126.577349)
			(xy 13.568939 -126.492) (xy 13.573041 -126.406651) (xy 13.585309 -126.322088) (xy 13.605629 -126.239092)
			(xy 13.633815 -126.158426) (xy 13.669607 -126.080836) (xy 13.712674 -126.007035) (xy 13.76262 -125.937704)
			(xy 13.790422 -125.90526) (xy 13.796101 -125.898135) (xy 13.80249 -125.881088) (xy 13.802868 -125.871986)
			(xy 13.802868 -125.842014) (xy 13.802473 -125.832913) (xy 13.7961 -125.815863) (xy 13.790422 -125.80874)
			(xy 13.76262 -125.776296) (xy 13.712674 -125.706965) (xy 13.669607 -125.633164) (xy 13.633815 -125.555574)
			(xy 13.605629 -125.474908) (xy 13.585309 -125.391912) (xy 13.573041 -125.307349) (xy 13.568939 -125.222)
			(xy 13.573041 -125.136651) (xy 13.585309 -125.052088) (xy 13.605629 -124.969092) (xy 13.633815 -124.888426)
			(xy 13.669607 -124.810836) (xy 13.712674 -124.737035) (xy 13.76262 -124.667704) (xy 13.790422 -124.63526)
			(xy 13.796101 -124.628135) (xy 13.80249 -124.611088) (xy 13.802868 -124.601986) (xy 13.802868 -124.572014)
			(xy 13.802473 -124.562913) (xy 13.7961 -124.545863) (xy 13.790422 -124.53874) (xy 13.764344 -124.508336)
			(xy 13.717125 -124.443626) (xy 13.675916 -124.374932) (xy 13.641053 -124.302811) (xy 13.612817 -124.227846)
			(xy 13.591437 -124.150645) (xy 13.577087 -124.071835) (xy 13.569882 -123.992053) (xy 13.569442 -123.952)
			(xy 13.569907 -123.911115) (xy 13.577414 -123.829691) (xy 13.592365 -123.7493) (xy 13.614633 -123.670621)
			(xy 13.64403 -123.594318) (xy 13.680308 -123.521037) (xy 13.72316 -123.451395) (xy 13.772225 -123.385982)
			(xy 13.799312 -123.355354) (xy 13.805164 -123.348302) (xy 13.811799 -123.331233) (xy 13.812266 -123.32208)
			(xy 13.812774 -123.292362) (xy 13.812521 -123.28315) (xy 13.806269 -123.265831) (xy 13.800582 -123.25858)
			(xy 13.771962 -123.224091) (xy 13.721041 -123.150332) (xy 13.677794 -123.071828) (xy 13.642658 -122.989374)
			(xy 13.61599 -122.903805) (xy 13.598059 -122.815988) (xy 13.589048 -122.726814) (xy 13.588492 -122.682)
			(xy 13.588996 -122.639652) (xy 13.597047 -122.555338) (xy 13.613076 -122.472172) (xy 13.636937 -122.390905)
			(xy 13.668416 -122.312275) (xy 13.707227 -122.236994) (xy 13.753017 -122.165742) (xy 13.805373 -122.099166)
			(xy 13.863821 -122.037868) (xy 13.927831 -121.982403) (xy 13.996823 -121.933274) (xy 14.070173 -121.890925)
			(xy 14.147216 -121.855741) (xy 14.227255 -121.828039) (xy 14.309564 -121.808071) (xy 14.393399 -121.796018)
			(xy 14.478 -121.791988) (xy 14.562601 -121.796018) (xy 14.646436 -121.808071) (xy 14.728745 -121.828039)
			(xy 14.808784 -121.855741) (xy 14.885827 -121.890925) (xy 14.959177 -121.933274) (xy 15.028169 -121.982403)
			(xy 15.092179 -122.037868) (xy 15.150627 -122.099166) (xy 15.202983 -122.165742) (xy 15.248773 -122.236994)
			(xy 15.287584 -122.312275) (xy 15.319063 -122.390905) (xy 15.342924 -122.472172) (xy 15.358953 -122.555338)
			(xy 15.367004 -122.639652) (xy 15.367508 -122.682) (xy 15.367056 -122.722885) (xy 15.359548 -122.80431)
			(xy 15.344597 -122.884702) (xy 15.322328 -122.963382) (xy 15.292929 -123.039684) (xy 15.256649 -123.112966)
			(xy 15.213794 -123.182606) (xy 15.164726 -123.248019) (xy 15.137638 -123.278646) (xy 15.131792 -123.285703)
			(xy 15.125153 -123.302768) (xy 15.124684 -123.31192) (xy 15.124176 -123.341638) (xy 15.12444 -123.350848)
			(xy 15.130686 -123.368167) (xy 15.136368 -123.37542) (xy 15.16498 -123.409916) (xy 15.215903 -123.483672)
			(xy 15.259152 -123.562175) (xy 15.294289 -123.644628) (xy 15.316862 -123.71705) (xy 20.592542 -123.71705)
			(xy 20.593024 -123.676359) (xy 20.600463 -123.595316) (xy 20.615273 -123.515292) (xy 20.637331 -123.436956)
			(xy 20.666453 -123.360962) (xy 20.702394 -123.287945) (xy 20.744855 -123.218517) (xy 20.79348 -123.153258)
			(xy 20.847863 -123.092713) (xy 20.907549 -123.037389) (xy 20.972039 -122.987749) (xy 21.040794 -122.944206)
			(xy 21.113239 -122.907127) (xy 21.150834 -122.89155) (xy 21.161248 -122.887232) (xy 21.176234 -122.871484)
			(xy 21.208746 -122.777758) (xy 21.206714 -122.756168) (xy 21.201126 -122.746262) (xy 21.182006 -122.712415)
			(xy 21.149082 -122.641987) (xy 21.122432 -122.568954) (xy 21.10226 -122.493873) (xy 21.08872 -122.417317)
			(xy 21.081915 -122.339872) (xy 21.081492 -122.301) (xy 21.081996 -122.258652) (xy 21.090047 -122.174338)
			(xy 21.106076 -122.091172) (xy 21.129937 -122.009905) (xy 21.161416 -121.931275) (xy 21.200227 -121.855994)
			(xy 21.246017 -121.784742) (xy 21.298373 -121.718166) (xy 21.356821 -121.656868) (xy 21.420831 -121.601403)
			(xy 21.489823 -121.552274) (xy 21.563173 -121.509925) (xy 21.640216 -121.474741) (xy 21.720255 -121.447039)
			(xy 21.802564 -121.427071) (xy 21.886399 -121.415018) (xy 21.971 -121.410988) (xy 22.055601 -121.415018)
			(xy 22.139436 -121.427071) (xy 22.221745 -121.447039) (xy 22.301784 -121.474741) (xy 22.378827 -121.509925)
			(xy 22.452177 -121.552274) (xy 22.521169 -121.601403) (xy 22.585179 -121.656868) (xy 22.643627 -121.718166)
			(xy 22.695983 -121.784742) (xy 22.741773 -121.855994) (xy 22.780584 -121.931275) (xy 22.812063 -122.009905)
			(xy 22.835924 -122.091172) (xy 22.851953 -122.174338) (xy 22.860004 -122.258652) (xy 22.860508 -122.301)
			(xy 22.860038 -122.341691) (xy 22.852596 -122.422733) (xy 22.837782 -122.502757) (xy 22.815721 -122.581092)
			(xy 22.786598 -122.657086) (xy 22.750655 -122.730101) (xy 22.714051 -122.78995) (xy 25.653492 -122.78995)
			(xy 25.653962 -122.749493) (xy 25.661309 -122.668913) (xy 25.675947 -122.589333) (xy 25.697755 -122.511413)
			(xy 25.726552 -122.435796) (xy 25.7621 -122.363109) (xy 25.804105 -122.293951) (xy 25.85222 -122.228897)
			(xy 25.87879 -122.198384) (xy 25.884754 -122.191207) (xy 25.891449 -122.173805) (xy 25.891442 -122.155159)
			(xy 25.884734 -122.137761) (xy 25.87879 -122.130566) (xy 25.852216 -122.100056) (xy 25.804103 -122.035)
			(xy 25.762098 -121.965842) (xy 25.72655 -121.893154) (xy 25.697752 -121.817537) (xy 25.675942 -121.739617)
			(xy 25.661301 -121.660038) (xy 25.653951 -121.579457) (xy 25.653492 -121.539) (xy 25.653996 -121.496652)
			(xy 25.662047 -121.412338) (xy 25.678076 -121.329172) (xy 25.701937 -121.247905) (xy 25.733416 -121.169275)
			(xy 25.772227 -121.093994) (xy 25.818017 -121.022742) (xy 25.870373 -120.956166) (xy 25.928821 -120.894868)
			(xy 25.992831 -120.839403) (xy 26.061823 -120.790274) (xy 26.135173 -120.747925) (xy 26.212216 -120.712741)
			(xy 26.292255 -120.685039) (xy 26.374564 -120.665071) (xy 26.458399 -120.653018) (xy 26.543 -120.648988)
			(xy 26.627601 -120.653018) (xy 26.711436 -120.665071) (xy 26.793745 -120.685039) (xy 26.873784 -120.712741)
			(xy 26.950827 -120.747925) (xy 27.024177 -120.790274) (xy 27.093169 -120.839403) (xy 27.157179 -120.894868)
			(xy 27.206265 -120.946348) (xy 27.939996 -120.946348) (xy 27.939996 -120.861652) (xy 27.948047 -120.777338)
			(xy 27.964076 -120.694172) (xy 27.987937 -120.612905) (xy 28.019416 -120.534275) (xy 28.058227 -120.458994)
			(xy 28.104017 -120.387742) (xy 28.156373 -120.321166) (xy 28.214821 -120.259868) (xy 28.278831 -120.204403)
			(xy 28.347823 -120.155274) (xy 28.421173 -120.112925) (xy 28.498216 -120.077741) (xy 28.578255 -120.050039)
			(xy 28.660564 -120.030071) (xy 28.744399 -120.018018) (xy 28.829 -120.013988) (xy 28.913601 -120.018018)
			(xy 28.997436 -120.030071) (xy 29.079745 -120.050039) (xy 29.159784 -120.077741) (xy 29.236827 -120.112925)
			(xy 29.310177 -120.155274) (xy 29.379169 -120.204403) (xy 29.443179 -120.259868) (xy 29.501627 -120.321166)
			(xy 29.553983 -120.387742) (xy 29.599773 -120.458994) (xy 29.638584 -120.534275) (xy 29.670063 -120.612905)
			(xy 29.693924 -120.694172) (xy 29.709953 -120.777338) (xy 29.718004 -120.861652) (xy 29.718508 -120.904)
			(xy 29.718004 -120.946348) (xy 29.717148 -120.955308) (xy 37.625782 -120.955308) (xy 37.626223 -120.912594)
			(xy 37.634406 -120.827558) (xy 37.650706 -120.7437) (xy 37.674975 -120.661791) (xy 37.706987 -120.582588)
			(xy 37.746448 -120.506819) (xy 37.792995 -120.435185) (xy 37.846196 -120.368345) (xy 37.905563 -120.306916)
			(xy 37.970548 -120.251464) (xy 38.040552 -120.2025) (xy 38.114929 -120.160476) (xy 38.192994 -120.125779)
			(xy 38.23335 -120.111774) (xy 38.24351 -120.108218) (xy 38.259004 -120.094248) (xy 38.298628 -120.007126)
			(xy 38.299136 -119.986044) (xy 38.295072 -119.976138) (xy 38.27866 -119.935404) (xy 38.252984 -119.851417)
			(xy 38.235719 -119.765306) (xy 38.227034 -119.677912) (xy 38.226492 -119.634) (xy 38.226996 -119.591652)
			(xy 38.235047 -119.507338) (xy 38.251076 -119.424172) (xy 38.274937 -119.342905) (xy 38.306416 -119.264275)
			(xy 38.345227 -119.188994) (xy 38.391017 -119.117742) (xy 38.443373 -119.051166) (xy 38.501821 -118.989868)
			(xy 38.565831 -118.934403) (xy 38.634823 -118.885274) (xy 38.708173 -118.842925) (xy 38.785216 -118.807741)
			(xy 38.865255 -118.780039) (xy 38.947564 -118.760071) (xy 39.031399 -118.748018) (xy 39.116 -118.743988)
			(xy 39.200601 -118.748018) (xy 39.284436 -118.760071) (xy 39.366745 -118.780039) (xy 39.446784 -118.807741)
			(xy 39.523827 -118.842925) (xy 39.597177 -118.885274) (xy 39.666169 -118.934403) (xy 39.730179 -118.989868)
			(xy 39.788627 -119.051166) (xy 39.840983 -119.117742) (xy 39.886773 -119.188994) (xy 39.925584 -119.264275)
			(xy 39.957063 -119.342905) (xy 39.980924 -119.424172) (xy 39.996953 -119.507338) (xy 40.005004 -119.591652)
			(xy 40.005508 -119.634) (xy 40.004991 -119.676713) (xy 39.996816 -119.761746) (xy 39.980524 -119.845603)
			(xy 39.956263 -119.92751) (xy 39.924258 -120.006714) (xy 39.884804 -120.082482) (xy 39.838264 -120.154116)
			(xy 39.785069 -120.220957) (xy 39.725707 -120.282387) (xy 39.660727 -120.33784) (xy 39.590728 -120.386805)
			(xy 39.516355 -120.42883) (xy 39.438294 -120.463528) (xy 39.39794 -120.477534) (xy 39.38778 -120.48109)
			(xy 39.372286 -120.49506) (xy 39.332662 -120.582182) (xy 39.332154 -120.603264) (xy 39.336218 -120.61317)
			(xy 39.352632 -120.653903) (xy 39.378308 -120.737891) (xy 39.395572 -120.824002) (xy 39.404256 -120.911396)
			(xy 39.404798 -120.955308) (xy 39.404294 -120.997656) (xy 39.396243 -121.08197) (xy 39.380214 -121.165136)
			(xy 39.356353 -121.246403) (xy 39.324874 -121.325033) (xy 39.286063 -121.400314) (xy 39.240273 -121.471566)
			(xy 39.187917 -121.538142) (xy 39.129469 -121.59944) (xy 39.065459 -121.654905) (xy 38.996467 -121.704034)
			(xy 38.923117 -121.746383) (xy 38.846074 -121.781567) (xy 38.766035 -121.809269) (xy 38.683726 -121.829237)
			(xy 38.599891 -121.84129) (xy 38.51529 -121.845321) (xy 38.430689 -121.84129) (xy 38.346854 -121.829237)
			(xy 38.264545 -121.809269) (xy 38.184506 -121.781567) (xy 38.107463 -121.746383) (xy 38.034113 -121.704034)
			(xy 37.965121 -121.654905) (xy 37.901111 -121.59944) (xy 37.842663 -121.538142) (xy 37.790307 -121.471566)
			(xy 37.744517 -121.400314) (xy 37.705706 -121.325033) (xy 37.674227 -121.246403) (xy 37.650366 -121.165136)
			(xy 37.634337 -121.08197) (xy 37.626286 -120.997656) (xy 37.625782 -120.955308) (xy 29.717148 -120.955308)
			(xy 29.709953 -121.030662) (xy 29.693924 -121.113828) (xy 29.670063 -121.195095) (xy 29.638584 -121.273725)
			(xy 29.599773 -121.349006) (xy 29.553983 -121.420258) (xy 29.501627 -121.486834) (xy 29.443179 -121.548132)
			(xy 29.379169 -121.603597) (xy 29.310177 -121.652726) (xy 29.236827 -121.695075) (xy 29.159784 -121.730259)
			(xy 29.079745 -121.757961) (xy 28.997436 -121.777929) (xy 28.913601 -121.789982) (xy 28.829 -121.794013)
			(xy 28.744399 -121.789982) (xy 28.660564 -121.777929) (xy 28.578255 -121.757961) (xy 28.498216 -121.730259)
			(xy 28.421173 -121.695075) (xy 28.347823 -121.652726) (xy 28.278831 -121.603597) (xy 28.214821 -121.548132)
			(xy 28.156373 -121.486834) (xy 28.104017 -121.420258) (xy 28.058227 -121.349006) (xy 28.019416 -121.273725)
			(xy 27.987937 -121.195095) (xy 27.964076 -121.113828) (xy 27.948047 -121.030662) (xy 27.939996 -120.946348)
			(xy 27.206265 -120.946348) (xy 27.215627 -120.956166) (xy 27.267983 -121.022742) (xy 27.313773 -121.093994)
			(xy 27.352584 -121.169275) (xy 27.384063 -121.247905) (xy 27.407924 -121.329172) (xy 27.423953 -121.412338)
			(xy 27.432004 -121.496652) (xy 27.432508 -121.539) (xy 27.432069 -121.579458) (xy 27.424717 -121.660039)
			(xy 27.410075 -121.739619) (xy 27.388263 -121.81754) (xy 27.359462 -121.893157) (xy 27.32391 -121.965844)
			(xy 27.281901 -122.035) (xy 27.233782 -122.100054) (xy 27.20721 -122.130566) (xy 27.201362 -122.137806)
			(xy 27.194753 -122.155185) (xy 27.194746 -122.173778) (xy 27.201342 -122.191162) (xy 27.20721 -122.198384)
			(xy 27.235423 -122.230793) (xy 27.286186 -122.300128) (xy 27.308556 -122.336814) (xy 27.313342 -122.344343)
			(xy 27.32715 -122.355631) (xy 27.343989 -122.361506) (xy 27.361822 -122.361257) (xy 27.370278 -122.358404)
			(xy 27.408163 -122.344505) (xy 27.485897 -122.322815) (xy 27.565277 -122.308256) (xy 27.645648 -122.300946)
			(xy 27.686 -122.300492) (xy 27.727505 -122.30099) (xy 27.810154 -122.308726) (xy 27.891723 -122.32413)
			(xy 27.971501 -122.347069) (xy 28.048794 -122.377343) (xy 28.122929 -122.414688) (xy 28.193262 -122.458779)
			(xy 28.226512 -122.483626) (xy 28.235711 -122.489969) (xy 28.2575 -122.4948) (xy 28.279289 -122.489969)
			(xy 28.288488 -122.483626) (xy 28.321738 -122.458779) (xy 28.392069 -122.414683) (xy 28.466204 -122.377333)
			(xy 28.543496 -122.347056) (xy 28.623275 -122.324115) (xy 28.704844 -122.308708) (xy 28.787494 -122.300972)
			(xy 28.829 -122.300492) (xy 28.872491 -122.301023) (xy 28.959055 -122.309524) (xy 29.044377 -122.326435)
			(xy 29.12764 -122.351594) (xy 29.208049 -122.384761) (xy 29.284837 -122.42562) (xy 29.357269 -122.473779)
			(xy 29.424654 -122.52878) (xy 29.455872 -122.559064) (xy 29.463238 -122.566176) (xy 29.481526 -122.573796)
			(xy 29.573474 -122.573796) (xy 29.591762 -122.566176) (xy 29.599128 -122.559064) (xy 29.630345 -122.528779)
			(xy 29.697728 -122.473777) (xy 29.77016 -122.425618) (xy 29.846948 -122.384761) (xy 29.927358 -122.351596)
			(xy 30.010622 -122.326442) (xy 30.095944 -122.309537) (xy 30.18251 -122.301044) (xy 30.26949 -122.301044)
			(xy 30.356056 -122.309537) (xy 30.441378 -122.326442) (xy 30.524642 -122.351596) (xy 30.605052 -122.384761)
			(xy 30.68184 -122.425618) (xy 30.754272 -122.473777) (xy 30.821655 -122.528779) (xy 30.852872 -122.559064)
			(xy 30.860238 -122.566176) (xy 30.878526 -122.573796) (xy 30.970474 -122.573796) (xy 30.988762 -122.566176)
			(xy 30.996128 -122.559064) (xy 31.027355 -122.528788) (xy 31.094733 -122.473779) (xy 31.167161 -122.425612)
			(xy 31.243947 -122.384749) (xy 31.324356 -122.35158) (xy 31.40762 -122.326421) (xy 31.492943 -122.309514)
			(xy 31.579509 -122.30102) (xy 31.623 -122.300492) (xy 31.666738 -122.301021) (xy 31.753791 -122.309619)
			(xy 31.839579 -122.326721) (xy 31.923274 -122.352163) (xy 32.004066 -122.385699) (xy 32.081176 -122.427004)
			(xy 32.153859 -122.47568) (xy 32.221411 -122.531257) (xy 32.252666 -122.561858) (xy 32.260032 -122.56897)
			(xy 32.27832 -122.57659) (xy 32.370268 -122.577098) (xy 32.388556 -122.569732) (xy 32.395922 -122.562366)
			(xy 32.427098 -122.532405) (xy 32.494339 -122.478034) (xy 32.566534 -122.430439) (xy 32.643005 -122.390069)
			(xy 32.72303 -122.357305) (xy 32.805855 -122.332456) (xy 32.8907 -122.315755) (xy 32.976764 -122.30736)
			(xy 33.02 -122.306842) (xy 33.063483 -122.307359) (xy 33.150035 -122.315844) (xy 33.235346 -122.332733)
			(xy 33.318602 -122.357865) (xy 33.399009 -122.391) (xy 33.4758 -122.431821) (xy 33.548242 -122.47994)
			(xy 33.615643 -122.534898) (xy 33.646872 -122.56516) (xy 33.653984 -122.572526) (xy 33.672272 -122.579892)
			(xy 33.764474 -122.579892) (xy 33.782762 -122.572526) (xy 33.789874 -122.56516) (xy 33.821103 -122.534866)
			(xy 33.888522 -122.479859) (xy 33.960987 -122.431696) (xy 34.037808 -122.390836) (xy 34.11825 -122.357669)
			(xy 34.201545 -122.332514) (xy 34.286899 -122.315608) (xy 34.373494 -122.307115) (xy 34.417 -122.306588)
			(xy 34.459348 -122.3071) (xy 34.543661 -122.315151) (xy 34.626827 -122.331179) (xy 34.708093 -122.355041)
			(xy 34.786723 -122.38652) (xy 34.862004 -122.42533) (xy 34.933256 -122.47112) (xy 34.999832 -122.523476)
			(xy 35.061129 -122.581924) (xy 35.116594 -122.645933) (xy 35.165723 -122.714925) (xy 35.208071 -122.788275)
			(xy 35.243255 -122.865317) (xy 35.270957 -122.945356) (xy 35.290925 -123.027665) (xy 35.302978 -123.111499)
			(xy 35.307009 -123.1961) (xy 35.302978 -123.280701) (xy 35.290925 -123.364535) (xy 35.270957 -123.446844)
			(xy 35.243255 -123.526883) (xy 35.208071 -123.603925) (xy 35.165723 -123.677275) (xy 35.116594 -123.746267)
			(xy 35.061129 -123.810276) (xy 34.999832 -123.868724) (xy 34.933256 -123.92108) (xy 34.862004 -123.96687)
			(xy 34.786723 -124.00568) (xy 34.708093 -124.037159) (xy 34.626827 -124.061021) (xy 34.543661 -124.077049)
			(xy 34.459348 -124.0851) (xy 34.417 -124.085604) (xy 34.373516 -124.085102) (xy 34.286963 -124.076617)
			(xy 34.201652 -124.059727) (xy 34.118395 -124.034593) (xy 34.037987 -124.001456) (xy 33.961197 -123.960632)
			(xy 33.888756 -123.91251) (xy 33.821357 -123.85755) (xy 33.790128 -123.827286) (xy 33.783016 -123.81992)
			(xy 33.764728 -123.812554) (xy 33.672526 -123.812554) (xy 33.654238 -123.81992) (xy 33.647126 -123.827286)
			(xy 33.615887 -123.85757) (xy 33.548471 -123.912579) (xy 33.476008 -123.960744) (xy 33.399189 -124.001606)
			(xy 33.318748 -124.034774) (xy 33.235453 -124.059931) (xy 33.150101 -124.076837) (xy 33.063505 -124.085331)
			(xy 33.02 -124.085858) (xy 32.976261 -124.085343) (xy 32.889208 -124.076745) (xy 32.803419 -124.059642)
			(xy 32.719724 -124.034198) (xy 32.638931 -124.000661) (xy 32.561821 -123.959353) (xy 32.489139 -123.910674)
			(xy 32.421588 -123.855095) (xy 32.390334 -123.824492) (xy 32.382968 -123.81738) (xy 32.36468 -123.80976)
			(xy 32.272732 -123.809252) (xy 32.254444 -123.816618) (xy 32.247078 -123.823984) (xy 32.21591 -123.853954)
			(xy 32.148668 -123.908323) (xy 32.07647 -123.955916) (xy 31.999998 -123.996284) (xy 31.919972 -124.029047)
			(xy 31.837146 -124.053895) (xy 31.752301 -124.070596) (xy 31.666236 -124.07899) (xy 31.623 -124.079508)
			(xy 31.579509 -124.078977) (xy 31.492945 -124.070476) (xy 31.407623 -124.053565) (xy 31.32436 -124.028406)
			(xy 31.243951 -123.995239) (xy 31.167163 -123.95438) (xy 31.094731 -123.906221) (xy 31.027346 -123.85122)
			(xy 30.996128 -123.820936) (xy 30.988762 -123.813824) (xy 30.970474 -123.806204) (xy 30.878526 -123.806204)
			(xy 30.860238 -123.813824) (xy 30.852872 -123.820936) (xy 30.821655 -123.851221) (xy 30.754272 -123.906223)
			(xy 30.68184 -123.954382) (xy 30.605052 -123.995239) (xy 30.524642 -124.028404) (xy 30.441378 -124.053558)
			(xy 30.356056 -124.070463) (xy 30.26949 -124.078956) (xy 30.18251 -124.078956) (xy 30.095944 -124.070463)
			(xy 30.010622 -124.053558) (xy 29.927358 -124.028404) (xy 29.846948 -123.995239) (xy 29.77016 -123.954382)
			(xy 29.697728 -123.906223) (xy 29.630345 -123.851221) (xy 29.599128 -123.820936) (xy 29.591762 -123.813824)
			(xy 29.573474 -123.806204) (xy 29.481526 -123.806204) (xy 29.463238 -123.813824) (xy 29.455872 -123.820936)
			(xy 29.424645 -123.851212) (xy 29.357267 -123.906221) (xy 29.284839 -123.954388) (xy 29.208053 -123.995251)
			(xy 29.127644 -124.02842) (xy 29.04438 -124.053579) (xy 28.959057 -124.070486) (xy 28.872491 -124.07898)
			(xy 28.829 -124.079508) (xy 28.787495 -124.07901) (xy 28.704846 -124.071274) (xy 28.623277 -124.05587)
			(xy 28.543499 -124.032931) (xy 28.466206 -124.002657) (xy 28.392071 -123.965312) (xy 28.321738 -123.921221)
			(xy 28.288488 -123.896374) (xy 28.279289 -123.890031) (xy 28.2575 -123.8852) (xy 28.235711 -123.890031)
			(xy 28.226512 -123.896374) (xy 28.18984 -123.923687) (xy 28.111909 -123.971528) (xy 28.029479 -124.011115)
			(xy 27.94342 -124.042031) (xy 27.854642 -124.063948) (xy 27.809444 -124.070872) (xy 27.800718 -124.072436)
			(xy 27.785013 -124.080623) (xy 27.773051 -124.093685) (xy 27.766274 -124.110048) (xy 27.765502 -124.118878)
			(xy 27.763 -124.16243) (xy 27.750613 -124.248787) (xy 27.729831 -124.333516) (xy 27.700854 -124.415803)
			(xy 27.663959 -124.494858) (xy 27.619501 -124.569921) (xy 27.567908 -124.64027) (xy 27.539188 -124.673106)
			(xy 27.533353 -124.68017) (xy 27.526708 -124.69723) (xy 27.526234 -124.70638) (xy 27.525726 -124.736098)
			(xy 27.526105 -124.745262) (xy 27.532467 -124.762446) (xy 27.538172 -124.769626) (xy 27.567115 -124.804187)
			(xy 27.618592 -124.878197) (xy 27.662318 -124.957035) (xy 27.697843 -125.039892) (xy 27.724803 -125.125919)
			(xy 27.742921 -125.214231) (xy 27.752011 -125.303924) (xy 27.752548 -125.349) (xy 27.75205 -125.391443)
			(xy 27.743964 -125.475943) (xy 27.727864 -125.559289) (xy 27.703899 -125.640722) (xy 27.672284 -125.719501)
			(xy 27.653234 -125.757432) (xy 27.64835 -125.768331) (xy 27.648235 -125.792189) (xy 27.65298 -125.803152)
			(xy 27.673381 -125.845715) (xy 27.677244 -125.856168) (xy 29.207456 -125.856168) (xy 29.207456 -125.771472)
			(xy 29.215507 -125.687158) (xy 29.231536 -125.603992) (xy 29.255397 -125.522725) (xy 29.286876 -125.444095)
			(xy 29.325687 -125.368814) (xy 29.371477 -125.297562) (xy 29.423833 -125.230986) (xy 29.482281 -125.169688)
			(xy 29.546291 -125.114223) (xy 29.615283 -125.065094) (xy 29.688633 -125.022745) (xy 29.765676 -124.987561)
			(xy 29.845715 -124.959859) (xy 29.928024 -124.939891) (xy 30.011859 -124.927838) (xy 30.09646 -124.923808)
			(xy 30.181061 -124.927838) (xy 30.264896 -124.939891) (xy 30.347205 -124.959859) (xy 30.427244 -124.987561)
			(xy 30.504287 -125.022745) (xy 30.577637 -125.065094) (xy 30.646629 -125.114223) (xy 30.710639 -125.169688)
			(xy 30.769087 -125.230986) (xy 30.821443 -125.297562) (xy 30.867233 -125.368814) (xy 30.906044 -125.444095)
			(xy 30.928754 -125.500822) (xy 31.132776 -125.500822) (xy 31.132776 -125.416126) (xy 31.140827 -125.331812)
			(xy 31.156856 -125.248646) (xy 31.180717 -125.167379) (xy 31.212196 -125.088749) (xy 31.251007 -125.013468)
			(xy 31.296797 -124.942216) (xy 31.349153 -124.87564) (xy 31.407601 -124.814342) (xy 31.471611 -124.758877)
			(xy 31.540603 -124.709748) (xy 31.613953 -124.667399) (xy 31.690996 -124.632215) (xy 31.771035 -124.604513)
			(xy 31.853344 -124.584545) (xy 31.937179 -124.572492) (xy 32.02178 -124.568462) (xy 32.106381 -124.572492)
			(xy 32.190216 -124.584545) (xy 32.272525 -124.604513) (xy 32.352564 -124.632215) (xy 32.429607 -124.667399)
			(xy 32.502957 -124.709748) (xy 32.571949 -124.758877) (xy 32.635959 -124.814342) (xy 32.694407 -124.87564)
			(xy 32.746763 -124.942216) (xy 32.792553 -125.013468) (xy 32.831364 -125.088749) (xy 32.862843 -125.167379)
			(xy 32.886704 -125.248646) (xy 32.902733 -125.331812) (xy 32.910784 -125.416126) (xy 32.911288 -125.458474)
			(xy 32.910784 -125.500822) (xy 32.902733 -125.585136) (xy 32.886704 -125.668302) (xy 32.862843 -125.749569)
			(xy 32.831364 -125.828199) (xy 32.792553 -125.90348) (xy 32.746763 -125.974732) (xy 32.694407 -126.041308)
			(xy 32.635959 -126.102606) (xy 32.571949 -126.158071) (xy 32.502957 -126.2072) (xy 32.429607 -126.249549)
			(xy 32.352564 -126.284733) (xy 32.272525 -126.312435) (xy 32.190216 -126.332403) (xy 32.106381 -126.344456)
			(xy 32.02178 -126.348487) (xy 31.937179 -126.344456) (xy 31.853344 -126.332403) (xy 31.771035 -126.312435)
			(xy 31.690996 -126.284733) (xy 31.613953 -126.249549) (xy 31.540603 -126.2072) (xy 31.471611 -126.158071)
			(xy 31.407601 -126.102606) (xy 31.349153 -126.041308) (xy 31.296797 -125.974732) (xy 31.251007 -125.90348)
			(xy 31.212196 -125.828199) (xy 31.180717 -125.749569) (xy 31.156856 -125.668302) (xy 31.140827 -125.585136)
			(xy 31.132776 -125.500822) (xy 30.928754 -125.500822) (xy 30.937523 -125.522725) (xy 30.961384 -125.603992)
			(xy 30.977413 -125.687158) (xy 30.985464 -125.771472) (xy 30.985968 -125.81382) (xy 30.985464 -125.856168)
			(xy 30.977413 -125.940482) (xy 30.961384 -126.023648) (xy 30.937523 -126.104915) (xy 30.906044 -126.183545)
			(xy 30.867233 -126.258826) (xy 30.821443 -126.330078) (xy 30.769087 -126.396654) (xy 30.710639 -126.457952)
			(xy 30.646629 -126.513417) (xy 30.577637 -126.562546) (xy 30.504287 -126.604895) (xy 30.427244 -126.640079)
			(xy 30.347205 -126.667781) (xy 30.264896 -126.687749) (xy 30.181061 -126.699802) (xy 30.09646 -126.703833)
			(xy 30.011859 -126.699802) (xy 29.928024 -126.687749) (xy 29.845715 -126.667781) (xy 29.765676 -126.640079)
			(xy 29.688633 -126.604895) (xy 29.615283 -126.562546) (xy 29.546291 -126.513417) (xy 29.482281 -126.457952)
			(xy 29.423833 -126.396654) (xy 29.371477 -126.330078) (xy 29.325687 -126.258826) (xy 29.286876 -126.183545)
			(xy 29.255397 -126.104915) (xy 29.231536 -126.023648) (xy 29.215507 -125.940482) (xy 29.207456 -125.856168)
			(xy 27.677244 -125.856168) (xy 27.706101 -125.934253) (xy 27.729261 -126.025758) (xy 27.736546 -126.072392)
			(xy 27.738734 -126.083392) (xy 27.751068 -126.102089) (xy 27.770181 -126.11377) (xy 27.78125 -126.115572)
			(xy 27.818526 -126.119977) (xy 27.892216 -126.134284) (xy 27.964435 -126.15476) (xy 27.99969 -126.167642)
			(xy 28.010113 -126.171043) (xy 28.031968 -126.169589) (xy 28.041854 -126.164848) (xy 28.080968 -126.144251)
			(xy 28.162463 -126.109992) (xy 28.246956 -126.083991) (xy 28.333614 -126.066506) (xy 28.421578 -126.057709)
			(xy 28.46578 -126.057152) (xy 28.506881 -126.057686) (xy 28.588732 -126.065268) (xy 28.669535 -126.080371)
			(xy 28.7486 -126.102864) (xy 28.825252 -126.132557) (xy 28.898837 -126.169196) (xy 28.968728 -126.212467)
			(xy 29.034328 -126.262003) (xy 29.095078 -126.31738) (xy 29.150459 -126.378126) (xy 29.199999 -126.443723)
			(xy 29.243275 -126.513611) (xy 29.279919 -126.587193) (xy 29.309616 -126.663843) (xy 29.332115 -126.742906)
			(xy 29.347223 -126.823708) (xy 29.354812 -126.905559) (xy 29.355288 -126.94666) (xy 29.354842 -126.987828)
			(xy 29.347239 -127.069813) (xy 29.332093 -127.150745) (xy 29.309534 -127.229931) (xy 29.279755 -127.306694)
			(xy 29.243011 -127.380377) (xy 29.199617 -127.45035) (xy 29.149943 -127.516014) (xy 29.094414 -127.576808)
			(xy 29.033506 -127.632212) (xy 28.96774 -127.681751) (xy 28.897678 -127.725001) (xy 28.861004 -127.743712)
			(xy 28.849828 -127.749046) (xy 28.835604 -127.76835) (xy 28.817316 -127.873506) (xy 28.824428 -127.896366)
			(xy 28.833064 -127.905256) (xy 28.862461 -127.936332) (xy 28.915788 -128.003226) (xy 28.962447 -128.074931)
			(xy 29.002007 -128.150784) (xy 29.015996 -128.185348) (xy 29.590996 -128.185348) (xy 29.590996 -128.100652)
			(xy 29.599047 -128.016338) (xy 29.615076 -127.933172) (xy 29.638937 -127.851905) (xy 29.670416 -127.773275)
			(xy 29.709227 -127.697994) (xy 29.755017 -127.626742) (xy 29.807373 -127.560166) (xy 29.865821 -127.498868)
			(xy 29.929831 -127.443403) (xy 29.998823 -127.394274) (xy 30.072173 -127.351925) (xy 30.149216 -127.316741)
			(xy 30.229255 -127.289039) (xy 30.311564 -127.269071) (xy 30.395399 -127.257018) (xy 30.48 -127.252988)
			(xy 30.564601 -127.257018) (xy 30.648436 -127.269071) (xy 30.730745 -127.289039) (xy 30.810784 -127.316741)
			(xy 30.887827 -127.351925) (xy 30.961177 -127.394274) (xy 31.030169 -127.443403) (xy 31.094179 -127.498868)
			(xy 31.152627 -127.560166) (xy 31.204983 -127.626742) (xy 31.250773 -127.697994) (xy 31.289584 -127.773275)
			(xy 31.321063 -127.851905) (xy 31.344924 -127.933172) (xy 31.360953 -128.016338) (xy 31.369004 -128.100652)
			(xy 31.369342 -128.12902) (xy 31.622097 -128.12902) (xy 31.627362 -128.045335) (xy 31.640479 -127.962517)
			(xy 31.661332 -127.8813) (xy 31.689736 -127.802407) (xy 31.725438 -127.726537) (xy 31.768121 -127.654363)
			(xy 31.817407 -127.586526) (xy 31.872859 -127.523629) (xy 31.933983 -127.466229) (xy 32.000238 -127.414837)
			(xy 32.071036 -127.369907) (xy 32.145747 -127.33184) (xy 32.223709 -127.300972) (xy 32.304231 -127.277579)
			(xy 32.386596 -127.261867) (xy 32.470075 -127.253976) (xy 32.512 -127.253492) (xy 32.554218 -127.253982)
			(xy 32.638274 -127.261996) (xy 32.721192 -127.277944) (xy 32.802224 -127.301681) (xy 32.88064 -127.332993)
			(xy 32.955735 -127.371598) (xy 32.991552 -127.393954) (xy 33.003744 -127.401828) (xy 33.031938 -127.402336)
			(xy 33.135316 -127.342138) (xy 33.148524 -127.317246) (xy 33.147762 -127.302768) (xy 33.146492 -127.254)
			(xy 33.146976 -127.212075) (xy 33.154867 -127.128596) (xy 33.170579 -127.046231) (xy 33.193972 -126.965709)
			(xy 33.22484 -126.887747) (xy 33.262907 -126.813036) (xy 33.307837 -126.742238) (xy 33.359229 -126.675983)
			(xy 33.416629 -126.614859) (xy 33.479526 -126.559407) (xy 33.547363 -126.510121) (xy 33.619537 -126.467438)
			(xy 33.695407 -126.431736) (xy 33.7743 -126.403332) (xy 33.855517 -126.382479) (xy 33.938335 -126.369362)
			(xy 34.02202 -126.364097) (xy 34.10583 -126.366731) (xy 34.189019 -126.37724) (xy 34.27085 -126.395532)
			(xy 34.350597 -126.421443) (xy 34.427551 -126.454744) (xy 34.50103 -126.49514) (xy 34.570382 -126.542271)
			(xy 34.63499 -126.595719) (xy 34.694281 -126.65501) (xy 34.747729 -126.719618) (xy 34.79486 -126.78897)
			(xy 34.835256 -126.862449) (xy 34.868557 -126.939403) (xy 34.894468 -127.01915) (xy 34.91276 -127.100981)
			(xy 34.923269 -127.18417) (xy 34.925903 -127.26798) (xy 34.920638 -127.351665) (xy 34.907521 -127.434483)
			(xy 34.886668 -127.5157) (xy 34.858264 -127.594593) (xy 34.822562 -127.670463) (xy 34.779879 -127.742637)
			(xy 34.730593 -127.810474) (xy 34.675141 -127.873371) (xy 34.614017 -127.930771) (xy 34.547762 -127.982163)
			(xy 34.476964 -128.027093) (xy 34.402253 -128.06516) (xy 34.324291 -128.096028) (xy 34.243769 -128.119421)
			(xy 34.161404 -128.135133) (xy 34.077925 -128.143024) (xy 34.036 -128.143508) (xy 33.993782 -128.143018)
			(xy 33.909726 -128.135004) (xy 33.826808 -128.119056) (xy 33.745776 -128.095319) (xy 33.66736 -128.064007)
			(xy 33.592265 -128.025402) (xy 33.556448 -128.003046) (xy 33.544256 -127.995172) (xy 33.516062 -127.994664)
			(xy 33.412684 -128.054862) (xy 33.399476 -128.079754) (xy 33.400238 -128.094232) (xy 33.401508 -128.143)
			(xy 33.401024 -128.184925) (xy 33.393133 -128.268404) (xy 33.377421 -128.350769) (xy 33.354028 -128.431291)
			(xy 33.32316 -128.509253) (xy 33.285093 -128.583964) (xy 33.240163 -128.654762) (xy 33.188771 -128.721017)
			(xy 33.131371 -128.782141) (xy 33.068474 -128.837593) (xy 33.000637 -128.886879) (xy 32.969996 -128.905)
			(xy 34.297117 -128.905) (xy 34.301148 -128.820399) (xy 34.313201 -128.736564) (xy 34.333169 -128.654255)
			(xy 34.360871 -128.574216) (xy 34.396055 -128.497173) (xy 34.438403 -128.423824) (xy 34.487532 -128.354831)
			(xy 34.542997 -128.290822) (xy 34.604295 -128.232374) (xy 34.670871 -128.180018) (xy 34.742123 -128.134227)
			(xy 34.817404 -128.095417) (xy 34.896034 -128.063938) (xy 34.9773 -128.040076) (xy 35.060466 -128.024047)
			(xy 35.14478 -128.015996) (xy 35.187128 -128.015492) (xy 35.228355 -128.015948) (xy 35.310455 -128.02359)
			(xy 35.391496 -128.038796) (xy 35.470782 -128.061436) (xy 35.547633 -128.091315) (xy 35.621389 -128.128178)
			(xy 35.691417 -128.171708) (xy 35.757117 -128.22153) (xy 35.817925 -128.277219) (xy 35.873319 -128.338295)
			(xy 35.922824 -128.404236) (xy 35.966014 -128.474474) (xy 36.002519 -128.548408) (xy 36.017708 -128.586738)
			(xy 36.022549 -128.597575) (xy 36.040017 -128.6136) (xy 36.051236 -128.617472) (xy 36.1061 -128.63322)
			(xy 36.1188 -128.62306) (xy 36.127182 -128.574546) (xy 36.12832 -128.565454) (xy 36.124807 -128.547485)
			(xy 36.120324 -128.539494) (xy 36.099448 -128.504509) (xy 36.063449 -128.431419) (xy 36.034286 -128.355342)
			(xy 36.012203 -128.276917) (xy 35.997387 -128.196801) (xy 35.989959 -128.115666) (xy 35.989514 -128.074928)
			(xy 35.989957 -128.034603) (xy 35.997254 -127.954283) (xy 36.011791 -127.874953) (xy 36.033449 -127.797265)
			(xy 36.062049 -127.721855) (xy 36.097357 -127.649344) (xy 36.139083 -127.580326) (xy 36.186884 -127.515368)
			(xy 36.213288 -127.484886) (xy 36.220908 -127.476504) (xy 36.227258 -127.455168) (xy 36.212526 -127.3556)
			(xy 36.200334 -127.337312) (xy 36.190682 -127.331216) (xy 36.155901 -127.309242) (xy 36.090206 -127.259707)
			(xy 36.029365 -127.204317) (xy 35.9739 -127.143546) (xy 35.924284 -127.077911) (xy 35.88094 -127.007976)
			(xy 35.844241 -126.934337) (xy 35.814499 -126.857623) (xy 35.791968 -126.77849) (xy 35.776841 -126.697615)
			(xy 35.769247 -126.615689) (xy 35.768788 -126.57455) (xy 35.769219 -126.533447) (xy 35.776808 -126.451591)
			(xy 35.791918 -126.370785) (xy 35.814418 -126.291718) (xy 35.844118 -126.215064) (xy 35.880763 -126.141478)
			(xy 35.924042 -126.071586) (xy 35.973584 -126.005985) (xy 36.028968 -125.945235) (xy 36.089721 -125.889855)
			(xy 36.155324 -125.840316) (xy 36.225218 -125.797041) (xy 36.298806 -125.760399) (xy 36.375462 -125.730703)
			(xy 36.45453 -125.708207) (xy 36.535337 -125.693102) (xy 36.617193 -125.685517) (xy 36.658296 -125.685042)
			(xy 36.700928 -125.685544) (xy 36.7858 -125.69371) (xy 36.869501 -125.709959) (xy 36.951263 -125.734141)
			(xy 37.030337 -125.766035) (xy 37.105997 -125.805348) (xy 37.177549 -125.851719) (xy 37.211254 -125.877828)
			(xy 37.223954 -125.887734) (xy 37.25545 -125.889766) (xy 37.364416 -125.822964) (xy 37.377116 -125.794008)
			(xy 37.374068 -125.77826) (xy 37.365891 -125.734906) (xy 37.357109 -125.647115) (xy 37.356542 -125.603)
			(xy 37.357094 -125.558186) (xy 37.366105 -125.469012) (xy 37.384037 -125.381195) (xy 37.410706 -125.295627)
			(xy 37.445844 -125.213173) (xy 37.489093 -125.13467) (xy 37.540016 -125.060913) (xy 37.568632 -125.02642)
			(xy 37.574322 -125.019171) (xy 37.580569 -125.00185) (xy 37.580824 -124.992638) (xy 37.580316 -124.96292)
			(xy 37.579781 -124.953781) (xy 37.573157 -124.936731) (xy 37.567362 -124.929646) (xy 37.540283 -124.899011)
			(xy 37.491216 -124.833599) (xy 37.448362 -124.763959) (xy 37.412083 -124.690679) (xy 37.382684 -124.614378)
			(xy 37.360415 -124.535699) (xy 37.345464 -124.455308) (xy 37.337957 -124.373885) (xy 37.337492 -124.333)
			(xy 37.337954 -124.292101) (xy 37.345461 -124.210647) (xy 37.360411 -124.130226) (xy 37.382679 -124.051517)
			(xy 37.412076 -123.975183) (xy 37.448354 -123.90187) (xy 37.491207 -123.832194) (xy 37.540274 -123.766746)
			(xy 37.567362 -123.7361) (xy 37.577014 -123.725432) (xy 37.582348 -123.697492) (xy 37.539422 -123.585732)
			(xy 37.516816 -123.56846) (xy 37.502338 -123.566936) (xy 37.45903 -123.56197) (xy 37.373572 -123.544748)
			(xy 37.29021 -123.519248) (xy 37.209742 -123.485714) (xy 37.132941 -123.444468) (xy 37.060544 -123.395906)
			(xy 36.993246 -123.340494) (xy 36.931692 -123.278763) (xy 36.876473 -123.211306) (xy 36.828118 -123.13877)
			(xy 36.787093 -123.061851) (xy 36.75379 -122.981287) (xy 36.728529 -122.897852) (xy 36.711553 -122.812345)
			(xy 36.703024 -122.725588) (xy 36.702492 -122.682) (xy 36.702996 -122.639652) (xy 36.711047 -122.555338)
			(xy 36.727076 -122.472172) (xy 36.750937 -122.390905) (xy 36.782416 -122.312275) (xy 36.821227 -122.236994)
			(xy 36.867017 -122.165742) (xy 36.919373 -122.099166) (xy 36.977821 -122.037868) (xy 37.041831 -121.982403)
			(xy 37.110823 -121.933274) (xy 37.184173 -121.890925) (xy 37.261216 -121.855741) (xy 37.341255 -121.828039)
			(xy 37.423564 -121.808071) (xy 37.507399 -121.796018) (xy 37.592 -121.791988) (xy 37.676601 -121.796018)
			(xy 37.760436 -121.808071) (xy 37.842745 -121.828039) (xy 37.922784 -121.855741) (xy 37.999827 -121.890925)
			(xy 38.073177 -121.933274) (xy 38.142169 -121.982403) (xy 38.206179 -122.037868) (xy 38.264627 -122.099166)
			(xy 38.316983 -122.165742) (xy 38.362773 -122.236994) (xy 38.401584 -122.312275) (xy 38.433063 -122.390905)
			(xy 38.456924 -122.472172) (xy 38.472953 -122.555338) (xy 38.481004 -122.639652) (xy 38.481508 -122.682)
			(xy 38.481046 -122.722899) (xy 38.473539 -122.804353) (xy 38.458589 -122.884774) (xy 38.436321 -122.963483)
			(xy 38.406924 -123.039817) (xy 38.370646 -123.11313) (xy 38.327793 -123.182806) (xy 38.278726 -123.248254)
			(xy 38.251638 -123.2789) (xy 38.241986 -123.289568) (xy 38.236652 -123.317508) (xy 38.279578 -123.429268)
			(xy 38.302184 -123.44654) (xy 38.316662 -123.448064) (xy 38.35997 -123.45303) (xy 38.445428 -123.470252)
			(xy 38.52879 -123.495752) (xy 38.609258 -123.529286) (xy 38.686059 -123.570532) (xy 38.758456 -123.619094)
			(xy 38.825754 -123.674506) (xy 38.887308 -123.736237) (xy 38.942527 -123.803694) (xy 38.990882 -123.87623)
			(xy 39.031907 -123.953149) (xy 39.06521 -124.033713) (xy 39.090471 -124.117148) (xy 39.107447 -124.202655)
			(xy 39.115976 -124.289412) (xy 39.116508 -124.333) (xy 39.115968 -124.377815) (xy 39.106956 -124.46699)
			(xy 39.089024 -124.554807) (xy 39.062353 -124.640376) (xy 39.027213 -124.722829) (xy 38.983961 -124.801332)
			(xy 38.933035 -124.875088) (xy 38.904418 -124.90958) (xy 38.898734 -124.916833) (xy 38.892482 -124.934151)
			(xy 38.892226 -124.943362) (xy 38.892734 -124.97308) (xy 38.893258 -124.98222) (xy 38.899889 -124.99927)
			(xy 38.905688 -125.006354) (xy 38.932775 -125.036982) (xy 38.98184 -125.102395) (xy 39.024693 -125.172037)
			(xy 39.060971 -125.245318) (xy 39.090368 -125.321621) (xy 39.112636 -125.4003) (xy 39.127586 -125.480691)
			(xy 39.135093 -125.562115) (xy 39.135558 -125.603) (xy 39.135125 -125.643053) (xy 39.127914 -125.722834)
			(xy 39.11356 -125.801644) (xy 39.092179 -125.878845) (xy 39.063943 -125.95381) (xy 39.029083 -126.025933)
			(xy 38.98788 -126.094631) (xy 38.940667 -126.159346) (xy 38.914578 -126.18974) (xy 38.908899 -126.196865)
			(xy 38.90251 -126.213912) (xy 38.902132 -126.223014) (xy 38.902132 -126.252986) (xy 38.902527 -126.262087)
			(xy 38.9089 -126.279137) (xy 38.914578 -126.28626) (xy 38.942381 -126.318704) (xy 38.99233 -126.388033)
			(xy 39.0354 -126.461834) (xy 39.071193 -126.539424) (xy 39.099381 -126.62009) (xy 39.119703 -126.703087)
			(xy 39.131971 -126.78765) (xy 39.136073 -126.873) (xy 39.131971 -126.95835) (xy 39.119703 -127.042913)
			(xy 39.099381 -127.12591) (xy 39.071193 -127.206576) (xy 39.0354 -127.284166) (xy 38.99233 -127.357967)
			(xy 38.942381 -127.427296) (xy 38.914578 -127.45974) (xy 38.908899 -127.466865) (xy 38.90251 -127.483912)
			(xy 38.902132 -127.493014) (xy 38.902132 -127.522986) (xy 38.902527 -127.532087) (xy 38.9089 -127.549137)
			(xy 38.914578 -127.55626) (xy 38.942381 -127.588704) (xy 38.99233 -127.658033) (xy 39.0354 -127.731834)
			(xy 39.071193 -127.809424) (xy 39.099381 -127.89009) (xy 39.119703 -127.973087) (xy 39.131971 -128.05765)
			(xy 39.136073 -128.143) (xy 39.134038 -128.185348) (xy 42.290996 -128.185348) (xy 42.290996 -128.100652)
			(xy 42.299047 -128.016338) (xy 42.315076 -127.933172) (xy 42.338937 -127.851905) (xy 42.370416 -127.773275)
			(xy 42.409227 -127.697994) (xy 42.455017 -127.626742) (xy 42.507373 -127.560166) (xy 42.565821 -127.498868)
			(xy 42.629831 -127.443403) (xy 42.698823 -127.394274) (xy 42.772173 -127.351925) (xy 42.849216 -127.316741)
			(xy 42.929255 -127.289039) (xy 43.011564 -127.269071) (xy 43.095399 -127.257018) (xy 43.18 -127.252988)
			(xy 43.264601 -127.257018) (xy 43.348436 -127.269071) (xy 43.430745 -127.289039) (xy 43.510784 -127.316741)
			(xy 43.587827 -127.351925) (xy 43.661177 -127.394274) (xy 43.730169 -127.443403) (xy 43.794179 -127.498868)
			(xy 43.852627 -127.560166) (xy 43.904983 -127.626742) (xy 43.950773 -127.697994) (xy 43.989584 -127.773275)
			(xy 44.021063 -127.851905) (xy 44.044924 -127.933172) (xy 44.060953 -128.016338) (xy 44.069004 -128.100652)
			(xy 44.069508 -128.143) (xy 44.069004 -128.185348) (xy 44.060953 -128.269662) (xy 44.044924 -128.352828)
			(xy 44.021063 -128.434095) (xy 43.989584 -128.512725) (xy 43.950773 -128.588006) (xy 43.904983 -128.659258)
			(xy 43.852627 -128.725834) (xy 43.794179 -128.787132) (xy 43.730169 -128.842597) (xy 43.661177 -128.891726)
			(xy 43.587827 -128.934075) (xy 43.510784 -128.969259) (xy 43.430745 -128.996961) (xy 43.348436 -129.016929)
			(xy 43.264601 -129.028982) (xy 43.18 -129.033013) (xy 43.095399 -129.028982) (xy 43.011564 -129.016929)
			(xy 42.929255 -128.996961) (xy 42.849216 -128.969259) (xy 42.772173 -128.934075) (xy 42.698823 -128.891726)
			(xy 42.629831 -128.842597) (xy 42.565821 -128.787132) (xy 42.507373 -128.725834) (xy 42.455017 -128.659258)
			(xy 42.409227 -128.588006) (xy 42.370416 -128.512725) (xy 42.338937 -128.434095) (xy 42.315076 -128.352828)
			(xy 42.299047 -128.269662) (xy 42.290996 -128.185348) (xy 39.134038 -128.185348) (xy 39.131971 -128.22835)
			(xy 39.119703 -128.312913) (xy 39.099381 -128.39591) (xy 39.071193 -128.476576) (xy 39.0354 -128.554166)
			(xy 38.99233 -128.627967) (xy 38.942381 -128.697296) (xy 38.914578 -128.72974) (xy 38.908899 -128.736865)
			(xy 38.90251 -128.753912) (xy 38.902132 -128.763014) (xy 38.902132 -128.792986) (xy 38.902527 -128.802087)
			(xy 38.9089 -128.819137) (xy 38.914578 -128.82626) (xy 38.940656 -128.856664) (xy 38.987875 -128.921374)
			(xy 39.029084 -128.990068) (xy 39.063947 -129.062189) (xy 39.092183 -129.137154) (xy 39.113563 -129.214355)
			(xy 39.127913 -129.293165) (xy 39.135118 -129.372947) (xy 39.135558 -129.413) (xy 39.135039 -129.457044)
			(xy 39.126365 -129.544703) (xy 39.109062 -129.631075) (xy 39.096696 -129.67335) (xy 39.093394 -129.684018)
			(xy 39.096188 -129.705608) (xy 39.149274 -129.789936) (xy 39.167562 -129.80162) (xy 39.178738 -129.803398)
			(xy 39.220342 -129.810159) (xy 39.302132 -129.830557) (xy 39.381625 -129.858601) (xy 39.458109 -129.894039)
			(xy 39.530897 -129.936553) (xy 39.599337 -129.985763) (xy 39.662815 -130.041226) (xy 39.720761 -130.102446)
			(xy 39.772656 -130.168872) (xy 39.818035 -130.239911) (xy 39.856489 -130.314923) (xy 39.887675 -130.393237)
			(xy 39.911313 -130.47415) (xy 39.92719 -130.556936) (xy 39.931125 -130.598348) (xy 42.036996 -130.598348)
			(xy 42.036996 -130.513652) (xy 42.045047 -130.429338) (xy 42.061076 -130.346172) (xy 42.084937 -130.264905)
			(xy 42.116416 -130.186275) (xy 42.155227 -130.110994) (xy 42.201017 -130.039742) (xy 42.253373 -129.973166)
			(xy 42.311821 -129.911868) (xy 42.375831 -129.856403) (xy 42.444823 -129.807274) (xy 42.518173 -129.764925)
			(xy 42.595216 -129.729741) (xy 42.675255 -129.702039) (xy 42.757564 -129.682071) (xy 42.841399 -129.670018)
			(xy 42.926 -129.665988) (xy 43.010601 -129.670018) (xy 43.094436 -129.682071) (xy 43.176745 -129.702039)
			(xy 43.256784 -129.729741) (xy 43.333827 -129.764925) (xy 43.407177 -129.807274) (xy 43.476169 -129.856403)
			(xy 43.540179 -129.911868) (xy 43.598627 -129.973166) (xy 43.650983 -130.039742) (xy 43.696773 -130.110994)
			(xy 43.735584 -130.186275) (xy 43.767063 -130.264905) (xy 43.790924 -130.346172) (xy 43.806953 -130.429338)
			(xy 43.815004 -130.513652) (xy 43.815508 -130.556) (xy 43.815004 -130.598348) (xy 44.068996 -130.598348)
			(xy 44.068996 -130.513652) (xy 44.077047 -130.429338) (xy 44.093076 -130.346172) (xy 44.116937 -130.264905)
			(xy 44.148416 -130.186275) (xy 44.187227 -130.110994) (xy 44.233017 -130.039742) (xy 44.285373 -129.973166)
			(xy 44.343821 -129.911868) (xy 44.407831 -129.856403) (xy 44.476823 -129.807274) (xy 44.550173 -129.764925)
			(xy 44.627216 -129.729741) (xy 44.707255 -129.702039) (xy 44.789564 -129.682071) (xy 44.873399 -129.670018)
			(xy 44.958 -129.665988) (xy 45.042601 -129.670018) (xy 45.126436 -129.682071) (xy 45.208745 -129.702039)
			(xy 45.288784 -129.729741) (xy 45.365827 -129.764925) (xy 45.439177 -129.807274) (xy 45.508169 -129.856403)
			(xy 45.572179 -129.911868) (xy 45.630627 -129.973166) (xy 45.682983 -130.039742) (xy 45.728773 -130.110994)
			(xy 45.767584 -130.186275) (xy 45.799063 -130.264905) (xy 45.822924 -130.346172) (xy 45.838953 -130.429338)
			(xy 45.847004 -130.513652) (xy 45.847508 -130.556) (xy 45.847004 -130.598348) (xy 45.838953 -130.682662)
			(xy 45.822924 -130.765828) (xy 45.799063 -130.847095) (xy 45.767584 -130.925725) (xy 45.728773 -131.001006)
			(xy 45.682983 -131.072258) (xy 45.630627 -131.138834) (xy 45.572179 -131.200132) (xy 45.508169 -131.255597)
			(xy 45.439177 -131.304726) (xy 45.365827 -131.347075) (xy 45.288784 -131.382259) (xy 45.208745 -131.409961)
			(xy 45.126436 -131.429929) (xy 45.042601 -131.441982) (xy 44.958 -131.446013) (xy 44.873399 -131.441982)
			(xy 44.789564 -131.429929) (xy 44.707255 -131.409961) (xy 44.627216 -131.382259) (xy 44.550173 -131.347075)
			(xy 44.476823 -131.304726) (xy 44.407831 -131.255597) (xy 44.343821 -131.200132) (xy 44.285373 -131.138834)
			(xy 44.233017 -131.072258) (xy 44.187227 -131.001006) (xy 44.148416 -130.925725) (xy 44.116937 -130.847095)
			(xy 44.093076 -130.765828) (xy 44.077047 -130.682662) (xy 44.068996 -130.598348) (xy 43.815004 -130.598348)
			(xy 43.806953 -130.682662) (xy 43.790924 -130.765828) (xy 43.767063 -130.847095) (xy 43.735584 -130.925725)
			(xy 43.696773 -131.001006) (xy 43.650983 -131.072258) (xy 43.598627 -131.138834) (xy 43.540179 -131.200132)
			(xy 43.476169 -131.255597) (xy 43.407177 -131.304726) (xy 43.333827 -131.347075) (xy 43.256784 -131.382259)
			(xy 43.176745 -131.409961) (xy 43.094436 -131.429929) (xy 43.010601 -131.441982) (xy 42.926 -131.446013)
			(xy 42.841399 -131.441982) (xy 42.757564 -131.429929) (xy 42.675255 -131.409961) (xy 42.595216 -131.382259)
			(xy 42.518173 -131.347075) (xy 42.444823 -131.304726) (xy 42.375831 -131.255597) (xy 42.311821 -131.200132)
			(xy 42.253373 -131.138834) (xy 42.201017 -131.072258) (xy 42.155227 -131.001006) (xy 42.116416 -130.925725)
			(xy 42.084937 -130.847095) (xy 42.061076 -130.765828) (xy 42.045047 -130.682662) (xy 42.036996 -130.598348)
			(xy 39.931125 -130.598348) (xy 39.935164 -130.640853) (xy 39.935658 -130.683) (xy 39.935143 -130.725148)
			(xy 39.927177 -130.809066) (xy 39.911307 -130.891853) (xy 39.887675 -130.972768) (xy 39.856493 -131.051084)
			(xy 39.818042 -131.126099) (xy 39.772666 -131.197138) (xy 39.720771 -131.263566) (xy 39.662825 -131.324786)
			(xy 39.599346 -131.380249) (xy 39.530905 -131.429457) (xy 39.458114 -131.471969) (xy 39.381628 -131.507403)
			(xy 39.302133 -131.535442) (xy 39.220341 -131.555833) (xy 39.178738 -131.562602) (xy 39.167562 -131.56438)
			(xy 39.149274 -131.576064) (xy 39.096188 -131.660392) (xy 39.093394 -131.681982) (xy 39.096696 -131.69265)
			(xy 39.109055 -131.734927) (xy 39.126351 -131.821299) (xy 39.135032 -131.908957) (xy 39.135558 -131.953)
			(xy 39.135039 -131.997044) (xy 39.126365 -132.084703) (xy 39.109062 -132.171075) (xy 39.096696 -132.21335)
			(xy 39.093394 -132.224018) (xy 39.096188 -132.245608) (xy 39.149274 -132.329936) (xy 39.167562 -132.34162)
			(xy 39.178738 -132.343398) (xy 39.220342 -132.350169) (xy 39.302134 -132.370563) (xy 39.38163 -132.398603)
			(xy 39.458116 -132.434038) (xy 39.530908 -132.47655) (xy 39.599351 -132.525758) (xy 39.662832 -132.58122)
			(xy 39.709336 -132.630348) (xy 42.036996 -132.630348) (xy 42.036996 -132.545652) (xy 42.045047 -132.461338)
			(xy 42.061076 -132.378172) (xy 42.084937 -132.296905) (xy 42.116416 -132.218275) (xy 42.155227 -132.142994)
			(xy 42.201017 -132.071742) (xy 42.253373 -132.005166) (xy 42.311821 -131.943868) (xy 42.375831 -131.888403)
			(xy 42.444823 -131.839274) (xy 42.518173 -131.796925) (xy 42.595216 -131.761741) (xy 42.675255 -131.734039)
			(xy 42.757564 -131.714071) (xy 42.841399 -131.702018) (xy 42.926 -131.697988) (xy 43.010601 -131.702018)
			(xy 43.094436 -131.714071) (xy 43.176745 -131.734039) (xy 43.256784 -131.761741) (xy 43.333827 -131.796925)
			(xy 43.407177 -131.839274) (xy 43.476169 -131.888403) (xy 43.540179 -131.943868) (xy 43.598627 -132.005166)
			(xy 43.650983 -132.071742) (xy 43.696773 -132.142994) (xy 43.735584 -132.218275) (xy 43.767063 -132.296905)
			(xy 43.790924 -132.378172) (xy 43.806953 -132.461338) (xy 43.815004 -132.545652) (xy 43.815508 -132.588)
			(xy 43.815004 -132.630348) (xy 44.068996 -132.630348) (xy 44.068996 -132.545652) (xy 44.077047 -132.461338)
			(xy 44.093076 -132.378172) (xy 44.116937 -132.296905) (xy 44.148416 -132.218275) (xy 44.187227 -132.142994)
			(xy 44.233017 -132.071742) (xy 44.285373 -132.005166) (xy 44.343821 -131.943868) (xy 44.407831 -131.888403)
			(xy 44.476823 -131.839274) (xy 44.550173 -131.796925) (xy 44.627216 -131.761741) (xy 44.707255 -131.734039)
			(xy 44.789564 -131.714071) (xy 44.873399 -131.702018) (xy 44.958 -131.697988) (xy 45.042601 -131.702018)
			(xy 45.126436 -131.714071) (xy 45.208745 -131.734039) (xy 45.288784 -131.761741) (xy 45.365827 -131.796925)
			(xy 45.439177 -131.839274) (xy 45.508169 -131.888403) (xy 45.572179 -131.943868) (xy 45.630627 -132.005166)
			(xy 45.682983 -132.071742) (xy 45.728773 -132.142994) (xy 45.767584 -132.218275) (xy 45.799063 -132.296905)
			(xy 45.822924 -132.378172) (xy 45.838953 -132.461338) (xy 45.847004 -132.545652) (xy 45.847508 -132.588)
			(xy 45.847004 -132.630348) (xy 45.838953 -132.714662) (xy 45.822924 -132.797828) (xy 45.799063 -132.879095)
			(xy 45.767584 -132.957725) (xy 45.728773 -133.033006) (xy 45.682983 -133.104258) (xy 45.630627 -133.170834)
			(xy 45.572179 -133.232132) (xy 45.508169 -133.287597) (xy 45.439177 -133.336726) (xy 45.365827 -133.379075)
			(xy 45.288784 -133.414259) (xy 45.208745 -133.441961) (xy 45.126436 -133.461929) (xy 45.042601 -133.473982)
			(xy 44.958 -133.478013) (xy 44.873399 -133.473982) (xy 44.789564 -133.461929) (xy 44.707255 -133.441961)
			(xy 44.627216 -133.414259) (xy 44.550173 -133.379075) (xy 44.476823 -133.336726) (xy 44.407831 -133.287597)
			(xy 44.343821 -133.232132) (xy 44.285373 -133.170834) (xy 44.233017 -133.104258) (xy 44.187227 -133.033006)
			(xy 44.148416 -132.957725) (xy 44.116937 -132.879095) (xy 44.093076 -132.797828) (xy 44.077047 -132.714662)
			(xy 44.068996 -132.630348) (xy 43.815004 -132.630348) (xy 43.806953 -132.714662) (xy 43.790924 -132.797828)
			(xy 43.767063 -132.879095) (xy 43.735584 -132.957725) (xy 43.696773 -133.033006) (xy 43.650983 -133.104258)
			(xy 43.598627 -133.170834) (xy 43.540179 -133.232132) (xy 43.476169 -133.287597) (xy 43.407177 -133.336726)
			(xy 43.333827 -133.379075) (xy 43.256784 -133.414259) (xy 43.176745 -133.441961) (xy 43.094436 -133.461929)
			(xy 43.010601 -133.473982) (xy 42.926 -133.478013) (xy 42.841399 -133.473982) (xy 42.757564 -133.461929)
			(xy 42.675255 -133.441961) (xy 42.595216 -133.414259) (xy 42.518173 -133.379075) (xy 42.444823 -133.336726)
			(xy 42.375831 -133.287597) (xy 42.311821 -133.232132) (xy 42.253373 -133.170834) (xy 42.201017 -133.104258)
			(xy 42.155227 -133.033006) (xy 42.116416 -132.957725) (xy 42.084937 -132.879095) (xy 42.061076 -132.797828)
			(xy 42.045047 -132.714662) (xy 42.036996 -132.630348) (xy 39.709336 -132.630348) (xy 39.720781 -132.642439)
			(xy 39.772678 -132.708866) (xy 39.818059 -132.779905) (xy 39.856516 -132.854918) (xy 39.887703 -132.933232)
			(xy 39.911342 -133.014146) (xy 39.92722 -133.096934) (xy 39.935195 -133.180852) (xy 39.935195 -133.265148)
			(xy 39.92722 -133.349066) (xy 39.911342 -133.431854) (xy 39.887703 -133.512768) (xy 39.856516 -133.591082)
			(xy 39.818059 -133.666095) (xy 39.772678 -133.737134) (xy 39.720781 -133.803561) (xy 39.662832 -133.86478)
			(xy 39.599351 -133.920242) (xy 39.530908 -133.96945) (xy 39.458116 -134.011962) (xy 39.38163 -134.047397)
			(xy 39.302134 -134.075437) (xy 39.220342 -134.095831) (xy 39.178738 -134.102602) (xy 39.167562 -134.10438)
			(xy 39.149274 -134.116064) (xy 39.096188 -134.200392) (xy 39.093394 -134.221982) (xy 39.096696 -134.23265)
			(xy 39.109055 -134.274927) (xy 39.126351 -134.361299) (xy 39.135032 -134.448957) (xy 39.135558 -134.493)
			(xy 39.135531 -134.49554) (xy 41.576752 -134.49554) (xy 41.577256 -134.453192) (xy 41.585307 -134.368878)
			(xy 41.601336 -134.285712) (xy 41.625197 -134.204445) (xy 41.656676 -134.125815) (xy 41.695487 -134.050534)
			(xy 41.741277 -133.979282) (xy 41.793633 -133.912706) (xy 41.852081 -133.851408) (xy 41.916091 -133.795943)
			(xy 41.985083 -133.746814) (xy 42.058433 -133.704465) (xy 42.135476 -133.669281) (xy 42.215515 -133.641579)
			(xy 42.297824 -133.621611) (xy 42.381659 -133.609558) (xy 42.46626 -133.605528) (xy 42.550861 -133.609558)
			(xy 42.634696 -133.621611) (xy 42.717005 -133.641579) (xy 42.797044 -133.669281) (xy 42.874087 -133.704465)
			(xy 42.947437 -133.746814) (xy 43.016429 -133.795943) (xy 43.080439 -133.851408) (xy 43.138887 -133.912706)
			(xy 43.191243 -133.979282) (xy 43.237033 -134.050534) (xy 43.275844 -134.125815) (xy 43.307323 -134.204445)
			(xy 43.331184 -134.285712) (xy 43.347213 -134.368878) (xy 43.355264 -134.453192) (xy 43.355768 -134.49554)
			(xy 43.35531 -134.535095) (xy 43.348261 -134.61389) (xy 43.33425 -134.691749) (xy 43.313386 -134.768058)
			(xy 43.285834 -134.842215) (xy 43.251812 -134.913635) (xy 43.23207 -134.947914) (xy 43.226482 -134.957312)
			(xy 43.224196 -134.978902) (xy 43.254676 -135.072374) (xy 43.269154 -135.088376) (xy 43.279314 -135.092694)
			(xy 43.318651 -135.110286) (xy 43.394055 -135.152008) (xy 43.465071 -135.200826) (xy 43.531034 -135.256283)
			(xy 43.591325 -135.317858) (xy 43.645379 -135.384975) (xy 43.69269 -135.457004) (xy 43.732814 -135.533271)
			(xy 43.765375 -135.61306) (xy 43.790067 -135.695624) (xy 43.806661 -135.780189) (xy 43.814999 -135.865961)
			(xy 43.815508 -135.90905) (xy 44.576492 -135.90905) (xy 44.576925 -135.869951) (xy 44.583812 -135.792056)
			(xy 44.597503 -135.715065) (xy 44.617893 -135.639571) (xy 44.644824 -135.566155) (xy 44.661074 -135.53059)
			(xy 44.66531 -135.520203) (xy 44.66531 -135.497797) (xy 44.661074 -135.48741) (xy 44.644794 -135.451857)
			(xy 44.617844 -135.378445) (xy 44.59745 -135.302949) (xy 44.58377 -135.225952) (xy 44.57691 -135.148051)
			(xy 44.576492 -135.10895) (xy 44.576996 -135.066602) (xy 44.585047 -134.982288) (xy 44.601076 -134.899122)
			(xy 44.624937 -134.817855) (xy 44.656416 -134.739225) (xy 44.695227 -134.663944) (xy 44.741017 -134.592692)
			(xy 44.793373 -134.526116) (xy 44.851821 -134.464818) (xy 44.915831 -134.409353) (xy 44.984823 -134.360224)
			(xy 45.058173 -134.317875) (xy 45.135216 -134.282691) (xy 45.215255 -134.254989) (xy 45.297564 -134.235021)
			(xy 45.381399 -134.222968) (xy 45.466 -134.218938) (xy 45.550601 -134.222968) (xy 45.634436 -134.235021)
			(xy 45.716745 -134.254989) (xy 45.796784 -134.282691) (xy 45.873827 -134.317875) (xy 45.947177 -134.360224)
			(xy 46.016169 -134.409353) (xy 46.080179 -134.464818) (xy 46.138627 -134.526116) (xy 46.190983 -134.592692)
			(xy 46.236773 -134.663944) (xy 46.275584 -134.739225) (xy 46.307063 -134.817855) (xy 46.330924 -134.899122)
			(xy 46.346953 -134.982288) (xy 46.355004 -135.066602) (xy 46.355508 -135.10895) (xy 46.355075 -135.148049)
			(xy 46.348188 -135.225944) (xy 46.334497 -135.302935) (xy 46.314107 -135.378429) (xy 46.287176 -135.451845)
			(xy 46.270926 -135.48741) (xy 46.26669 -135.497797) (xy 46.26669 -135.520203) (xy 46.270926 -135.53059)
			(xy 46.287206 -135.566143) (xy 46.314156 -135.639555) (xy 46.33455 -135.715051) (xy 46.34823 -135.792048)
			(xy 46.35509 -135.869949) (xy 46.355508 -135.90905) (xy 46.355004 -135.951398) (xy 46.346953 -136.035712)
			(xy 46.330924 -136.118878) (xy 46.307063 -136.200145) (xy 46.275584 -136.278775) (xy 46.236773 -136.354056)
			(xy 46.190983 -136.425308) (xy 46.138627 -136.491884) (xy 46.080179 -136.553182) (xy 46.016169 -136.608647)
			(xy 45.947177 -136.657776) (xy 45.873827 -136.700125) (xy 45.796784 -136.735309) (xy 45.716745 -136.763011)
			(xy 45.634436 -136.782979) (xy 45.550601 -136.795032) (xy 45.466 -136.799063) (xy 45.381399 -136.795032)
			(xy 45.297564 -136.782979) (xy 45.215255 -136.763011) (xy 45.135216 -136.735309) (xy 45.058173 -136.700125)
			(xy 44.984823 -136.657776) (xy 44.915831 -136.608647) (xy 44.851821 -136.553182) (xy 44.793373 -136.491884)
			(xy 44.741017 -136.425308) (xy 44.695227 -136.354056) (xy 44.656416 -136.278775) (xy 44.624937 -136.200145)
			(xy 44.601076 -136.118878) (xy 44.585047 -136.035712) (xy 44.576996 -135.951398) (xy 44.576492 -135.90905)
			(xy 43.815508 -135.90905) (xy 43.814991 -135.950301) (xy 43.807339 -136.032448) (xy 43.792114 -136.113534)
			(xy 43.769447 -136.192862) (xy 43.739534 -136.26975) (xy 43.70263 -136.343539) (xy 43.659052 -136.413594)
			(xy 43.609176 -136.479314) (xy 43.55343 -136.540133) (xy 43.492292 -136.59553) (xy 43.426288 -136.645029)
			(xy 43.355985 -136.688205) (xy 43.319192 -136.706864) (xy 43.310877 -136.711418) (xy 43.298122 -136.725424)
			(xy 43.291332 -136.74311) (xy 43.290998 -136.752584) (xy 43.290998 -136.843516) (xy 43.291363 -136.852984)
			(xy 43.298157 -136.870657) (xy 43.31089 -136.88467) (xy 43.319192 -136.889236) (xy 43.355993 -136.907887)
			(xy 43.426313 -136.951047) (xy 43.492332 -137.000535) (xy 43.553484 -137.055926) (xy 43.609242 -137.116743)
			(xy 43.659127 -137.182463) (xy 43.70271 -137.252522) (xy 43.739617 -137.326316) (xy 43.769529 -137.403212)
			(xy 43.79219 -137.482548) (xy 43.807405 -137.563641) (xy 43.815043 -137.645796) (xy 43.815508 -137.68705)
			(xy 43.815004 -137.729398) (xy 43.806953 -137.813712) (xy 43.790924 -137.896878) (xy 43.767063 -137.978145)
			(xy 43.735584 -138.056775) (xy 43.696773 -138.132056) (xy 43.650983 -138.203308) (xy 43.598627 -138.269884)
			(xy 43.540179 -138.331182) (xy 43.476169 -138.386647) (xy 43.407177 -138.435776) (xy 43.333827 -138.478125)
			(xy 43.256784 -138.513309) (xy 43.176745 -138.541011) (xy 43.094436 -138.560979) (xy 43.010601 -138.573032)
			(xy 42.926 -138.577063) (xy 42.841399 -138.573032) (xy 42.757564 -138.560979) (xy 42.675255 -138.541011)
			(xy 42.595216 -138.513309) (xy 42.518173 -138.478125) (xy 42.444823 -138.435776) (xy 42.375831 -138.386647)
			(xy 42.311821 -138.331182) (xy 42.253373 -138.269884) (xy 42.201017 -138.203308) (xy 42.155227 -138.132056)
			(xy 42.116416 -138.056775) (xy 42.084937 -137.978145) (xy 42.061076 -137.896878) (xy 42.045047 -137.813712)
			(xy 42.036996 -137.729398) (xy 42.036492 -137.68705) (xy 42.037009 -137.645799) (xy 42.044661 -137.563652)
			(xy 42.059886 -137.482566) (xy 42.082553 -137.403238) (xy 42.112466 -137.32635) (xy 42.14937 -137.252561)
			(xy 42.192948 -137.182506) (xy 42.242824 -137.116786) (xy 42.29857 -137.055967) (xy 42.359708 -137.00057)
			(xy 42.425712 -136.951071) (xy 42.496015 -136.907895) (xy 42.532808 -136.889236) (xy 42.541123 -136.884682)
			(xy 42.553878 -136.870676) (xy 42.560668 -136.85299) (xy 42.561002 -136.843516) (xy 42.561002 -136.752584)
			(xy 42.560637 -136.743116) (xy 42.553843 -136.725443) (xy 42.54111 -136.71143) (xy 42.532808 -136.706864)
			(xy 42.496007 -136.688213) (xy 42.425687 -136.645053) (xy 42.359668 -136.595565) (xy 42.298516 -136.540174)
			(xy 42.242758 -136.479357) (xy 42.192873 -136.413637) (xy 42.14929 -136.343578) (xy 42.112383 -136.269784)
			(xy 42.082471 -136.192888) (xy 42.05981 -136.113552) (xy 42.044595 -136.032459) (xy 42.036957 -135.950304)
			(xy 42.036492 -135.90905) (xy 42.036951 -135.869495) (xy 42.044 -135.7907) (xy 42.058012 -135.712841)
			(xy 42.078876 -135.636532) (xy 42.106427 -135.562375) (xy 42.140449 -135.490955) (xy 42.16019 -135.456676)
			(xy 42.165778 -135.447278) (xy 42.168064 -135.425688) (xy 42.137584 -135.332216) (xy 42.123106 -135.316214)
			(xy 42.112946 -135.311896) (xy 42.073619 -135.294282) (xy 41.998213 -135.252564) (xy 41.927195 -135.203749)
			(xy 41.861231 -135.148296) (xy 41.800939 -135.086723) (xy 41.746883 -135.019608) (xy 41.699571 -134.947581)
			(xy 41.659446 -134.871315) (xy 41.626885 -134.791527) (xy 41.602192 -134.708964) (xy 41.585599 -134.6244)
			(xy 41.577261 -134.538628) (xy 41.576752 -134.49554) (xy 39.135531 -134.49554) (xy 39.135125 -134.533053)
			(xy 39.127914 -134.612834) (xy 39.11356 -134.691644) (xy 39.092179 -134.768845) (xy 39.063943 -134.84381)
			(xy 39.029083 -134.915933) (xy 38.98788 -134.984631) (xy 38.940667 -135.049346) (xy 38.914578 -135.07974)
			(xy 38.908899 -135.086865) (xy 38.90251 -135.103912) (xy 38.902132 -135.113014) (xy 38.902132 -135.142986)
			(xy 38.902527 -135.152087) (xy 38.9089 -135.169137) (xy 38.914578 -135.17626) (xy 38.942381 -135.208704)
			(xy 38.99233 -135.278033) (xy 39.0354 -135.351834) (xy 39.071193 -135.429424) (xy 39.099381 -135.51009)
			(xy 39.119703 -135.593087) (xy 39.131971 -135.67765) (xy 39.136073 -135.763) (xy 39.131971 -135.84835)
			(xy 39.119703 -135.932913) (xy 39.099381 -136.01591) (xy 39.071193 -136.096576) (xy 39.0354 -136.174166)
			(xy 38.99233 -136.247967) (xy 38.942381 -136.317296) (xy 38.914578 -136.34974) (xy 38.908899 -136.356865)
			(xy 38.90251 -136.373912) (xy 38.902132 -136.383014) (xy 38.902132 -136.412986) (xy 38.902527 -136.422087)
			(xy 38.9089 -136.439137) (xy 38.914578 -136.44626) (xy 38.940656 -136.476664) (xy 38.987875 -136.541374)
			(xy 39.029084 -136.610068) (xy 39.063947 -136.682189) (xy 39.092183 -136.757154) (xy 39.113563 -136.834355)
			(xy 39.127913 -136.913165) (xy 39.135118 -136.992947) (xy 39.135558 -137.033) (xy 39.135093 -137.073885)
			(xy 39.127586 -137.155309) (xy 39.112635 -137.2357) (xy 39.090367 -137.314379) (xy 39.06097 -137.390682)
			(xy 39.024692 -137.463963) (xy 38.98184 -137.533605) (xy 38.932775 -137.599018) (xy 38.905688 -137.629646)
			(xy 38.899836 -137.636698) (xy 38.893201 -137.653767) (xy 38.892734 -137.66292) (xy 38.892226 -137.692638)
			(xy 38.892479 -137.70185) (xy 38.898731 -137.719169) (xy 38.904418 -137.72642) (xy 38.933038 -137.760909)
			(xy 38.983959 -137.834668) (xy 39.027206 -137.913172) (xy 39.062342 -137.995626) (xy 39.08901 -138.081195)
			(xy 39.106941 -138.169012) (xy 39.115952 -138.258186) (xy 39.116508 -138.303) (xy 39.116004 -138.345348)
			(xy 39.107953 -138.429662) (xy 39.091924 -138.512828) (xy 39.068063 -138.594095) (xy 39.036584 -138.672725)
			(xy 38.997773 -138.748006) (xy 38.951983 -138.819258) (xy 38.899627 -138.885834) (xy 38.841179 -138.947132)
			(xy 38.777169 -139.002597) (xy 38.708177 -139.051726) (xy 38.634827 -139.094075) (xy 38.557784 -139.129259)
			(xy 38.477745 -139.156961) (xy 38.395436 -139.176929) (xy 38.311601 -139.188982) (xy 38.227 -139.193013)
			(xy 38.142399 -139.188982) (xy 38.058564 -139.176929) (xy 37.976255 -139.156961) (xy 37.896216 -139.129259)
			(xy 37.819173 -139.094075) (xy 37.745823 -139.051726) (xy 37.676831 -139.002597) (xy 37.612821 -138.947132)
			(xy 37.554373 -138.885834) (xy 37.502017 -138.819258) (xy 37.456227 -138.748006) (xy 37.417416 -138.672725)
			(xy 37.385937 -138.594095) (xy 37.362076 -138.512828) (xy 37.346047 -138.429662) (xy 37.337996 -138.345348)
			(xy 37.337492 -138.303) (xy 37.337944 -138.262115) (xy 37.345452 -138.18069) (xy 37.360403 -138.100298)
			(xy 37.382672 -138.021618) (xy 37.412071 -137.945316) (xy 37.448351 -137.872034) (xy 37.491206 -137.802394)
			(xy 37.540274 -137.736981) (xy 37.567362 -137.706354) (xy 37.573208 -137.699297) (xy 37.579847 -137.682232)
			(xy 37.580316 -137.67308) (xy 37.580824 -137.643362) (xy 37.58056 -137.634152) (xy 37.574314 -137.616833)
			(xy 37.568632 -137.60958) (xy 37.54002 -137.575084) (xy 37.489097 -137.501328) (xy 37.445848 -137.422825)
			(xy 37.410711 -137.340372) (xy 37.384041 -137.254804) (xy 37.36611 -137.166988) (xy 37.357099 -137.077814)
			(xy 37.356542 -137.033) (xy 37.356975 -136.992947) (xy 37.364186 -136.913166) (xy 37.37854 -136.834356)
			(xy 37.399921 -136.757155) (xy 37.428157 -136.68219) (xy 37.463017 -136.610067) (xy 37.50422 -136.541369)
			(xy 37.551433 -136.476654) (xy 37.577522 -136.44626) (xy 37.583201 -136.439135) (xy 37.58959 -136.422088)
			(xy 37.589968 -136.412986) (xy 37.589968 -136.383014) (xy 37.589573 -136.373913) (xy 37.5832 -136.356863)
			(xy 37.577522 -136.34974) (xy 37.549719 -136.317296) (xy 37.49977 -136.247967) (xy 37.4567 -136.174166)
			(xy 37.420907 -136.096576) (xy 37.392719 -136.01591) (xy 37.372397 -135.932913) (xy 37.360129 -135.84835)
			(xy 37.356027 -135.763) (xy 37.360129 -135.67765) (xy 37.372397 -135.593087) (xy 37.392719 -135.51009)
			(xy 37.420907 -135.429424) (xy 37.4567 -135.351834) (xy 37.49977 -135.278033) (xy 37.549719 -135.208704)
			(xy 37.577522 -135.17626) (xy 37.583201 -135.169135) (xy 37.58959 -135.152088) (xy 37.589968 -135.142986)
			(xy 37.589968 -135.113014) (xy 37.589573 -135.103913) (xy 37.5832 -135.086863) (xy 37.577522 -135.07974)
			(xy 37.549719 -135.047296) (xy 37.49977 -134.977967) (xy 37.4567 -134.904166) (xy 37.420907 -134.826576)
			(xy 37.392719 -134.74591) (xy 37.372397 -134.662913) (xy 37.360129 -134.57835) (xy 37.356027 -134.493)
			(xy 37.360129 -134.40765) (xy 37.372397 -134.323087) (xy 37.392719 -134.24009) (xy 37.420907 -134.159424)
			(xy 37.4567 -134.081834) (xy 37.49977 -134.008033) (xy 37.549719 -133.938704) (xy 37.577522 -133.90626)
			(xy 37.583201 -133.899135) (xy 37.58959 -133.882088) (xy 37.589968 -133.872986) (xy 37.589968 -133.843014)
			(xy 37.589573 -133.833913) (xy 37.5832 -133.816863) (xy 37.577522 -133.80974) (xy 37.551444 -133.779336)
			(xy 37.504225 -133.714626) (xy 37.463016 -133.645932) (xy 37.428153 -133.573811) (xy 37.399917 -133.498846)
			(xy 37.378537 -133.421645) (xy 37.364187 -133.342835) (xy 37.356982 -133.263053) (xy 37.356542 -133.223)
			(xy 37.356975 -133.182947) (xy 37.364186 -133.103166) (xy 37.37854 -133.024356) (xy 37.399921 -132.947155)
			(xy 37.428157 -132.87219) (xy 37.463017 -132.800067) (xy 37.50422 -132.731369) (xy 37.551433 -132.666654)
			(xy 37.577522 -132.63626) (xy 37.583201 -132.629135) (xy 37.58959 -132.612088) (xy 37.589968 -132.602986)
			(xy 37.589968 -132.573014) (xy 37.589573 -132.563913) (xy 37.5832 -132.546863) (xy 37.577522 -132.53974)
			(xy 37.551444 -132.509336) (xy 37.504225 -132.444626) (xy 37.463016 -132.375932) (xy 37.428153 -132.303811)
			(xy 37.399917 -132.228846) (xy 37.378537 -132.151645) (xy 37.364187 -132.072835) (xy 37.356982 -131.993053)
			(xy 37.356542 -131.953) (xy 37.357057 -131.910852) (xy 37.365023 -131.826934) (xy 37.380893 -131.744147)
			(xy 37.404525 -131.663232) (xy 37.435707 -131.584916) (xy 37.474158 -131.509901) (xy 37.519534 -131.438862)
			(xy 37.571429 -131.372434) (xy 37.629375 -131.311214) (xy 37.692854 -131.255751) (xy 37.761295 -131.206543)
			(xy 37.834086 -131.164031) (xy 37.910572 -131.128597) (xy 37.990067 -131.100558) (xy 38.071859 -131.080167)
			(xy 38.113462 -131.073398) (xy 38.124638 -131.07162) (xy 38.142926 -131.059936) (xy 38.196012 -130.975608)
			(xy 38.198806 -130.954018) (xy 38.195504 -130.94335) (xy 38.183145 -130.901073) (xy 38.165849 -130.814701)
			(xy 38.157168 -130.727043) (xy 38.156642 -130.683) (xy 38.157161 -130.638956) (xy 38.165835 -130.551297)
			(xy 38.183138 -130.464925) (xy 38.195504 -130.42265) (xy 38.198806 -130.411982) (xy 38.196012 -130.390392)
			(xy 38.142926 -130.306064) (xy 38.124638 -130.29438) (xy 38.113462 -130.292602) (xy 38.07285 -130.286033)
			(xy 37.992979 -130.266286) (xy 37.915273 -130.23925) (xy 37.840393 -130.205158) (xy 37.76898 -130.164299)
			(xy 37.701643 -130.117023) (xy 37.638958 -130.063733) (xy 37.581459 -130.004885) (xy 37.529637 -129.940981)
			(xy 37.506402 -129.90703) (xy 37.499544 -129.89687) (xy 37.47897 -129.885186) (xy 37.373306 -129.879598)
			(xy 37.351716 -129.888996) (xy 37.343842 -129.898394) (xy 37.315707 -129.931244) (xy 37.254076 -129.991932)
			(xy 37.186846 -130.046351) (xy 37.11465 -130.093988) (xy 37.038173 -130.134394) (xy 36.958134 -130.167185)
			(xy 36.875291 -130.192053) (xy 36.790425 -130.208764) (xy 36.704338 -130.217158) (xy 36.66109 -130.217672)
			(xy 36.617935 -130.217172) (xy 36.532031 -130.208818) (xy 36.447341 -130.19218) (xy 36.364661 -130.167414)
			(xy 36.28477 -130.134753) (xy 36.20842 -130.094505) (xy 36.136328 -130.047049) (xy 36.069174 -129.992831)
			(xy 36.007589 -129.932361) (xy 35.952154 -129.866208) (xy 35.903388 -129.794995) (xy 35.861753 -129.719393)
			(xy 35.844226 -129.679954) (xy 35.839654 -129.669286) (xy 35.822636 -129.654554) (xy 35.724846 -129.62636)
			(xy 35.702494 -129.629916) (xy 35.693096 -129.63652) (xy 35.65587 -129.661564) (xy 35.577323 -129.704934)
			(xy 35.494808 -129.740173) (xy 35.409163 -129.766921) (xy 35.321259 -129.784906) (xy 35.23199 -129.793946)
			(xy 35.187128 -129.794508) (xy 35.14478 -129.794004) (xy 35.060466 -129.785953) (xy 34.9773 -129.769924)
			(xy 34.896034 -129.746062) (xy 34.817404 -129.714583) (xy 34.742123 -129.675773) (xy 34.670871 -129.629982)
			(xy 34.604295 -129.577626) (xy 34.542997 -129.519178) (xy 34.487532 -129.455169) (xy 34.438403 -129.386176)
			(xy 34.396055 -129.312827) (xy 34.360871 -129.235784) (xy 34.333169 -129.155745) (xy 34.313201 -129.073436)
			(xy 34.301148 -128.989601) (xy 34.297117 -128.905) (xy 32.969996 -128.905) (xy 32.928463 -128.929562)
			(xy 32.852593 -128.965264) (xy 32.7737 -128.993668) (xy 32.692483 -129.014521) (xy 32.609665 -129.027638)
			(xy 32.52598 -129.032903) (xy 32.44217 -129.030269) (xy 32.358981 -129.01976) (xy 32.27715 -129.001468)
			(xy 32.197403 -128.975557) (xy 32.120449 -128.942256) (xy 32.04697 -128.90186) (xy 31.977618 -128.854729)
			(xy 31.91301 -128.801281) (xy 31.853719 -128.74199) (xy 31.800271 -128.677382) (xy 31.75314 -128.60803)
			(xy 31.712744 -128.534551) (xy 31.679443 -128.457597) (xy 31.653532 -128.37785) (xy 31.63524 -128.296019)
			(xy 31.624731 -128.21283) (xy 31.622097 -128.12902) (xy 31.369342 -128.12902) (xy 31.369508 -128.143)
			(xy 31.369004 -128.185348) (xy 31.360953 -128.269662) (xy 31.344924 -128.352828) (xy 31.321063 -128.434095)
			(xy 31.289584 -128.512725) (xy 31.250773 -128.588006) (xy 31.204983 -128.659258) (xy 31.152627 -128.725834)
			(xy 31.094179 -128.787132) (xy 31.030169 -128.842597) (xy 30.961177 -128.891726) (xy 30.887827 -128.934075)
			(xy 30.810784 -128.969259) (xy 30.730745 -128.996961) (xy 30.648436 -129.016929) (xy 30.564601 -129.028982)
			(xy 30.48 -129.033013) (xy 30.395399 -129.028982) (xy 30.311564 -129.016929) (xy 30.229255 -128.996961)
			(xy 30.149216 -128.969259) (xy 30.072173 -128.934075) (xy 29.998823 -128.891726) (xy 29.929831 -128.842597)
			(xy 29.865821 -128.787132) (xy 29.807373 -128.725834) (xy 29.755017 -128.659258) (xy 29.709227 -128.588006)
			(xy 29.670416 -128.512725) (xy 29.638937 -128.434095) (xy 29.615076 -128.352828) (xy 29.599047 -128.269662)
			(xy 29.590996 -128.185348) (xy 29.015996 -128.185348) (xy 29.034103 -128.230084) (xy 29.058438 -128.312099)
			(xy 29.074787 -128.396071) (xy 29.083 -128.481225) (xy 29.083508 -128.524) (xy 29.082976 -128.5649)
			(xy 29.075474 -128.646354) (xy 29.060525 -128.726775) (xy 29.038254 -128.805485) (xy 29.00885 -128.881816)
			(xy 28.972562 -128.955125) (xy 28.929696 -129.024793) (xy 28.880614 -129.09023) (xy 28.82573 -129.150884)
			(xy 28.76551 -129.206243) (xy 28.70046 -129.255838) (xy 28.631132 -129.29925) (xy 28.55811 -129.336114)
			(xy 28.482012 -129.366116) (xy 28.40348 -129.389005) (xy 28.363418 -129.397252) (xy 28.350972 -129.399538)
			(xy 28.33116 -129.415794) (xy 28.288742 -129.517394) (xy 28.291282 -129.542794) (xy 28.298394 -129.553462)
			(xy 28.322251 -129.590088) (xy 28.363483 -129.667168) (xy 28.396957 -129.74792) (xy 28.422349 -129.831566)
			(xy 28.439414 -129.917299) (xy 28.447988 -130.004292) (xy 28.448508 -130.048) (xy 28.448004 -130.090348)
			(xy 28.439953 -130.174662) (xy 28.431726 -130.217348) (xy 29.590996 -130.217348) (xy 29.590996 -130.132652)
			(xy 29.599047 -130.048338) (xy 29.615076 -129.965172) (xy 29.638937 -129.883905) (xy 29.670416 -129.805275)
			(xy 29.709227 -129.729994) (xy 29.755017 -129.658742) (xy 29.807373 -129.592166) (xy 29.865821 -129.530868)
			(xy 29.929831 -129.475403) (xy 29.998823 -129.426274) (xy 30.072173 -129.383925) (xy 30.149216 -129.348741)
			(xy 30.229255 -129.321039) (xy 30.311564 -129.301071) (xy 30.395399 -129.289018) (xy 30.48 -129.284988)
			(xy 30.564601 -129.289018) (xy 30.648436 -129.301071) (xy 30.730745 -129.321039) (xy 30.810784 -129.348741)
			(xy 30.887827 -129.383925) (xy 30.961177 -129.426274) (xy 31.030169 -129.475403) (xy 31.094179 -129.530868)
			(xy 31.152627 -129.592166) (xy 31.204983 -129.658742) (xy 31.250773 -129.729994) (xy 31.289584 -129.805275)
			(xy 31.321063 -129.883905) (xy 31.344924 -129.965172) (xy 31.360953 -130.048338) (xy 31.369004 -130.132652)
			(xy 31.369508 -130.175) (xy 31.369004 -130.217348) (xy 31.622996 -130.217348) (xy 31.622996 -130.132652)
			(xy 31.631047 -130.048338) (xy 31.647076 -129.965172) (xy 31.670937 -129.883905) (xy 31.702416 -129.805275)
			(xy 31.741227 -129.729994) (xy 31.787017 -129.658742) (xy 31.839373 -129.592166) (xy 31.897821 -129.530868)
			(xy 31.961831 -129.475403) (xy 32.030823 -129.426274) (xy 32.104173 -129.383925) (xy 32.181216 -129.348741)
			(xy 32.261255 -129.321039) (xy 32.343564 -129.301071) (xy 32.427399 -129.289018) (xy 32.512 -129.284988)
			(xy 32.596601 -129.289018) (xy 32.680436 -129.301071) (xy 32.762745 -129.321039) (xy 32.842784 -129.348741)
			(xy 32.919827 -129.383925) (xy 32.993177 -129.426274) (xy 33.062169 -129.475403) (xy 33.126179 -129.530868)
			(xy 33.184627 -129.592166) (xy 33.236983 -129.658742) (xy 33.282773 -129.729994) (xy 33.321584 -129.805275)
			(xy 33.353063 -129.883905) (xy 33.376924 -129.965172) (xy 33.392953 -130.048338) (xy 33.401004 -130.132652)
			(xy 33.401508 -130.175) (xy 33.401004 -130.217348) (xy 33.392953 -130.301662) (xy 33.376924 -130.384828)
			(xy 33.353063 -130.466095) (xy 33.321584 -130.544725) (xy 33.282773 -130.620006) (xy 33.236983 -130.691258)
			(xy 33.184627 -130.757834) (xy 33.126179 -130.819132) (xy 33.062169 -130.874597) (xy 32.993177 -130.923726)
			(xy 32.919827 -130.966075) (xy 32.842784 -131.001259) (xy 32.762745 -131.028961) (xy 32.680436 -131.048929)
			(xy 32.596601 -131.060982) (xy 32.512 -131.065013) (xy 32.427399 -131.060982) (xy 32.343564 -131.048929)
			(xy 32.261255 -131.028961) (xy 32.181216 -131.001259) (xy 32.104173 -130.966075) (xy 32.030823 -130.923726)
			(xy 31.961831 -130.874597) (xy 31.897821 -130.819132) (xy 31.839373 -130.757834) (xy 31.787017 -130.691258)
			(xy 31.741227 -130.620006) (xy 31.702416 -130.544725) (xy 31.670937 -130.466095) (xy 31.647076 -130.384828)
			(xy 31.631047 -130.301662) (xy 31.622996 -130.217348) (xy 31.369004 -130.217348) (xy 31.360953 -130.301662)
			(xy 31.344924 -130.384828) (xy 31.321063 -130.466095) (xy 31.289584 -130.544725) (xy 31.250773 -130.620006)
			(xy 31.204983 -130.691258) (xy 31.152627 -130.757834) (xy 31.094179 -130.819132) (xy 31.030169 -130.874597)
			(xy 30.961177 -130.923726) (xy 30.887827 -130.966075) (xy 30.810784 -131.001259) (xy 30.730745 -131.028961)
			(xy 30.648436 -131.048929) (xy 30.564601 -131.060982) (xy 30.48 -131.065013) (xy 30.395399 -131.060982)
			(xy 30.311564 -131.048929) (xy 30.229255 -131.028961) (xy 30.149216 -131.001259) (xy 30.072173 -130.966075)
			(xy 29.998823 -130.923726) (xy 29.929831 -130.874597) (xy 29.865821 -130.819132) (xy 29.807373 -130.757834)
			(xy 29.755017 -130.691258) (xy 29.709227 -130.620006) (xy 29.670416 -130.544725) (xy 29.638937 -130.466095)
			(xy 29.615076 -130.384828) (xy 29.599047 -130.301662) (xy 29.590996 -130.217348) (xy 28.431726 -130.217348)
			(xy 28.423924 -130.257828) (xy 28.400063 -130.339095) (xy 28.368584 -130.417725) (xy 28.329773 -130.493006)
			(xy 28.283983 -130.564258) (xy 28.231627 -130.630834) (xy 28.173179 -130.692132) (xy 28.109169 -130.747597)
			(xy 28.040177 -130.796726) (xy 27.966827 -130.839075) (xy 27.889784 -130.874259) (xy 27.809745 -130.901961)
			(xy 27.727436 -130.921929) (xy 27.643601 -130.933982) (xy 27.559 -130.938013) (xy 27.474399 -130.933982)
			(xy 27.390564 -130.921929) (xy 27.308255 -130.901961) (xy 27.228216 -130.874259) (xy 27.151173 -130.839075)
			(xy 27.077823 -130.796726) (xy 27.008831 -130.747597) (xy 26.944821 -130.692132) (xy 26.886373 -130.630834)
			(xy 26.834017 -130.564258) (xy 26.788227 -130.493006) (xy 26.749416 -130.417725) (xy 26.717937 -130.339095)
			(xy 26.694076 -130.257828) (xy 26.678047 -130.174662) (xy 26.669996 -130.090348) (xy 26.669492 -130.048)
			(xy 26.670024 -130.0071) (xy 26.677526 -129.925646) (xy 26.692475 -129.845225) (xy 26.714746 -129.766515)
			(xy 26.74415 -129.690184) (xy 26.780438 -129.616875) (xy 26.823304 -129.547207) (xy 26.872386 -129.48177)
			(xy 26.92727 -129.421116) (xy 26.98749 -129.365757) (xy 27.05254 -129.316162) (xy 27.121868 -129.27275)
			(xy 27.19489 -129.235886) (xy 27.270988 -129.205884) (xy 27.34952 -129.182995) (xy 27.389582 -129.174748)
			(xy 27.402028 -129.172462) (xy 27.42184 -129.156206) (xy 27.464258 -129.054606) (xy 27.461718 -129.029206)
			(xy 27.454606 -129.018538) (xy 27.430749 -128.981912) (xy 27.389517 -128.904832) (xy 27.356043 -128.82408)
			(xy 27.330651 -128.740434) (xy 27.313586 -128.654701) (xy 27.305012 -128.567708) (xy 27.304492 -128.524)
			(xy 27.304901 -128.484398) (xy 27.311947 -128.405507) (xy 27.325975 -128.327554) (xy 27.346872 -128.251156)
			(xy 27.374475 -128.176917) (xy 27.408565 -128.105423) (xy 27.448872 -128.037242) (xy 27.471624 -128.004824)
			(xy 27.478736 -127.994918) (xy 27.482546 -127.970788) (xy 27.448764 -127.869442) (xy 27.431238 -127.852424)
			(xy 27.419554 -127.848614) (xy 27.37992 -127.835685) (xy 27.303051 -127.803401) (xy 27.229542 -127.764063)
			(xy 27.160038 -127.718016) (xy 27.09515 -127.665665) (xy 27.035448 -127.60747) (xy 26.981455 -127.543942)
			(xy 26.933647 -127.475638) (xy 26.892442 -127.403158) (xy 26.858203 -127.32714) (xy 26.831231 -127.24825)
			(xy 26.811762 -127.167182) (xy 26.805382 -127.125984) (xy 26.803187 -127.114987) (xy 26.790853 -127.096293)
			(xy 26.771745 -127.08461) (xy 26.760678 -127.082804) (xy 26.717582 -127.07763) (xy 26.632592 -127.059967)
			(xy 26.549728 -127.034109) (xy 26.469776 -127.000303) (xy 26.393497 -126.958869) (xy 26.321617 -126.910203)
			(xy 26.254819 -126.854766) (xy 26.193738 -126.793087) (xy 26.138956 -126.725751) (xy 26.090994 -126.653399)
			(xy 26.050307 -126.57672) (xy 26.017282 -126.496442) (xy 25.992234 -126.413329) (xy 25.975402 -126.328171)
			(xy 25.966944 -126.241779) (xy 25.96642 -126.198376) (xy 25.966911 -126.155933) (xy 25.975 -126.071432)
			(xy 25.991101 -125.988087) (xy 26.015068 -125.906654) (xy 26.046683 -125.827875) (xy 26.065734 -125.789944)
			(xy 26.070571 -125.779028) (xy 26.070717 -125.755186) (xy 26.065988 -125.744224) (xy 26.048218 -125.70732)
			(xy 26.018768 -125.630882) (xy 25.996465 -125.552063) (xy 25.981496 -125.471527) (xy 25.973989 -125.389957)
			(xy 25.973532 -125.349) (xy 25.974018 -125.308337) (xy 25.98143 -125.227349) (xy 25.996201 -125.147376)
			(xy 26.018209 -125.069084) (xy 26.047268 -124.993127) (xy 26.083138 -124.920138) (xy 26.125518 -124.850727)
			(xy 26.174056 -124.785473) (xy 26.200862 -124.754894) (xy 26.206691 -124.747825) (xy 26.213341 -124.730769)
			(xy 26.213816 -124.72162) (xy 26.214324 -124.691902) (xy 26.213956 -124.682737) (xy 26.207588 -124.665552)
			(xy 26.201878 -124.658374) (xy 26.172943 -124.623807) (xy 26.121464 -124.549799) (xy 26.077736 -124.470962)
			(xy 26.04221 -124.388106) (xy 26.015249 -124.30208) (xy 25.99713 -124.213768) (xy 25.988039 -124.124076)
			(xy 25.987502 -124.079) (xy 25.988064 -124.03358) (xy 25.997353 -123.943215) (xy 26.015804 -123.854268)
			(xy 26.043225 -123.767664) (xy 26.07933 -123.684306) (xy 26.10104 -123.644406) (xy 26.105372 -123.635672)
			(xy 26.107867 -123.616354) (xy 26.105866 -123.606814) (xy 26.098246 -123.57735) (xy 26.095366 -123.568016)
			(xy 26.083733 -123.552342) (xy 26.07564 -123.54687) (xy 26.040858 -123.524865) (xy 25.975123 -123.475329)
			(xy 25.914244 -123.419931) (xy 25.858743 -123.359147) (xy 25.809094 -123.293496) (xy 25.765722 -123.22354)
			(xy 25.728997 -123.149876) (xy 25.699235 -123.073134) (xy 25.676688 -122.993972) (xy 25.661551 -122.913065)
			(xy 25.653952 -122.831105) (xy 25.653492 -122.78995) (xy 22.714051 -122.78995) (xy 22.708193 -122.799528)
			(xy 22.659567 -122.864787) (xy 22.605184 -122.925332) (xy 22.545498 -122.980656) (xy 22.481008 -123.030297)
			(xy 22.412254 -123.073841) (xy 22.33981 -123.110922) (xy 22.302216 -123.1265) (xy 22.291802 -123.130818)
			(xy 22.276816 -123.146566) (xy 22.244304 -123.240292) (xy 22.246336 -123.261882) (xy 22.251924 -123.271788)
			(xy 22.271029 -123.305643) (xy 22.303955 -123.376069) (xy 22.330606 -123.449101) (xy 22.350781 -123.524181)
			(xy 22.364324 -123.600735) (xy 22.371133 -123.678179) (xy 22.371558 -123.71705) (xy 22.371054 -123.759398)
			(xy 22.363003 -123.843712) (xy 22.346974 -123.926878) (xy 22.323113 -124.008145) (xy 22.291634 -124.086775)
			(xy 22.252823 -124.162056) (xy 22.207033 -124.233308) (xy 22.154677 -124.299884) (xy 22.096229 -124.361182)
			(xy 22.032219 -124.416647) (xy 21.963227 -124.465776) (xy 21.889877 -124.508125) (xy 21.812834 -124.543309)
			(xy 21.732795 -124.571011) (xy 21.650486 -124.590979) (xy 21.566651 -124.603032) (xy 21.48205 -124.607063)
			(xy 21.397449 -124.603032) (xy 21.313614 -124.590979) (xy 21.231305 -124.571011) (xy 21.151266 -124.543309)
			(xy 21.074223 -124.508125) (xy 21.000873 -124.465776) (xy 20.931881 -124.416647) (xy 20.867871 -124.361182)
			(xy 20.809423 -124.299884) (xy 20.757067 -124.233308) (xy 20.711277 -124.162056) (xy 20.672466 -124.086775)
			(xy 20.640987 -124.008145) (xy 20.617126 -123.926878) (xy 20.601097 -123.843712) (xy 20.593046 -123.759398)
			(xy 20.592542 -123.71705) (xy 15.316862 -123.71705) (xy 15.320959 -123.730196) (xy 15.33889 -123.818012)
			(xy 15.347901 -123.907186) (xy 15.348458 -123.952) (xy 15.348025 -123.992053) (xy 15.340814 -124.071834)
			(xy 15.32646 -124.150644) (xy 15.305079 -124.227845) (xy 15.276843 -124.30281) (xy 15.241983 -124.374933)
			(xy 15.20078 -124.443631) (xy 15.153567 -124.508346) (xy 15.127478 -124.53874) (xy 15.121799 -124.545865)
			(xy 15.11541 -124.562912) (xy 15.115032 -124.572014) (xy 15.115032 -124.601986) (xy 15.115427 -124.611087)
			(xy 15.1218 -124.628137) (xy 15.127478 -124.63526) (xy 15.15528 -124.667704) (xy 15.205226 -124.737035)
			(xy 15.248293 -124.810836) (xy 15.284085 -124.888426) (xy 15.312271 -124.969092) (xy 15.332591 -125.052088)
			(xy 15.344859 -125.136651) (xy 15.348961 -125.222) (xy 15.344859 -125.307349) (xy 15.332591 -125.391912)
			(xy 15.314881 -125.464246) (xy 23.287732 -125.464246) (xy 23.287732 -125.37955) (xy 23.295783 -125.295236)
			(xy 23.311812 -125.21207) (xy 23.335673 -125.130803) (xy 23.367152 -125.052173) (xy 23.405963 -124.976892)
			(xy 23.451753 -124.90564) (xy 23.504109 -124.839064) (xy 23.562557 -124.777766) (xy 23.626567 -124.722301)
			(xy 23.695559 -124.673172) (xy 23.768909 -124.630823) (xy 23.845952 -124.595639) (xy 23.925991 -124.567937)
			(xy 24.0083 -124.547969) (xy 24.092135 -124.535916) (xy 24.176736 -124.531886) (xy 24.261337 -124.535916)
			(xy 24.345172 -124.547969) (xy 24.427481 -124.567937) (xy 24.50752 -124.595639) (xy 24.584563 -124.630823)
			(xy 24.657913 -124.673172) (xy 24.726905 -124.722301) (xy 24.790915 -124.777766) (xy 24.849363 -124.839064)
			(xy 24.901719 -124.90564) (xy 24.947509 -124.976892) (xy 24.98632 -125.052173) (xy 25.017799 -125.130803)
			(xy 25.04166 -125.21207) (xy 25.057689 -125.295236) (xy 25.06574 -125.37955) (xy 25.066244 -125.421898)
			(xy 25.06574 -125.464246) (xy 25.057689 -125.54856) (xy 25.04166 -125.631726) (xy 25.017799 -125.712993)
			(xy 24.98632 -125.791623) (xy 24.947509 -125.866904) (xy 24.901719 -125.938156) (xy 24.849363 -126.004732)
			(xy 24.790915 -126.06603) (xy 24.726905 -126.121495) (xy 24.657913 -126.170624) (xy 24.584563 -126.212973)
			(xy 24.50752 -126.248157) (xy 24.427481 -126.275859) (xy 24.345172 -126.295827) (xy 24.261337 -126.30788)
			(xy 24.176736 -126.311911) (xy 24.092135 -126.30788) (xy 24.0083 -126.295827) (xy 23.925991 -126.275859)
			(xy 23.845952 -126.248157) (xy 23.768909 -126.212973) (xy 23.695559 -126.170624) (xy 23.626567 -126.121495)
			(xy 23.562557 -126.06603) (xy 23.504109 -126.004732) (xy 23.451753 -125.938156) (xy 23.405963 -125.866904)
			(xy 23.367152 -125.791623) (xy 23.335673 -125.712993) (xy 23.311812 -125.631726) (xy 23.295783 -125.54856)
			(xy 23.287732 -125.464246) (xy 15.314881 -125.464246) (xy 15.312271 -125.474908) (xy 15.284085 -125.555574)
			(xy 15.248293 -125.633164) (xy 15.205226 -125.706965) (xy 15.15528 -125.776296) (xy 15.127478 -125.80874)
			(xy 15.121799 -125.815865) (xy 15.11541 -125.832912) (xy 15.115032 -125.842014) (xy 15.115032 -125.871986)
			(xy 15.115427 -125.881087) (xy 15.1218 -125.898137) (xy 15.127478 -125.90526) (xy 15.15528 -125.937704)
			(xy 15.205226 -126.007035) (xy 15.248293 -126.080836) (xy 15.284085 -126.158426) (xy 15.312271 -126.239092)
			(xy 15.332591 -126.322088) (xy 15.344859 -126.406651) (xy 15.348961 -126.492) (xy 15.344859 -126.577349)
			(xy 15.332591 -126.661912) (xy 15.312271 -126.744908) (xy 15.284085 -126.825574) (xy 15.248293 -126.903164)
			(xy 15.205226 -126.976965) (xy 15.15528 -127.046296) (xy 15.127478 -127.07874) (xy 15.121799 -127.085865)
			(xy 15.11541 -127.102912) (xy 15.115032 -127.112014) (xy 15.115032 -127.141986) (xy 15.115427 -127.151087)
			(xy 15.1218 -127.168137) (xy 15.127478 -127.17526) (xy 15.153556 -127.205664) (xy 15.200775 -127.270374)
			(xy 15.241984 -127.339068) (xy 15.276847 -127.411189) (xy 15.305083 -127.486154) (xy 15.326463 -127.563355)
			(xy 15.340813 -127.642165) (xy 15.348018 -127.721947) (xy 15.348458 -127.762) (xy 15.347942 -127.805491)
			(xy 15.33944 -127.892057) (xy 15.322528 -127.977379) (xy 15.297367 -128.060643) (xy 15.264198 -128.141052)
			(xy 15.240627 -128.185348) (xy 19.049996 -128.185348) (xy 19.049996 -128.100652) (xy 19.058047 -128.016338)
			(xy 19.074076 -127.933172) (xy 19.097937 -127.851905) (xy 19.129416 -127.773275) (xy 19.168227 -127.697994)
			(xy 19.214017 -127.626742) (xy 19.266373 -127.560166) (xy 19.324821 -127.498868) (xy 19.388831 -127.443403)
			(xy 19.457823 -127.394274) (xy 19.531173 -127.351925) (xy 19.608216 -127.316741) (xy 19.688255 -127.289039)
			(xy 19.770564 -127.269071) (xy 19.854399 -127.257018) (xy 19.939 -127.252988) (xy 20.023601 -127.257018)
			(xy 20.107436 -127.269071) (xy 20.189745 -127.289039) (xy 20.269784 -127.316741) (xy 20.346827 -127.351925)
			(xy 20.420177 -127.394274) (xy 20.489169 -127.443403) (xy 20.553179 -127.498868) (xy 20.611627 -127.560166)
			(xy 20.663983 -127.626742) (xy 20.709773 -127.697994) (xy 20.748584 -127.773275) (xy 20.780063 -127.851905)
			(xy 20.803924 -127.933172) (xy 20.819953 -128.016338) (xy 20.828004 -128.100652) (xy 20.828508 -128.143)
			(xy 20.828004 -128.185348) (xy 21.081996 -128.185348) (xy 21.081996 -128.100652) (xy 21.090047 -128.016338)
			(xy 21.106076 -127.933172) (xy 21.129937 -127.851905) (xy 21.161416 -127.773275) (xy 21.200227 -127.697994)
			(xy 21.246017 -127.626742) (xy 21.298373 -127.560166) (xy 21.356821 -127.498868) (xy 21.420831 -127.443403)
			(xy 21.489823 -127.394274) (xy 21.563173 -127.351925) (xy 21.640216 -127.316741) (xy 21.720255 -127.289039)
			(xy 21.802564 -127.269071) (xy 21.886399 -127.257018) (xy 21.971 -127.252988) (xy 22.055601 -127.257018)
			(xy 22.139436 -127.269071) (xy 22.221745 -127.289039) (xy 22.301784 -127.316741) (xy 22.378827 -127.351925)
			(xy 22.452177 -127.394274) (xy 22.521169 -127.443403) (xy 22.585179 -127.498868) (xy 22.643627 -127.560166)
			(xy 22.695983 -127.626742) (xy 22.741773 -127.697994) (xy 22.780584 -127.773275) (xy 22.812063 -127.851905)
			(xy 22.835924 -127.933172) (xy 22.851953 -128.016338) (xy 22.860004 -128.100652) (xy 22.860508 -128.143)
			(xy 22.860004 -128.185348) (xy 22.851953 -128.269662) (xy 22.835924 -128.352828) (xy 22.812063 -128.434095)
			(xy 22.780584 -128.512725) (xy 22.741773 -128.588006) (xy 22.695983 -128.659258) (xy 22.643627 -128.725834)
			(xy 22.585179 -128.787132) (xy 22.521169 -128.842597) (xy 22.452177 -128.891726) (xy 22.378827 -128.934075)
			(xy 22.301784 -128.969259) (xy 22.221745 -128.996961) (xy 22.139436 -129.016929) (xy 22.055601 -129.028982)
			(xy 21.971 -129.033013) (xy 21.886399 -129.028982) (xy 21.802564 -129.016929) (xy 21.720255 -128.996961)
			(xy 21.640216 -128.969259) (xy 21.563173 -128.934075) (xy 21.489823 -128.891726) (xy 21.420831 -128.842597)
			(xy 21.356821 -128.787132) (xy 21.298373 -128.725834) (xy 21.246017 -128.659258) (xy 21.200227 -128.588006)
			(xy 21.161416 -128.512725) (xy 21.129937 -128.434095) (xy 21.106076 -128.352828) (xy 21.090047 -128.269662)
			(xy 21.081996 -128.185348) (xy 20.828004 -128.185348) (xy 20.819953 -128.269662) (xy 20.803924 -128.352828)
			(xy 20.780063 -128.434095) (xy 20.748584 -128.512725) (xy 20.709773 -128.588006) (xy 20.663983 -128.659258)
			(xy 20.611627 -128.725834) (xy 20.553179 -128.787132) (xy 20.489169 -128.842597) (xy 20.420177 -128.891726)
			(xy 20.346827 -128.934075) (xy 20.269784 -128.969259) (xy 20.189745 -128.996961) (xy 20.107436 -129.016929)
			(xy 20.023601 -129.028982) (xy 19.939 -129.033013) (xy 19.854399 -129.028982) (xy 19.770564 -129.016929)
			(xy 19.688255 -128.996961) (xy 19.608216 -128.969259) (xy 19.531173 -128.934075) (xy 19.457823 -128.891726)
			(xy 19.388831 -128.842597) (xy 19.324821 -128.787132) (xy 19.266373 -128.725834) (xy 19.214017 -128.659258)
			(xy 19.168227 -128.588006) (xy 19.129416 -128.512725) (xy 19.097937 -128.434095) (xy 19.074076 -128.352828)
			(xy 19.058047 -128.269662) (xy 19.049996 -128.185348) (xy 15.240627 -128.185348) (xy 15.223337 -128.21784)
			(xy 15.175175 -128.290271) (xy 15.120172 -128.357655) (xy 15.089886 -128.388872) (xy 15.082774 -128.396238)
			(xy 15.075154 -128.414526) (xy 15.075154 -128.506474) (xy 15.082774 -128.524762) (xy 15.089886 -128.532128)
			(xy 15.120153 -128.563364) (xy 15.175164 -128.63074) (xy 15.223332 -128.703166) (xy 15.264197 -128.77995)
			(xy 15.297368 -128.860358) (xy 15.322528 -128.943621) (xy 15.339436 -129.028944) (xy 15.34793 -129.115509)
			(xy 15.348458 -129.159) (xy 15.348025 -129.199053) (xy 15.340814 -129.278834) (xy 15.32646 -129.357644)
			(xy 15.305079 -129.434845) (xy 15.276843 -129.50981) (xy 15.241983 -129.581933) (xy 15.20078 -129.650631)
			(xy 15.153567 -129.715346) (xy 15.127478 -129.74574) (xy 15.121799 -129.752865) (xy 15.11541 -129.769912)
			(xy 15.115032 -129.779014) (xy 15.115032 -129.808986) (xy 15.115427 -129.818087) (xy 15.1218 -129.835137)
			(xy 15.127478 -129.84226) (xy 15.15528 -129.874704) (xy 15.205226 -129.944035) (xy 15.248293 -130.017836)
			(xy 15.284085 -130.095426) (xy 15.312271 -130.176092) (xy 15.332591 -130.259088) (xy 15.344859 -130.343651)
			(xy 15.348961 -130.429) (xy 15.344859 -130.514349) (xy 15.332591 -130.598912) (xy 15.312271 -130.681908)
			(xy 15.284085 -130.762574) (xy 15.252834 -130.83032) (xy 18.065496 -130.83032) (xy 18.065971 -130.789217)
			(xy 18.073555 -130.707362) (xy 18.088658 -130.626555) (xy 18.111154 -130.547487) (xy 18.140849 -130.470832)
			(xy 18.17749 -130.397244) (xy 18.220765 -130.32735) (xy 18.270304 -130.261748) (xy 18.325685 -130.200997)
			(xy 18.386436 -130.145614) (xy 18.452037 -130.096074) (xy 18.52193 -130.052798) (xy 18.595517 -130.016155)
			(xy 18.672172 -129.986459) (xy 18.75124 -129.963962) (xy 18.832046 -129.948857) (xy 18.913901 -129.941272)
			(xy 18.955004 -129.940812) (xy 18.975545 -129.940931) (xy 19.016582 -129.942837) (xy 19.037046 -129.944622)
			(xy 19.048613 -129.945145) (xy 19.070261 -129.936999) (xy 19.086145 -129.920187) (xy 19.090132 -129.909316)
			(xy 19.103614 -129.868091) (xy 19.137451 -129.788222) (xy 19.178902 -129.712027) (xy 19.227573 -129.640229)
			(xy 19.283003 -129.57351) (xy 19.344666 -129.512505) (xy 19.411974 -129.457792) (xy 19.484289 -129.409891)
			(xy 19.560923 -129.369258) (xy 19.641149 -129.336278) (xy 19.724205 -129.311266) (xy 19.809301 -129.294457)
			(xy 19.89563 -129.286013) (xy 19.939 -129.285492) (xy 19.980102 -129.285967) (xy 20.061957 -129.293552)
			(xy 20.142762 -129.308657) (xy 20.221829 -129.331153) (xy 20.298483 -129.360849) (xy 20.37207 -129.397491)
			(xy 20.441962 -129.440766) (xy 20.507563 -129.490306) (xy 20.568313 -129.545687) (xy 20.623694 -129.606437)
			(xy 20.673234 -129.672038) (xy 20.716509 -129.74193) (xy 20.753151 -129.815517) (xy 20.782847 -129.892171)
			(xy 20.805343 -129.971238) (xy 20.820448 -130.052043) (xy 20.828033 -130.133898) (xy 20.828508 -130.175)
			(xy 20.828013 -130.217348) (xy 21.081996 -130.217348) (xy 21.081996 -130.132652) (xy 21.090047 -130.048338)
			(xy 21.106076 -129.965172) (xy 21.129937 -129.883905) (xy 21.161416 -129.805275) (xy 21.200227 -129.729994)
			(xy 21.246017 -129.658742) (xy 21.298373 -129.592166) (xy 21.356821 -129.530868) (xy 21.420831 -129.475403)
			(xy 21.489823 -129.426274) (xy 21.563173 -129.383925) (xy 21.640216 -129.348741) (xy 21.720255 -129.321039)
			(xy 21.802564 -129.301071) (xy 21.886399 -129.289018) (xy 21.971 -129.284988) (xy 22.055601 -129.289018)
			(xy 22.139436 -129.301071) (xy 22.221745 -129.321039) (xy 22.301784 -129.348741) (xy 22.378827 -129.383925)
			(xy 22.452177 -129.426274) (xy 22.521169 -129.475403) (xy 22.585179 -129.530868) (xy 22.643627 -129.592166)
			(xy 22.695983 -129.658742) (xy 22.741773 -129.729994) (xy 22.780584 -129.805275) (xy 22.812063 -129.883905)
			(xy 22.835924 -129.965172) (xy 22.851953 -130.048338) (xy 22.860004 -130.132652) (xy 22.860508 -130.175)
			(xy 22.860004 -130.217348) (xy 22.851953 -130.301662) (xy 22.835924 -130.384828) (xy 22.812063 -130.466095)
			(xy 22.780584 -130.544725) (xy 22.741773 -130.620006) (xy 22.695983 -130.691258) (xy 22.643627 -130.757834)
			(xy 22.585179 -130.819132) (xy 22.521169 -130.874597) (xy 22.452177 -130.923726) (xy 22.378827 -130.966075)
			(xy 22.301784 -131.001259) (xy 22.221745 -131.028961) (xy 22.139436 -131.048929) (xy 22.055601 -131.060982)
			(xy 21.971 -131.065013) (xy 21.886399 -131.060982) (xy 21.802564 -131.048929) (xy 21.720255 -131.028961)
			(xy 21.640216 -131.001259) (xy 21.563173 -130.966075) (xy 21.489823 -130.923726) (xy 21.420831 -130.874597)
			(xy 21.356821 -130.819132) (xy 21.298373 -130.757834) (xy 21.246017 -130.691258) (xy 21.200227 -130.620006)
			(xy 21.161416 -130.544725) (xy 21.129937 -130.466095) (xy 21.106076 -130.384828) (xy 21.090047 -130.301662)
			(xy 21.081996 -130.217348) (xy 20.828013 -130.217348) (xy 20.827999 -130.21856) (xy 20.819463 -130.30526)
			(xy 20.802493 -130.390712) (xy 20.777252 -130.474095) (xy 20.743981 -130.554611) (xy 20.702998 -130.631489)
			(xy 20.654697 -130.703994) (xy 20.59954 -130.771429) (xy 20.538055 -130.83315) (xy 20.470831 -130.888565)
			(xy 20.398513 -130.937144) (xy 20.321792 -130.97842) (xy 20.241403 -131.012) (xy 20.158118 -131.03756)
			(xy 20.11553 -131.046728) (xy 20.104354 -131.049014) (xy 20.08632 -131.062476) (xy 20.038314 -131.151122)
			(xy 20.037044 -131.173474) (xy 20.041362 -131.184142) (xy 20.056524 -131.223519) (xy 20.080209 -131.304511)
			(xy 20.096119 -131.387382) (xy 20.104111 -131.471388) (xy 20.104608 -131.51358) (xy 20.104085 -131.557432)
			(xy 20.095445 -131.64471) (xy 20.078256 -131.730714) (xy 20.052685 -131.814609) (xy 20.01898 -131.895579)
			(xy 19.99869 -131.934458) (xy 19.992086 -131.946904) (xy 19.993102 -131.974082) (xy 20.055586 -132.07238)
			(xy 20.079716 -132.084826) (xy 20.093686 -132.084064) (xy 20.140422 -132.082794) (xy 20.182346 -132.083299)
			(xy 20.265822 -132.091191) (xy 20.348184 -132.106905) (xy 20.428703 -132.1303) (xy 20.506662 -132.161168)
			(xy 20.58137 -132.199236) (xy 20.652165 -132.244165) (xy 20.718417 -132.295558) (xy 20.779538 -132.352957)
			(xy 20.834987 -132.415854) (xy 20.88427 -132.483689) (xy 20.926951 -132.555861) (xy 20.96265 -132.63173)
			(xy 20.991051 -132.710622) (xy 21.011902 -132.791836) (xy 21.018508 -132.833548) (xy 21.335996 -132.833548)
			(xy 21.335996 -132.748852) (xy 21.344047 -132.664538) (xy 21.360076 -132.581372) (xy 21.383937 -132.500105)
			(xy 21.415416 -132.421475) (xy 21.454227 -132.346194) (xy 21.500017 -132.274942) (xy 21.552373 -132.208366)
			(xy 21.610821 -132.147068) (xy 21.674831 -132.091603) (xy 21.743823 -132.042474) (xy 21.817173 -132.000125)
			(xy 21.894216 -131.964941) (xy 21.974255 -131.937239) (xy 22.056564 -131.917271) (xy 22.140399 -131.905218)
			(xy 22.225 -131.901188) (xy 22.309601 -131.905218) (xy 22.393436 -131.917271) (xy 22.475745 -131.937239)
			(xy 22.555784 -131.964941) (xy 22.632827 -132.000125) (xy 22.661189 -132.0165) (xy 23.564342 -132.0165)
			(xy 23.564901 -131.9727) (xy 23.573512 -131.885523) (xy 23.590651 -131.799615) (xy 23.616152 -131.715808)
			(xy 23.649767 -131.634913) (xy 23.691172 -131.557715) (xy 23.739965 -131.484961) (xy 23.795673 -131.417355)
			(xy 23.857757 -131.355553) (xy 23.925615 -131.300153) (xy 23.998591 -131.251692) (xy 24.075977 -131.210639)
			(xy 24.157023 -131.177392) (xy 24.198834 -131.16433) (xy 24.208486 -131.161536) (xy 24.223726 -131.14909)
			(xy 24.267922 -131.069842) (xy 24.270462 -131.050284) (xy 24.267922 -131.040632) (xy 24.258236 -131.002964)
			(xy 24.244684 -130.926373) (xy 24.237869 -130.848891) (xy 24.237442 -130.81) (xy 24.237885 -130.771712)
			(xy 24.244504 -130.695422) (xy 24.257649 -130.619982) (xy 24.277223 -130.54595) (xy 24.289766 -130.509772)
			(xy 24.292409 -130.501334) (xy 24.292409 -130.483666) (xy 24.289766 -130.475228) (xy 24.277207 -130.439054)
			(xy 24.257612 -130.365025) (xy 24.244461 -130.289583) (xy 24.237853 -130.213289) (xy 24.237442 -130.175)
			(xy 24.237988 -130.130963) (xy 24.246703 -130.043321) (xy 24.264037 -129.95697) (xy 24.289821 -129.872755)
			(xy 24.323803 -129.791501) (xy 24.365649 -129.714003) (xy 24.41495 -129.641021) (xy 24.442674 -129.606802)
			(xy 24.449532 -129.59842) (xy 24.455374 -129.577338) (xy 24.440388 -129.480818) (xy 24.428704 -129.46253)
			(xy 24.41956 -129.456688) (xy 24.385904 -129.434455) (xy 24.32239 -129.384723) (xy 24.263638 -129.329446)
			(xy 24.210132 -129.269077) (xy 24.16231 -129.204112) (xy 24.120565 -129.135085) (xy 24.085241 -129.062562)
			(xy 24.056626 -128.98714) (xy 24.034956 -128.909437) (xy 24.02041 -128.830091) (xy 24.013106 -128.749754)
			(xy 24.012652 -128.70942) (xy 24.013237 -128.663024) (xy 24.022881 -128.570736) (xy 24.042076 -128.479952)
			(xy 24.070614 -128.391659) (xy 24.088852 -128.348994) (xy 24.092257 -128.340374) (xy 24.093285 -128.321879)
			(xy 24.090884 -128.312926) (xy 24.08174 -128.284478) (xy 24.078517 -128.275781) (xy 24.066919 -128.261326)
			(xy 24.059134 -128.256284) (xy 24.023251 -128.23454) (xy 23.955354 -128.185238) (xy 23.8924 -128.129763)
			(xy 23.834948 -128.068608) (xy 23.783507 -128.002317) (xy 23.738534 -127.931478) (xy 23.70043 -127.85672)
			(xy 23.669532 -127.778707) (xy 23.646115 -127.698132) (xy 23.630386 -127.61571) (xy 23.622485 -127.532174)
			(xy 23.622 -127.49022) (xy 23.622504 -127.447872) (xy 23.630555 -127.363558) (xy 23.646584 -127.280392)
			(xy 23.670445 -127.199125) (xy 23.701924 -127.120495) (xy 23.740735 -127.045214) (xy 23.786525 -126.973962)
			(xy 23.838881 -126.907386) (xy 23.897329 -126.846088) (xy 23.961339 -126.790623) (xy 24.030331 -126.741494)
			(xy 24.103681 -126.699145) (xy 24.180724 -126.663961) (xy 24.260763 -126.636259) (xy 24.343072 -126.616291)
			(xy 24.426907 -126.604238) (xy 24.511508 -126.600208) (xy 24.596109 -126.604238) (xy 24.679944 -126.616291)
			(xy 24.762253 -126.636259) (xy 24.842292 -126.663961) (xy 24.919335 -126.699145) (xy 24.992685 -126.741494)
			(xy 25.061677 -126.790623) (xy 25.125687 -126.846088) (xy 25.184135 -126.907386) (xy 25.236491 -126.973962)
			(xy 25.282281 -127.045214) (xy 25.321092 -127.120495) (xy 25.352571 -127.199125) (xy 25.376432 -127.280392)
			(xy 25.392461 -127.363558) (xy 25.400512 -127.447872) (xy 25.401016 -127.49022) (xy 25.400404 -127.536615)
			(xy 25.390768 -127.628902) (xy 25.37158 -127.719686) (xy 25.34305 -127.80798) (xy 25.324816 -127.850646)
			(xy 25.321441 -127.859276) (xy 25.320395 -127.877762) (xy 25.322784 -127.886714) (xy 25.331928 -127.915162)
			(xy 25.335147 -127.92386) (xy 25.346748 -127.938314) (xy 25.354534 -127.943356) (xy 25.390427 -127.965084)
			(xy 25.458325 -128.014387) (xy 25.52128 -128.069863) (xy 25.578733 -128.131019) (xy 25.630174 -128.197312)
			(xy 25.675146 -128.268153) (xy 25.713249 -128.342912) (xy 25.744146 -128.420927) (xy 25.767561 -128.501504)
			(xy 25.783287 -128.583927) (xy 25.791184 -128.667465) (xy 25.791668 -128.70942) (xy 25.791155 -128.753458)
			(xy 25.782437 -128.841101) (xy 25.765099 -128.927454) (xy 25.73931 -129.011669) (xy 25.705323 -129.092923)
			(xy 25.66347 -129.17042) (xy 25.614163 -129.2434) (xy 25.586436 -129.277618) (xy 25.579578 -129.286)
			(xy 25.573736 -129.307082) (xy 25.588722 -129.403602) (xy 25.600406 -129.42189) (xy 25.60955 -129.427732)
			(xy 25.643171 -129.450015) (xy 25.706685 -129.499742) (xy 25.765437 -129.555015) (xy 25.818945 -129.615379)
			(xy 25.866769 -129.680338) (xy 25.908516 -129.74936) (xy 25.943844 -129.821877) (xy 25.972463 -129.897295)
			(xy 25.994138 -129.974993) (xy 26.00869 -130.054335) (xy 26.016001 -130.134668) (xy 26.016458 -130.175)
			(xy 26.016015 -130.213288) (xy 26.009396 -130.289578) (xy 25.996251 -130.365018) (xy 25.976677 -130.43905)
			(xy 25.964134 -130.475228) (xy 25.961491 -130.483666) (xy 25.961491 -130.501334) (xy 25.964134 -130.509772)
			(xy 25.976693 -130.545946) (xy 25.996288 -130.619975) (xy 26.009439 -130.695417) (xy 26.016047 -130.771711)
			(xy 26.016458 -130.81) (xy 26.015899 -130.8538) (xy 26.007288 -130.940977) (xy 25.990149 -131.026885)
			(xy 25.964648 -131.110692) (xy 25.931033 -131.191587) (xy 25.908635 -131.233348) (xy 35.051996 -131.233348)
			(xy 35.051996 -131.148652) (xy 35.060047 -131.064338) (xy 35.076076 -130.981172) (xy 35.099937 -130.899905)
			(xy 35.131416 -130.821275) (xy 35.170227 -130.745994) (xy 35.216017 -130.674742) (xy 35.268373 -130.608166)
			(xy 35.326821 -130.546868) (xy 35.390831 -130.491403) (xy 35.459823 -130.442274) (xy 35.533173 -130.399925)
			(xy 35.610216 -130.364741) (xy 35.690255 -130.337039) (xy 35.772564 -130.317071) (xy 35.856399 -130.305018)
			(xy 35.941 -130.300988) (xy 36.025601 -130.305018) (xy 36.109436 -130.317071) (xy 36.191745 -130.337039)
			(xy 36.271784 -130.364741) (xy 36.348827 -130.399925) (xy 36.422177 -130.442274) (xy 36.491169 -130.491403)
			(xy 36.555179 -130.546868) (xy 36.613627 -130.608166) (xy 36.665983 -130.674742) (xy 36.711773 -130.745994)
			(xy 36.750584 -130.821275) (xy 36.782063 -130.899905) (xy 36.805924 -130.981172) (xy 36.821953 -131.064338)
			(xy 36.830004 -131.148652) (xy 36.830508 -131.191) (xy 36.830004 -131.233348) (xy 36.821953 -131.317662)
			(xy 36.805924 -131.400828) (xy 36.782063 -131.482095) (xy 36.750584 -131.560725) (xy 36.711773 -131.636006)
			(xy 36.665983 -131.707258) (xy 36.613627 -131.773834) (xy 36.555179 -131.835132) (xy 36.491169 -131.890597)
			(xy 36.422177 -131.939726) (xy 36.348827 -131.982075) (xy 36.271784 -132.017259) (xy 36.191745 -132.044961)
			(xy 36.109436 -132.064929) (xy 36.025601 -132.076982) (xy 35.941 -132.081013) (xy 35.856399 -132.076982)
			(xy 35.772564 -132.064929) (xy 35.690255 -132.044961) (xy 35.610216 -132.017259) (xy 35.533173 -131.982075)
			(xy 35.459823 -131.939726) (xy 35.390831 -131.890597) (xy 35.326821 -131.835132) (xy 35.268373 -131.773834)
			(xy 35.216017 -131.707258) (xy 35.170227 -131.636006) (xy 35.131416 -131.560725) (xy 35.099937 -131.482095)
			(xy 35.076076 -131.400828) (xy 35.060047 -131.317662) (xy 35.051996 -131.233348) (xy 25.908635 -131.233348)
			(xy 25.889628 -131.268785) (xy 25.840835 -131.341539) (xy 25.785127 -131.409145) (xy 25.723043 -131.470947)
			(xy 25.655185 -131.526347) (xy 25.582209 -131.574808) (xy 25.504823 -131.615861) (xy 25.423777 -131.649108)
			(xy 25.381966 -131.66217) (xy 25.372314 -131.664964) (xy 25.357074 -131.67741) (xy 25.312878 -131.756658)
			(xy 25.310338 -131.776216) (xy 25.312878 -131.785868) (xy 25.322564 -131.823536) (xy 25.336116 -131.900127)
			(xy 25.342931 -131.977609) (xy 25.343358 -132.0165) (xy 25.342998 -132.052991) (xy 25.337019 -132.125727)
			(xy 25.33142 -132.161788) (xy 25.33033 -132.170962) (xy 25.333972 -132.18906) (xy 25.338532 -132.197094)
			(xy 25.35428 -132.22224) (xy 25.359449 -132.229852) (xy 25.374043 -132.24104) (xy 25.382728 -132.244084)
			(xy 25.424496 -132.257181) (xy 25.505462 -132.290465) (xy 25.582766 -132.331541) (xy 25.655662 -132.380013)
			(xy 25.723443 -132.435412) (xy 25.785453 -132.497201) (xy 25.841094 -132.564784) (xy 25.889826 -132.637506)
			(xy 25.931178 -132.714663) (xy 25.96475 -132.795509) (xy 25.978887 -132.842) (xy 27.939492 -132.842)
			(xy 27.939996 -132.799652) (xy 27.948047 -132.715338) (xy 27.964076 -132.632172) (xy 27.987937 -132.550905)
			(xy 28.019416 -132.472275) (xy 28.058227 -132.396994) (xy 28.104017 -132.325742) (xy 28.156373 -132.259166)
			(xy 28.214821 -132.197868) (xy 28.278831 -132.142403) (xy 28.347823 -132.093274) (xy 28.421173 -132.050925)
			(xy 28.498216 -132.015741) (xy 28.578255 -131.988039) (xy 28.660564 -131.968071) (xy 28.744399 -131.956018)
			(xy 28.829 -131.951988) (xy 28.913601 -131.956018) (xy 28.997436 -131.968071) (xy 29.079745 -131.988039)
			(xy 29.159784 -132.015741) (xy 29.236827 -132.050925) (xy 29.310177 -132.093274) (xy 29.379169 -132.142403)
			(xy 29.443179 -132.197868) (xy 29.501627 -132.259166) (xy 29.553983 -132.325742) (xy 29.599773 -132.396994)
			(xy 29.638584 -132.472275) (xy 29.670063 -132.550905) (xy 29.693924 -132.632172) (xy 29.709953 -132.715338)
			(xy 29.718004 -132.799652) (xy 29.718508 -132.842) (xy 29.718046 -132.882899) (xy 29.710539 -132.964353)
			(xy 29.695589 -133.044774) (xy 29.673321 -133.123483) (xy 29.643924 -133.199817) (xy 29.607646 -133.27313)
			(xy 29.564793 -133.342806) (xy 29.515726 -133.408254) (xy 29.488638 -133.4389) (xy 29.479614 -133.449629)
			(xy 29.467201 -133.474751) (xy 29.462084 -133.502302) (xy 29.464647 -133.530206) (xy 29.474698 -133.556363)
			(xy 29.49148 -133.578803) (xy 29.513729 -133.595838) (xy 29.539771 -133.606184) (xy 29.553662 -133.608064)
			(xy 29.59697 -133.61303) (xy 29.682428 -133.630252) (xy 29.76579 -133.655752) (xy 29.846258 -133.689286)
			(xy 29.923059 -133.730532) (xy 29.995456 -133.779094) (xy 30.062754 -133.834506) (xy 30.124308 -133.896237)
			(xy 30.179527 -133.963694) (xy 30.227882 -134.03623) (xy 30.268907 -134.113149) (xy 30.30221 -134.193713)
			(xy 30.327471 -134.277148) (xy 30.344447 -134.362655) (xy 30.352976 -134.449412) (xy 30.353508 -134.493)
			(xy 30.353004 -134.535348) (xy 30.344953 -134.619662) (xy 30.328924 -134.702828) (xy 30.305063 -134.784095)
			(xy 30.273584 -134.862725) (xy 30.234773 -134.938006) (xy 30.188983 -135.009258) (xy 30.136627 -135.075834)
			(xy 30.078179 -135.137132) (xy 30.014169 -135.192597) (xy 29.945177 -135.241726) (xy 29.871827 -135.284075)
			(xy 29.794784 -135.319259) (xy 29.714745 -135.346961) (xy 29.632436 -135.366929) (xy 29.548601 -135.378982)
			(xy 29.464 -135.383013) (xy 29.379399 -135.378982) (xy 29.295564 -135.366929) (xy 29.213255 -135.346961)
			(xy 29.133216 -135.319259) (xy 29.056173 -135.284075) (xy 28.982823 -135.241726) (xy 28.913831 -135.192597)
			(xy 28.849821 -135.137132) (xy 28.791373 -135.075834) (xy 28.739017 -135.009258) (xy 28.693227 -134.938006)
			(xy 28.654416 -134.862725) (xy 28.622937 -134.784095) (xy 28.599076 -134.702828) (xy 28.583047 -134.619662)
			(xy 28.574996 -134.535348) (xy 28.574492 -134.493) (xy 28.574954 -134.452101) (xy 28.582461 -134.370647)
			(xy 28.597411 -134.290226) (xy 28.619679 -134.211517) (xy 28.649076 -134.135183) (xy 28.685354 -134.06187)
			(xy 28.728207 -133.992194) (xy 28.777274 -133.926746) (xy 28.804362 -133.8961) (xy 28.813386 -133.885371)
			(xy 28.825799 -133.860249) (xy 28.830916 -133.832698) (xy 28.828353 -133.804794) (xy 28.818302 -133.778637)
			(xy 28.80152 -133.756197) (xy 28.779271 -133.739162) (xy 28.753229 -133.728816) (xy 28.739338 -133.726936)
			(xy 28.69603 -133.72197) (xy 28.610572 -133.704748) (xy 28.52721 -133.679248) (xy 28.446742 -133.645714)
			(xy 28.369941 -133.604468) (xy 28.297544 -133.555906) (xy 28.230246 -133.500494) (xy 28.168692 -133.438763)
			(xy 28.113473 -133.371306) (xy 28.065118 -133.29877) (xy 28.024093 -133.221851) (xy 27.99079 -133.141287)
			(xy 27.965529 -133.057852) (xy 27.948553 -132.972345) (xy 27.940024 -132.885588) (xy 27.939492 -132.842)
			(xy 25.978887 -132.842) (xy 25.990218 -132.879263) (xy 26.007335 -132.965113) (xy 26.015935 -133.05223)
			(xy 26.016458 -133.096) (xy 26.015954 -133.138348) (xy 26.007903 -133.222662) (xy 25.991874 -133.305828)
			(xy 25.968013 -133.387095) (xy 25.936534 -133.465725) (xy 25.897723 -133.541006) (xy 25.851933 -133.612258)
			(xy 25.799577 -133.678834) (xy 25.741129 -133.740132) (xy 25.677119 -133.795597) (xy 25.608127 -133.844726)
			(xy 25.534777 -133.887075) (xy 25.457734 -133.922259) (xy 25.377695 -133.949961) (xy 25.295386 -133.969929)
			(xy 25.211551 -133.981982) (xy 25.12695 -133.986013) (xy 25.042349 -133.981982) (xy 24.958514 -133.969929)
			(xy 24.876205 -133.949961) (xy 24.796166 -133.922259) (xy 24.719123 -133.887075) (xy 24.645773 -133.844726)
			(xy 24.576781 -133.795597) (xy 24.512771 -133.740132) (xy 24.454323 -133.678834) (xy 24.401967 -133.612258)
			(xy 24.356177 -133.541006) (xy 24.317366 -133.465725) (xy 24.285887 -133.387095) (xy 24.262026 -133.305828)
			(xy 24.245997 -133.222662) (xy 24.237946 -133.138348) (xy 24.237442 -133.096) (xy 24.237802 -133.059509)
			(xy 24.243781 -132.986773) (xy 24.24938 -132.950712) (xy 24.25047 -132.941538) (xy 24.246828 -132.92344)
			(xy 24.242268 -132.915406) (xy 24.22652 -132.89026) (xy 24.221351 -132.882648) (xy 24.206757 -132.87146)
			(xy 24.198072 -132.868416) (xy 24.156304 -132.855319) (xy 24.075338 -132.822035) (xy 23.998034 -132.780959)
			(xy 23.925138 -132.732487) (xy 23.857357 -132.677088) (xy 23.795347 -132.615299) (xy 23.739706 -132.547716)
			(xy 23.690974 -132.474994) (xy 23.649622 -132.397837) (xy 23.61605 -132.316991) (xy 23.590582 -132.233237)
			(xy 23.573465 -132.147387) (xy 23.564865 -132.06027) (xy 23.564342 -132.0165) (xy 22.661189 -132.0165)
			(xy 22.706177 -132.042474) (xy 22.775169 -132.091603) (xy 22.839179 -132.147068) (xy 22.897627 -132.208366)
			(xy 22.949983 -132.274942) (xy 22.995773 -132.346194) (xy 23.034584 -132.421475) (xy 23.066063 -132.500105)
			(xy 23.089924 -132.581372) (xy 23.105953 -132.664538) (xy 23.114004 -132.748852) (xy 23.114508 -132.7912)
			(xy 23.114004 -132.833548) (xy 23.105953 -132.917862) (xy 23.089924 -133.001028) (xy 23.066063 -133.082295)
			(xy 23.034584 -133.160925) (xy 22.995773 -133.236206) (xy 22.949983 -133.307458) (xy 22.897627 -133.374034)
			(xy 22.839179 -133.435332) (xy 22.775169 -133.490797) (xy 22.706177 -133.539926) (xy 22.632827 -133.582275)
			(xy 22.555784 -133.617459) (xy 22.475745 -133.645161) (xy 22.393436 -133.665129) (xy 22.309601 -133.677182)
			(xy 22.225 -133.681213) (xy 22.140399 -133.677182) (xy 22.056564 -133.665129) (xy 21.974255 -133.645161)
			(xy 21.894216 -133.617459) (xy 21.817173 -133.582275) (xy 21.743823 -133.539926) (xy 21.674831 -133.490797)
			(xy 21.610821 -133.435332) (xy 21.552373 -133.374034) (xy 21.500017 -133.307458) (xy 21.454227 -133.236206)
			(xy 21.415416 -133.160925) (xy 21.383937 -133.082295) (xy 21.360076 -133.001028) (xy 21.344047 -132.917862)
			(xy 21.335996 -132.833548) (xy 21.018508 -132.833548) (xy 21.025017 -132.874652) (xy 21.030281 -132.958335)
			(xy 21.027646 -133.042141) (xy 21.017136 -133.125328) (xy 20.998844 -133.207157) (xy 20.972932 -133.286901)
			(xy 20.939631 -133.363852) (xy 20.899236 -133.437328) (xy 20.852105 -133.506677) (xy 20.798658 -133.571282)
			(xy 20.739368 -133.630571) (xy 20.674761 -133.684017) (xy 20.605411 -133.731146) (xy 20.531934 -133.77154)
			(xy 20.454982 -133.804839) (xy 20.375237 -133.830749) (xy 20.293408 -133.849039) (xy 20.210221 -133.859547)
			(xy 20.126415 -133.862181) (xy 20.042732 -133.856915) (xy 19.959916 -133.843798) (xy 19.878703 -133.822945)
			(xy 19.799812 -133.794542) (xy 19.723944 -133.758841) (xy 19.651772 -133.716159) (xy 19.583938 -133.666874)
			(xy 19.521043 -133.611424) (xy 19.463645 -133.550301) (xy 19.412254 -133.484048) (xy 19.367326 -133.413253)
			(xy 19.32926 -133.338544) (xy 19.298393 -133.260584) (xy 19.275 -133.180065) (xy 19.259289 -133.097702)
			(xy 19.251398 -133.014226) (xy 19.250914 -132.972302) (xy 19.251426 -132.928449) (xy 19.260069 -132.841171)
			(xy 19.27726 -132.755167) (xy 19.302834 -132.671273) (xy 19.33654 -132.590303) (xy 19.356832 -132.551424)
			(xy 19.363436 -132.538978) (xy 19.36242 -132.5118) (xy 19.299936 -132.413502) (xy 19.275806 -132.401056)
			(xy 19.261836 -132.401818) (xy 19.2151 -132.403088) (xy 19.173996 -132.402648) (xy 19.092139 -132.395063)
			(xy 19.011332 -132.379957) (xy 18.932263 -132.357459) (xy 18.855606 -132.327762) (xy 18.782018 -132.291119)
			(xy 18.712124 -132.247841) (xy 18.646521 -132.1983) (xy 18.58577 -132.142916) (xy 18.530388 -132.082163)
			(xy 18.480847 -132.01656) (xy 18.437572 -131.946665) (xy 18.40093 -131.873075) (xy 18.371234 -131.796419)
			(xy 18.348739 -131.717349) (xy 18.333635 -131.636541) (xy 18.326051 -131.554684) (xy 18.325592 -131.51358)
			(xy 18.3261 -131.482084) (xy 18.326026 -131.471854) (xy 18.318836 -131.452723) (xy 18.31213 -131.445)
			(xy 18.283169 -131.413994) (xy 18.230627 -131.347369) (xy 18.18467 -131.276043) (xy 18.145716 -131.200664)
			(xy 18.114118 -131.121917) (xy 18.090164 -131.040519) (xy 18.074072 -130.957209) (xy 18.065989 -130.872745)
			(xy 18.065496 -130.83032) (xy 15.252834 -130.83032) (xy 15.248293 -130.840164) (xy 15.205226 -130.913965)
			(xy 15.15528 -130.983296) (xy 15.127478 -131.01574) (xy 15.121799 -131.022865) (xy 15.11541 -131.039912)
			(xy 15.115032 -131.049014) (xy 15.115032 -131.078986) (xy 15.115427 -131.088087) (xy 15.1218 -131.105137)
			(xy 15.127478 -131.11226) (xy 15.15528 -131.144704) (xy 15.205226 -131.214035) (xy 15.248293 -131.287836)
			(xy 15.284085 -131.365426) (xy 15.312271 -131.446092) (xy 15.332591 -131.529088) (xy 15.344859 -131.613651)
			(xy 15.348961 -131.699) (xy 15.344859 -131.784349) (xy 15.332591 -131.868912) (xy 15.312271 -131.951908)
			(xy 15.284085 -132.032574) (xy 15.248293 -132.110164) (xy 15.205226 -132.183965) (xy 15.15528 -132.253296)
			(xy 15.127478 -132.28574) (xy 15.121799 -132.292865) (xy 15.11541 -132.309912) (xy 15.115032 -132.319014)
			(xy 15.115032 -132.348986) (xy 15.115427 -132.358087) (xy 15.1218 -132.375137) (xy 15.127478 -132.38226)
			(xy 15.153556 -132.412664) (xy 15.200775 -132.477374) (xy 15.241984 -132.546068) (xy 15.276847 -132.618189)
			(xy 15.305083 -132.693154) (xy 15.326463 -132.770355) (xy 15.340813 -132.849165) (xy 15.348018 -132.928947)
			(xy 15.348458 -132.969) (xy 15.348025 -133.009053) (xy 15.340814 -133.088834) (xy 15.32646 -133.167644)
			(xy 15.305079 -133.244845) (xy 15.276843 -133.31981) (xy 15.241983 -133.391933) (xy 15.20078 -133.460631)
			(xy 15.153567 -133.525346) (xy 15.127478 -133.55574) (xy 15.121799 -133.562865) (xy 15.11541 -133.579912)
			(xy 15.115032 -133.589014) (xy 15.115032 -133.618986) (xy 15.115427 -133.628087) (xy 15.1218 -133.645137)
			(xy 15.127478 -133.65226) (xy 15.15528 -133.684704) (xy 15.205226 -133.754035) (xy 15.248293 -133.827836)
			(xy 15.284085 -133.905426) (xy 15.312271 -133.986092) (xy 15.332591 -134.069088) (xy 15.344859 -134.153651)
			(xy 15.348961 -134.239) (xy 15.344859 -134.324349) (xy 15.332591 -134.408912) (xy 15.312271 -134.491908)
			(xy 15.284085 -134.572574) (xy 15.248293 -134.650164) (xy 15.205226 -134.723965) (xy 15.15528 -134.793296)
			(xy 15.127478 -134.82574) (xy 15.121799 -134.832865) (xy 15.11541 -134.849912) (xy 15.115032 -134.859014)
			(xy 15.115032 -134.888986) (xy 15.115427 -134.898087) (xy 15.1218 -134.915137) (xy 15.127478 -134.92226)
			(xy 15.153556 -134.952664) (xy 15.200775 -135.017374) (xy 15.241984 -135.086068) (xy 15.276847 -135.158189)
			(xy 15.305083 -135.233154) (xy 15.326463 -135.310355) (xy 15.340813 -135.389165) (xy 15.346245 -135.44931)
			(xy 16.470122 -135.44931) (xy 16.470626 -135.406962) (xy 16.478677 -135.322648) (xy 16.494706 -135.239482)
			(xy 16.518567 -135.158215) (xy 16.550046 -135.079585) (xy 16.588857 -135.004304) (xy 16.634647 -134.933052)
			(xy 16.687003 -134.866476) (xy 16.745451 -134.805178) (xy 16.809461 -134.749713) (xy 16.878453 -134.700584)
			(xy 16.951803 -134.658235) (xy 17.028846 -134.623051) (xy 17.108885 -134.595349) (xy 17.191194 -134.575381)
			(xy 17.275029 -134.563328) (xy 17.35963 -134.559298) (xy 17.444231 -134.563328) (xy 17.528066 -134.575381)
			(xy 17.610375 -134.595349) (xy 17.690414 -134.623051) (xy 17.767457 -134.658235) (xy 17.840807 -134.700584)
			(xy 17.909799 -134.749713) (xy 17.973809 -134.805178) (xy 18.032257 -134.866476) (xy 18.084613 -134.933052)
			(xy 18.12436 -134.9949) (xy 18.540992 -134.9949) (xy 18.545022 -134.910299) (xy 18.557075 -134.826465)
			(xy 18.577043 -134.744156) (xy 18.604745 -134.664117) (xy 18.639929 -134.587075) (xy 18.682277 -134.513725)
			(xy 18.731406 -134.444733) (xy 18.786871 -134.380724) (xy 18.848168 -134.322276) (xy 18.914744 -134.26992)
			(xy 18.985996 -134.22413) (xy 19.061277 -134.18532) (xy 19.139907 -134.153841) (xy 19.221173 -134.129979)
			(xy 19.304339 -134.113951) (xy 19.388652 -134.1059) (xy 19.431 -134.105396) (xy 19.474491 -134.105926)
			(xy 19.561056 -134.114427) (xy 19.646377 -134.131338) (xy 19.72964 -134.156497) (xy 19.81005 -134.189665)
			(xy 19.886837 -134.230523) (xy 19.959269 -134.278683) (xy 20.026654 -134.333684) (xy 20.057872 -134.363968)
			(xy 20.065238 -134.37108) (xy 20.083526 -134.3787) (xy 20.175474 -134.3787) (xy 20.193762 -134.37108)
			(xy 20.201128 -134.363968) (xy 20.232355 -134.333692) (xy 20.299733 -134.278683) (xy 20.372162 -134.230517)
			(xy 20.448947 -134.189653) (xy 20.529356 -134.156484) (xy 20.61262 -134.131325) (xy 20.697943 -134.114418)
			(xy 20.784509 -134.105924) (xy 20.828 -134.105396) (xy 20.869366 -134.105858) (xy 20.951742 -134.113533)
			(xy 21.033049 -134.128826) (xy 21.112584 -134.151604) (xy 21.18966 -134.181671) (xy 21.26361 -134.218766)
			(xy 21.333795 -134.26257) (xy 21.366988 -134.28726) (xy 21.375176 -134.292946) (xy 21.394388 -134.298186)
			(xy 21.404326 -134.29742) (xy 21.433023 -134.29387) (xy 21.490727 -134.290056) (xy 21.519642 -134.2898)
			(xy 21.55131 -134.290052) (xy 21.614489 -134.2945) (xy 21.64588 -134.29869) (xy 21.655989 -134.299683)
			(xy 21.675632 -134.294571) (xy 21.68398 -134.288784) (xy 21.717259 -134.263907) (xy 21.78765 -134.219749)
			(xy 21.861851 -134.182347) (xy 21.939216 -134.152027) (xy 22.019071 -134.129053) (xy 22.10072 -134.113624)
			(xy 22.183453 -134.105877) (xy 22.225 -134.105396) (xy 22.268491 -134.105926) (xy 22.355056 -134.114427)
			(xy 22.440377 -134.131338) (xy 22.52364 -134.156497) (xy 22.60405 -134.189665) (xy 22.680837 -134.230523)
			(xy 22.753269 -134.278683) (xy 22.820654 -134.333684) (xy 22.851872 -134.363968) (xy 22.859238 -134.37108)
			(xy 22.877526 -134.3787) (xy 22.969474 -134.3787) (xy 22.987762 -134.37108) (xy 22.995128 -134.363968)
			(xy 23.026355 -134.333692) (xy 23.093733 -134.278683) (xy 23.166162 -134.230517) (xy 23.242947 -134.189653)
			(xy 23.323356 -134.156484) (xy 23.40662 -134.131325) (xy 23.491943 -134.114418) (xy 23.578509 -134.105924)
			(xy 23.622 -134.105396) (xy 23.665638 -134.105915) (xy 23.752495 -134.114463) (xy 23.838097 -134.131476)
			(xy 23.921621 -134.156791) (xy 24.002264 -134.190165) (xy 24.079251 -134.231277) (xy 24.151841 -134.279731)
			(xy 24.219337 -134.335061) (xy 24.281089 -134.396736) (xy 24.336504 -134.464162) (xy 24.385049 -134.536692)
			(xy 24.426257 -134.613627) (xy 24.459732 -134.694228) (xy 24.485152 -134.77772) (xy 24.494236 -134.820406)
			(xy 24.496776 -134.833106) (xy 24.51227 -134.852156) (xy 24.613108 -134.895082) (xy 24.637746 -134.89305)
			(xy 24.648414 -134.886192) (xy 24.684169 -134.863933) (xy 24.759137 -134.825533) (xy 24.8374 -134.794393)
			(xy 24.918256 -134.770792) (xy 25.000981 -134.754941) (xy 25.084835 -134.746982) (xy 25.12695 -134.746492)
			(xy 25.166049 -134.746925) (xy 25.243944 -134.753812) (xy 25.320935 -134.767503) (xy 25.396429 -134.787893)
			(xy 25.469845 -134.814824) (xy 25.50541 -134.831074) (xy 25.515797 -134.835309) (xy 25.538203 -134.835309)
			(xy 25.54859 -134.831074) (xy 25.584143 -134.814794) (xy 25.657555 -134.787844) (xy 25.733051 -134.76745)
			(xy 25.810048 -134.75377) (xy 25.887949 -134.74691) (xy 25.92705 -134.746492) (xy 25.969398 -134.746996)
			(xy 26.053712 -134.755047) (xy 26.136878 -134.771076) (xy 26.218145 -134.794937) (xy 26.296775 -134.826416)
			(xy 26.372056 -134.865227) (xy 26.443308 -134.911017) (xy 26.509884 -134.963373) (xy 26.571182 -135.021821)
			(xy 26.626647 -135.085831) (xy 26.675776 -135.154823) (xy 26.718125 -135.228173) (xy 26.753309 -135.305216)
			(xy 26.781011 -135.385255) (xy 26.800979 -135.467564) (xy 26.813032 -135.551399) (xy 26.817063 -135.636)
			(xy 26.813032 -135.720601) (xy 26.800979 -135.804436) (xy 26.781011 -135.886745) (xy 26.753309 -135.966784)
			(xy 26.718125 -136.043827) (xy 26.675776 -136.117177) (xy 26.626647 -136.186169) (xy 26.571182 -136.250179)
			(xy 26.509884 -136.308627) (xy 26.443308 -136.360983) (xy 26.372056 -136.406773) (xy 26.296775 -136.445584)
			(xy 26.218145 -136.477063) (xy 26.136878 -136.500924) (xy 26.053712 -136.516953) (xy 25.969398 -136.525004)
			(xy 25.92705 -136.525508) (xy 25.887951 -136.525075) (xy 25.810056 -136.518188) (xy 25.733065 -136.504497)
			(xy 25.657571 -136.484107) (xy 25.584155 -136.457176) (xy 25.54859 -136.440926) (xy 25.538203 -136.436691)
			(xy 25.515797 -136.436691) (xy 25.50541 -136.440926) (xy 25.469857 -136.457206) (xy 25.396445 -136.484156)
			(xy 25.320949 -136.50455) (xy 25.243952 -136.51823) (xy 25.166051 -136.52509) (xy 25.12695 -136.525508)
			(xy 25.083313 -136.524939) (xy 24.996458 -136.516396) (xy 24.910857 -136.499388) (xy 24.827334 -136.474077)
			(xy 24.746691 -136.440707) (xy 24.669705 -136.3996) (xy 24.597114 -136.35115) (xy 24.529618 -136.295824)
			(xy 24.467865 -136.234152) (xy 24.41245 -136.166729) (xy 24.363904 -136.094203) (xy 24.322695 -136.017271)
			(xy 24.289219 -135.936672) (xy 24.263798 -135.853182) (xy 24.254714 -135.810498) (xy 24.252174 -135.797798)
			(xy 24.23668 -135.778748) (xy 24.135842 -135.735822) (xy 24.111204 -135.737854) (xy 24.100536 -135.744712)
			(xy 24.064768 -135.766951) (xy 23.989803 -135.805353) (xy 23.911543 -135.836496) (xy 23.830689 -135.860101)
			(xy 23.747966 -135.875956) (xy 23.664114 -135.883919) (xy 23.622 -135.884412) (xy 23.578509 -135.88388)
			(xy 23.491945 -135.875379) (xy 23.406623 -135.858468) (xy 23.32336 -135.833309) (xy 23.242951 -135.800142)
			(xy 23.166163 -135.759284) (xy 23.093731 -135.711124) (xy 23.026346 -135.656124) (xy 22.995128 -135.62584)
			(xy 22.987762 -135.618728) (xy 22.969474 -135.611108) (xy 22.877526 -135.611108) (xy 22.859238 -135.618728)
			(xy 22.851872 -135.62584) (xy 22.820646 -135.656117) (xy 22.753268 -135.711126) (xy 22.680839 -135.759292)
			(xy 22.604053 -135.800155) (xy 22.523644 -135.833325) (xy 22.44038 -135.858483) (xy 22.355057 -135.87539)
			(xy 22.268491 -135.883884) (xy 22.225 -135.884412) (xy 22.193332 -135.884166) (xy 22.130153 -135.879714)
			(xy 22.098762 -135.875522) (xy 22.088653 -135.87455) (xy 22.069011 -135.879648) (xy 22.060662 -135.885428)
			(xy 22.027403 -135.910334) (xy 21.957009 -135.954488) (xy 21.882804 -135.991886) (xy 21.805435 -136.022202)
			(xy 21.725577 -136.045172) (xy 21.643925 -136.060595) (xy 21.56119 -136.068338) (xy 21.519642 -136.068816)
			(xy 21.478276 -136.068328) (xy 21.395901 -136.060657) (xy 21.314595 -136.045368) (xy 21.23506 -136.022594)
			(xy 21.157984 -135.992532) (xy 21.084034 -135.95544) (xy 21.013848 -135.911641) (xy 20.980654 -135.886952)
			(xy 20.972482 -135.881239) (xy 20.953258 -135.876016) (xy 20.943316 -135.876792) (xy 20.914619 -135.880348)
			(xy 20.856915 -135.884158) (xy 20.828 -135.884412) (xy 20.784509 -135.88388) (xy 20.697945 -135.875379)
			(xy 20.612623 -135.858468) (xy 20.52936 -135.833309) (xy 20.448951 -135.800142) (xy 20.372163 -135.759284)
			(xy 20.299731 -135.711124) (xy 20.232346 -135.656124) (xy 20.201128 -135.62584) (xy 20.193762 -135.618728)
			(xy 20.175474 -135.611108) (xy 20.083526 -135.611108) (xy 20.065238 -135.618728) (xy 20.057872 -135.62584)
			(xy 20.026646 -135.656117) (xy 19.959268 -135.711126) (xy 19.886839 -135.759292) (xy 19.810053 -135.800155)
			(xy 19.729644 -135.833325) (xy 19.64638 -135.858483) (xy 19.561057 -135.87539) (xy 19.474491 -135.883884)
			(xy 19.431 -135.884412) (xy 19.388652 -135.8839) (xy 19.304339 -135.875849) (xy 19.221173 -135.859821)
			(xy 19.139907 -135.835959) (xy 19.061277 -135.80448) (xy 18.985996 -135.76567) (xy 18.914744 -135.71988)
			(xy 18.848168 -135.667524) (xy 18.786871 -135.609076) (xy 18.731406 -135.545067) (xy 18.682277 -135.476075)
			(xy 18.639929 -135.402725) (xy 18.604745 -135.325683) (xy 18.577043 -135.245644) (xy 18.557075 -135.163335)
			(xy 18.545022 -135.079501) (xy 18.540992 -134.9949) (xy 18.12436 -134.9949) (xy 18.130403 -135.004304)
			(xy 18.169214 -135.079585) (xy 18.200693 -135.158215) (xy 18.224554 -135.239482) (xy 18.240583 -135.322648)
			(xy 18.248634 -135.406962) (xy 18.249138 -135.44931) (xy 18.248608 -135.493825) (xy 18.239743 -135.582413)
			(xy 18.222063 -135.669669) (xy 18.195745 -135.75472) (xy 18.161054 -135.836713) (xy 18.140172 -135.87603)
			(xy 18.136043 -135.884267) (xy 18.133425 -135.902491) (xy 18.13746 -135.920455) (xy 18.142204 -135.928354)
			(xy 18.165462 -135.964673) (xy 18.205659 -136.040983) (xy 18.23828 -136.120825) (xy 18.263018 -136.20345)
			(xy 18.279643 -136.288082) (xy 18.287997 -136.373925) (xy 18.288508 -136.41705) (xy 18.288243 -136.447053)
			(xy 18.284174 -136.506921) (xy 18.28038 -136.536684) (xy 18.278856 -136.548114) (xy 18.28546 -136.569196)
			(xy 18.35277 -136.643872) (xy 18.37309 -136.652508) (xy 18.38452 -136.652) (xy 18.415 -136.651492)
			(xy 18.456558 -136.651927) (xy 18.539313 -136.659672) (xy 18.620984 -136.675103) (xy 18.700859 -136.698087)
			(xy 18.778242 -136.728422) (xy 18.852457 -136.765844) (xy 18.922857 -136.810027) (xy 18.988828 -136.860585)
			(xy 19.049795 -136.917077) (xy 19.105225 -136.979011) (xy 19.145139 -137.033) (xy 26.542492 -137.033)
			(xy 26.542996 -136.990652) (xy 26.551047 -136.906338) (xy 26.567076 -136.823172) (xy 26.590937 -136.741905)
			(xy 26.622416 -136.663275) (xy 26.661227 -136.587994) (xy 26.707017 -136.516742) (xy 26.759373 -136.450166)
			(xy 26.817821 -136.388868) (xy 26.881831 -136.333403) (xy 26.950823 -136.284274) (xy 27.024173 -136.241925)
			(xy 27.101216 -136.206741) (xy 27.181255 -136.179039) (xy 27.263564 -136.159071) (xy 27.347399 -136.147018)
			(xy 27.432 -136.142988) (xy 27.516601 -136.147018) (xy 27.600436 -136.159071) (xy 27.682745 -136.179039)
			(xy 27.762784 -136.206741) (xy 27.839827 -136.241925) (xy 27.913177 -136.284274) (xy 27.982169 -136.333403)
			(xy 28.046179 -136.388868) (xy 28.104627 -136.450166) (xy 28.156983 -136.516742) (xy 28.202773 -136.587994)
			(xy 28.241584 -136.663275) (xy 28.273063 -136.741905) (xy 28.296924 -136.823172) (xy 28.312953 -136.906338)
			(xy 28.321004 -136.990652) (xy 28.321508 -137.033) (xy 28.321105 -137.071422) (xy 28.314474 -137.14798)
			(xy 28.301261 -137.223679) (xy 28.281564 -137.297956) (xy 28.26893 -137.334244) (xy 28.265863 -137.343874)
			(xy 28.266774 -137.364047) (xy 28.275422 -137.382294) (xy 28.282646 -137.389362) (xy 28.312981 -137.417385)
			(xy 28.368838 -137.478223) (xy 28.418813 -137.543977) (xy 28.462478 -137.614081) (xy 28.499455 -137.687931)
			(xy 28.529427 -137.764892) (xy 28.552134 -137.844299) (xy 28.567382 -137.92547) (xy 28.575039 -138.007705)
			(xy 28.575508 -138.049) (xy 28.575004 -138.091348) (xy 28.566953 -138.175662) (xy 28.550924 -138.258828)
			(xy 28.527063 -138.340095) (xy 28.495584 -138.418725) (xy 28.456773 -138.494006) (xy 28.410983 -138.565258)
			(xy 28.358627 -138.631834) (xy 28.300179 -138.693132) (xy 28.236169 -138.748597) (xy 28.167177 -138.797726)
			(xy 28.093827 -138.840075) (xy 28.016784 -138.875259) (xy 27.936745 -138.902961) (xy 27.854436 -138.922929)
			(xy 27.770601 -138.934982) (xy 27.686 -138.939013) (xy 27.601399 -138.934982) (xy 27.517564 -138.922929)
			(xy 27.435255 -138.902961) (xy 27.355216 -138.875259) (xy 27.278173 -138.840075) (xy 27.204823 -138.797726)
			(xy 27.135831 -138.748597) (xy 27.071821 -138.693132) (xy 27.013373 -138.631834) (xy 26.961017 -138.565258)
			(xy 26.915227 -138.494006) (xy 26.876416 -138.418725) (xy 26.844937 -138.340095) (xy 26.821076 -138.258828)
			(xy 26.805047 -138.175662) (xy 26.796996 -138.091348) (xy 26.796492 -138.049) (xy 26.796895 -138.010578)
			(xy 26.803526 -137.93402) (xy 26.816739 -137.858321) (xy 26.836436 -137.784044) (xy 26.84907 -137.747756)
			(xy 26.852137 -137.738126) (xy 26.851226 -137.717953) (xy 26.842578 -137.699706) (xy 26.835354 -137.692638)
			(xy 26.805019 -137.664615) (xy 26.749162 -137.603777) (xy 26.699187 -137.538023) (xy 26.655522 -137.467919)
			(xy 26.618545 -137.394069) (xy 26.588573 -137.317108) (xy 26.565866 -137.237701) (xy 26.550618 -137.15653)
			(xy 26.542961 -137.074295) (xy 26.542492 -137.033) (xy 19.145139 -137.033) (xy 19.154636 -137.045846)
			(xy 19.197596 -137.116998) (xy 19.23373 -137.191849) (xy 19.262724 -137.269744) (xy 19.284324 -137.350004)
			(xy 19.291808 -137.390886) (xy 19.293945 -137.400831) (xy 19.304852 -137.417979) (xy 19.321574 -137.429527)
			(xy 19.331432 -137.432034) (xy 19.373832 -137.441344) (xy 19.456708 -137.467198) (xy 19.536671 -137.501002)
			(xy 19.612961 -137.542435) (xy 19.684851 -137.591103) (xy 19.751659 -137.646543) (xy 19.812749 -137.708227)
			(xy 19.867539 -137.775568) (xy 19.915508 -137.847927) (xy 19.9562 -137.924614) (xy 19.989229 -138.004901)
			(xy 20.014279 -138.088023) (xy 20.031112 -138.173191) (xy 20.039569 -138.259593) (xy 20.040092 -138.303)
			(xy 20.039648 -138.344104) (xy 20.032063 -138.42596) (xy 20.016957 -138.506768) (xy 19.99446 -138.585837)
			(xy 19.964763 -138.662493) (xy 19.928119 -138.736081) (xy 19.884842 -138.805975) (xy 19.835301 -138.871577)
			(xy 19.779918 -138.932329) (xy 19.719165 -138.987711) (xy 19.653562 -139.037251) (xy 19.583667 -139.080527)
			(xy 19.510078 -139.117169) (xy 19.433422 -139.146865) (xy 19.354352 -139.169361) (xy 19.273544 -139.184465)
			(xy 19.191688 -139.192049) (xy 19.150584 -139.192508) (xy 19.109026 -139.192088) (xy 19.026271 -139.184342)
			(xy 18.944599 -139.168909) (xy 18.864724 -139.145924) (xy 18.787341 -139.115587) (xy 18.713126 -139.078164)
			(xy 18.642726 -139.03398) (xy 18.576755 -138.983421) (xy 18.515788 -138.926928) (xy 18.460358 -138.864993)
			(xy 18.410947 -138.798158) (xy 18.367988 -138.727004) (xy 18.331853 -138.652153) (xy 18.30286 -138.574257)
			(xy 18.28126 -138.493996) (xy 18.273776 -138.453114) (xy 18.27165 -138.443166) (xy 18.26074 -138.426017)
			(xy 18.244012 -138.414471) (xy 18.234152 -138.411966) (xy 18.191749 -138.402668) (xy 18.108873 -138.376812)
			(xy 18.02891 -138.343007) (xy 17.952621 -138.301572) (xy 17.88073 -138.252903) (xy 17.813923 -138.197463)
			(xy 17.752834 -138.135778) (xy 17.698044 -138.068435) (xy 17.650075 -137.996076) (xy 17.609383 -137.919388)
			(xy 17.576355 -137.839101) (xy 17.551305 -137.755978) (xy 17.534471 -137.67081) (xy 17.526015 -137.584408)
			(xy 17.525492 -137.541) (xy 17.525762 -137.510997) (xy 17.529828 -137.451129) (xy 17.53362 -137.421366)
			(xy 17.535144 -137.409936) (xy 17.52854 -137.388854) (xy 17.46123 -137.314178) (xy 17.44091 -137.305542)
			(xy 17.42948 -137.30605) (xy 17.399 -137.306558) (xy 17.357898 -137.306083) (xy 17.276043 -137.298498)
			(xy 17.195238 -137.283393) (xy 17.116171 -137.260897) (xy 17.039517 -137.231201) (xy 16.96593 -137.194559)
			(xy 16.896038 -137.151284) (xy 16.830437 -137.101744) (xy 16.769687 -137.046363) (xy 16.714306 -136.985613)
			(xy 16.664766 -136.920012) (xy 16.621491 -136.85012) (xy 16.584849 -136.776533) (xy 16.555153 -136.699879)
			(xy 16.532657 -136.620812) (xy 16.517552 -136.540007) (xy 16.509967 -136.458152) (xy 16.509492 -136.41705)
			(xy 16.510001 -136.372534) (xy 16.518871 -136.283946) (xy 16.536555 -136.196689) (xy 16.562878 -136.111638)
			(xy 16.597574 -136.029646) (xy 16.618458 -135.99033) (xy 16.622535 -135.982071) (xy 16.625169 -135.963862)
			(xy 16.621157 -135.945906) (xy 16.616426 -135.938006) (xy 16.593154 -135.901696) (xy 16.552959 -135.825384)
			(xy 16.52034 -135.74554) (xy 16.495603 -135.662913) (xy 16.478982 -135.57828) (xy 16.470632 -135.492435)
			(xy 16.470122 -135.44931) (xy 15.346245 -135.44931) (xy 15.348018 -135.468947) (xy 15.348458 -135.509)
			(xy 15.347906 -135.553814) (xy 15.338895 -135.642988) (xy 15.320963 -135.730805) (xy 15.294294 -135.816373)
			(xy 15.259156 -135.898827) (xy 15.215907 -135.97733) (xy 15.164984 -136.051087) (xy 15.136368 -136.08558)
			(xy 15.130678 -136.092829) (xy 15.124431 -136.11015) (xy 15.124176 -136.119362) (xy 15.124684 -136.14908)
			(xy 15.125219 -136.158219) (xy 15.131843 -136.175269) (xy 15.137638 -136.182354) (xy 15.164717 -136.212989)
			(xy 15.213784 -136.278401) (xy 15.256638 -136.348041) (xy 15.292917 -136.421321) (xy 15.322316 -136.497622)
			(xy 15.344585 -136.576301) (xy 15.359536 -136.656692) (xy 15.367043 -136.738115) (xy 15.367508 -136.779)
			(xy 15.367004 -136.821348) (xy 15.358953 -136.905662) (xy 15.342924 -136.988828) (xy 15.319063 -137.070095)
			(xy 15.287584 -137.148725) (xy 15.248773 -137.224006) (xy 15.202983 -137.295258) (xy 15.150627 -137.361834)
			(xy 15.092179 -137.423132) (xy 15.028169 -137.478597) (xy 14.959177 -137.527726) (xy 14.885827 -137.570075)
			(xy 14.808784 -137.605259) (xy 14.728745 -137.632961) (xy 14.646436 -137.652929) (xy 14.562601 -137.664982)
			(xy 14.478 -137.669013) (xy 14.393399 -137.664982) (xy 14.309564 -137.652929) (xy 14.227255 -137.632961)
			(xy 14.147216 -137.605259) (xy 14.070173 -137.570075) (xy 13.996823 -137.527726) (xy 13.927831 -137.478597)
			(xy 13.863821 -137.423132) (xy 13.805373 -137.361834) (xy 13.753017 -137.295258) (xy 13.707227 -137.224006)
			(xy 13.668416 -137.148725) (xy 13.636937 -137.070095) (xy 13.613076 -136.988828) (xy 13.597047 -136.905662)
			(xy 13.588996 -136.821348) (xy 13.588492 -136.779) (xy 13.589032 -136.734185) (xy 13.598044 -136.64501)
			(xy 13.615976 -136.557193) (xy 13.642647 -136.471624) (xy 13.677787 -136.389171) (xy 13.721039 -136.310668)
			(xy 13.771965 -136.236912) (xy 13.800582 -136.20242) (xy 13.806266 -136.195167) (xy 13.812518 -136.177849)
			(xy 13.812774 -136.168638) (xy 13.812266 -136.13892) (xy 13.811742 -136.12978) (xy 13.805111 -136.11273)
			(xy 13.799312 -136.105646) (xy 13.772225 -136.075018) (xy 13.72316 -136.009605) (xy 13.680307 -135.939963)
			(xy 13.644029 -135.866682) (xy 13.614632 -135.790379) (xy 13.592364 -135.7117) (xy 13.577414 -135.631309)
			(xy 13.569907 -135.549885) (xy 13.569442 -135.509) (xy 13.569875 -135.468947) (xy 13.577086 -135.389166)
			(xy 13.59144 -135.310356) (xy 13.612821 -135.233155) (xy 13.641057 -135.15819) (xy 13.675917 -135.086067)
			(xy 13.71712 -135.017369) (xy 13.764333 -134.952654) (xy 13.790422 -134.92226) (xy 13.796101 -134.915135)
			(xy 13.80249 -134.898088) (xy 13.802868 -134.888986) (xy 13.802868 -134.859014) (xy 13.802473 -134.849913)
			(xy 13.7961 -134.832863) (xy 13.790422 -134.82574) (xy 13.76262 -134.793296) (xy 13.712674 -134.723965)
			(xy 13.669607 -134.650164) (xy 13.633815 -134.572574) (xy 13.605629 -134.491908) (xy 13.585309 -134.408912)
			(xy 13.573041 -134.324349) (xy 13.568939 -134.239) (xy 7.894368 -134.239) (xy 7.894352 -134.240377)
			(xy 7.886529 -134.323536) (xy 7.870942 -134.405595) (xy 7.84773 -134.485832) (xy 7.817097 -134.563538)
			(xy 7.779312 -134.638029) (xy 7.757414 -134.673594) (xy 7.751064 -134.6835) (xy 7.748524 -134.705852)
			(xy 7.780782 -134.802626) (xy 7.79653 -134.818882) (xy 7.807452 -134.822946) (xy 7.849889 -134.839618)
			(xy 7.931424 -134.880438) (xy 8.00836 -134.929376) (xy 8.079894 -134.985919) (xy 8.145276 -135.049476)
			(xy 8.17499 -135.084058) (xy 8.182356 -135.092694) (xy 8.202676 -135.102346) (xy 8.30326 -135.102346)
			(xy 8.32358 -135.092694) (xy 8.330946 -135.084058) (xy 8.359075 -135.051285) (xy 8.420674 -134.990741)
			(xy 8.487853 -134.936453) (xy 8.559977 -134.888932) (xy 8.636368 -134.848627) (xy 8.716306 -134.815916)
			(xy 8.799038 -134.791107) (xy 8.883786 -134.774435) (xy 8.96975 -134.766057) (xy 9.012936 -134.765542)
			(xy 9.055285 -134.76603) (xy 9.139601 -134.774081) (xy 9.222769 -134.79011) (xy 9.304037 -134.813972)
			(xy 9.382668 -134.845451) (xy 9.457952 -134.884262) (xy 9.529205 -134.930053) (xy 9.595783 -134.98241)
			(xy 9.657082 -135.040859) (xy 9.712548 -135.10487) (xy 9.761678 -135.173863) (xy 9.804028 -135.247214)
			(xy 9.839213 -135.324259) (xy 9.866915 -135.404299) (xy 9.886884 -135.486611) (xy 9.898938 -135.570447)
			(xy 9.902968 -135.65505) (xy 9.898938 -135.739653) (xy 9.886884 -135.823489) (xy 9.866915 -135.905801)
			(xy 9.839213 -135.985841) (xy 9.804028 -136.062886) (xy 9.761678 -136.136237) (xy 9.712548 -136.20523)
			(xy 9.657082 -136.269241) (xy 9.595783 -136.32769) (xy 9.529205 -136.380047) (xy 9.457952 -136.425838)
			(xy 9.382668 -136.464649) (xy 9.304037 -136.496128) (xy 9.222769 -136.51999) (xy 9.139601 -136.536019)
			(xy 9.055285 -136.54407) (xy 9.012936 -136.544558) (xy 8.969748 -136.544062) (xy 8.883778 -136.535699)
			(xy 8.799024 -136.519037) (xy 8.716285 -136.494234) (xy 8.636342 -136.461525) (xy 8.559948 -136.421216)
			(xy 8.487823 -136.373689) (xy 8.420648 -136.319392) (xy 8.359054 -136.258835) (xy 8.330946 -136.226042)
			(xy 8.32358 -136.217406) (xy 8.30326 -136.207754) (xy 8.202676 -136.207754) (xy 8.182356 -136.217406)
			(xy 8.17499 -136.226042) (xy 8.146841 -136.258798) (xy 8.085245 -136.319343) (xy 8.018069 -136.373632)
			(xy 7.945948 -136.421154) (xy 7.869559 -136.461461) (xy 7.789624 -136.494174) (xy 7.706893 -136.518985)
			(xy 7.622148 -136.53566) (xy 7.536185 -136.544041) (xy 7.493 -136.544558) (xy 7.451898 -136.544083)
			(xy 7.370043 -136.536498) (xy 7.289238 -136.521393) (xy 7.210171 -136.498897) (xy 7.133517 -136.469201)
			(xy 7.05993 -136.432559) (xy 6.990038 -136.389284) (xy 6.924437 -136.339744) (xy 6.863687 -136.284363)
			(xy 6.808306 -136.223613) (xy 6.758766 -136.158012) (xy 6.715491 -136.08812) (xy 6.678849 -136.014533)
			(xy 6.649153 -135.937879) (xy 6.626657 -135.858812) (xy 6.611552 -135.778007) (xy 6.603967 -135.696152)
			(xy 6.603492 -135.65505) (xy 6.603947 -135.613286) (xy 6.611774 -135.530126) (xy 6.627365 -135.448067)
			(xy 6.650581 -135.367831) (xy 6.681218 -135.290125) (xy 6.719006 -135.215634) (xy 6.740906 -135.18007)
			(xy 6.747256 -135.170164) (xy 6.749796 -135.147812) (xy 6.717538 -135.051038) (xy 6.70179 -135.034782)
			(xy 6.690868 -135.030718) (xy 6.652318 -135.01565) (xy 6.577944 -134.979317) (xy 6.507267 -134.936233)
			(xy 6.440898 -134.886768) (xy 6.379411 -134.831353) (xy 6.323338 -134.770465) (xy 6.273163 -134.704631)
			(xy 6.229321 -134.634421) (xy 6.192191 -134.560442) (xy 6.162094 -134.483333) (xy 6.13929 -134.403762)
			(xy 6.123977 -134.322417) (xy 6.116286 -134.240001) (xy 6.115812 -134.198614) (xy 1.651254 -134.198614)
			(xy 1.651254 -134.740904) (xy 1.652778 -134.79145) (xy 1.651254 -134.841996) (xy 1.651254 -139.820904)
			(xy 1.652778 -139.87145) (xy 1.651254 -139.921996) (xy 1.651254 -144.900904) (xy 1.652778 -144.95145)
			(xy 1.651254 -145.001996) (xy 1.651254 -149.980904) (xy 1.652778 -150.03145) (xy 1.651254 -150.081996)
			(xy 1.651254 -155.060904) (xy 1.652778 -155.11145) (xy 1.651254 -155.161996) (xy 1.651254 -157.661102)
			(xy 6.349492 -157.661102) (xy 6.349492 -145.660872) (xy 6.349965 -145.568032) (xy 6.357624 -145.382509)
			(xy 6.372927 -145.19746) (xy 6.395848 -145.0132) (xy 6.426349 -144.830041) (xy 6.464377 -144.648296)
			(xy 6.509867 -144.468274) (xy 6.562744 -144.290282) (xy 6.622915 -144.114621) (xy 6.69028 -143.941591)
			(xy 6.764722 -143.771486) (xy 6.846117 -143.604596) (xy 6.934325 -143.441205) (xy 7.029196 -143.281591)
			(xy 7.130569 -143.126024) (xy 7.238271 -142.974771) (xy 7.352119 -142.828088) (xy 7.471919 -142.686225)
			(xy 7.597468 -142.549422) (xy 7.662672 -142.483332) (xy 7.674864 -142.47114) (xy 7.679436 -142.437104)
			(xy 7.613396 -142.322296) (xy 7.581646 -142.309088) (xy 7.565136 -142.313406) (xy 7.528423 -142.322566)
			(xy 7.453839 -142.33535) (xy 7.378436 -142.341739) (xy 7.3406 -142.342108) (xy 7.298675 -142.341624)
			(xy 7.215196 -142.333733) (xy 7.132831 -142.318021) (xy 7.052309 -142.294628) (xy 6.974347 -142.26376)
			(xy 6.899636 -142.225693) (xy 6.828838 -142.180763) (xy 6.762583 -142.129371) (xy 6.701459 -142.071971)
			(xy 6.646007 -142.009074) (xy 6.596721 -141.941237) (xy 6.554038 -141.869063) (xy 6.518336 -141.793193)
			(xy 6.489932 -141.7143) (xy 6.469079 -141.633083) (xy 6.455962 -141.550265) (xy 6.450697 -141.46658)
			(xy 6.453331 -141.38277) (xy 6.46384 -141.299581) (xy 6.482132 -141.21775) (xy 6.508043 -141.138003)
			(xy 6.541344 -141.061049) (xy 6.58174 -140.98757) (xy 6.628871 -140.918218) (xy 6.682319 -140.85361)
			(xy 6.74161 -140.794319) (xy 6.806218 -140.740871) (xy 6.87557 -140.69374) (xy 6.949049 -140.653344)
			(xy 7.026003 -140.620043) (xy 7.10575 -140.594132) (xy 7.187581 -140.57584) (xy 7.27077 -140.565331)
			(xy 7.35458 -140.562697) (xy 7.438265 -140.567962) (xy 7.521083 -140.581079) (xy 7.6023 -140.601932)
			(xy 7.681193 -140.630336) (xy 7.757063 -140.666038) (xy 7.829237 -140.708721) (xy 7.897074 -140.758007)
			(xy 7.959971 -140.813459) (xy 8.017371 -140.874583) (xy 8.068763 -140.940838) (xy 8.113693 -141.011636)
			(xy 8.15176 -141.086347) (xy 8.182628 -141.164309) (xy 8.206021 -141.244831) (xy 8.221733 -141.327196)
			(xy 8.229624 -141.410675) (xy 8.230108 -141.4526) (xy 8.229687 -141.491361) (xy 8.222961 -141.568592)
			(xy 8.209532 -141.644942) (xy 8.189504 -141.719833) (xy 8.163028 -141.792695) (xy 8.14705 -141.828012)
			(xy 8.139684 -141.84376) (xy 8.14705 -141.877288) (xy 8.248142 -141.962632) (xy 8.282432 -141.96441)
			(xy 8.296656 -141.954504) (xy 8.374415 -141.901531) (xy 8.533706 -141.801351) (xy 8.697044 -141.707916)
			(xy 8.864145 -141.621389) (xy 9.034716 -141.541922) (xy 9.20846 -141.469653) (xy 9.385072 -141.404709)
			(xy 9.564244 -141.347204) (xy 9.745663 -141.297237) (xy 9.929012 -141.254897) (xy 10.113971 -141.220256)
			(xy 10.300215 -141.193376) (xy 10.487421 -141.174304) (xy 10.675259 -141.163073) (xy 10.863403 -141.159703)
			(xy 11.051524 -141.164199) (xy 11.239292 -141.176553) (xy 11.42638 -141.196745) (xy 11.480922 -141.20495)
			(xy 20.459192 -141.20495) (xy 20.459696 -141.162602) (xy 20.467747 -141.078288) (xy 20.483776 -140.995122)
			(xy 20.507637 -140.913855) (xy 20.539116 -140.835225) (xy 20.577927 -140.759944) (xy 20.623717 -140.688692)
			(xy 20.676073 -140.622116) (xy 20.734521 -140.560818) (xy 20.798531 -140.505353) (xy 20.867523 -140.456224)
			(xy 20.940873 -140.413875) (xy 21.017916 -140.378691) (xy 21.097955 -140.350989) (xy 21.180264 -140.331021)
			(xy 21.264099 -140.318968) (xy 21.3487 -140.314938) (xy 21.433301 -140.318968) (xy 21.517136 -140.331021)
			(xy 21.599445 -140.350989) (xy 21.679484 -140.378691) (xy 21.756527 -140.413875) (xy 21.829877 -140.456224)
			(xy 21.898869 -140.505353) (xy 21.962879 -140.560818) (xy 22.021327 -140.622116) (xy 22.073683 -140.688692)
			(xy 22.119473 -140.759944) (xy 22.158284 -140.835225) (xy 22.189763 -140.913855) (xy 22.213624 -140.995122)
			(xy 22.229653 -141.078288) (xy 22.237704 -141.162602) (xy 22.238208 -141.20495) (xy 22.237711 -141.248711)
			(xy 22.2291 -141.335809) (xy 22.211975 -141.421641) (xy 22.186503 -141.505375) (xy 22.152929 -141.586202)
			(xy 22.111579 -141.663341) (xy 22.062852 -141.736045) (xy 22.007219 -141.803612) (xy 21.976588 -141.83487)
			(xy 21.967952 -141.843506) (xy 21.960586 -141.866366) (xy 21.976588 -141.971776) (xy 21.990558 -141.991334)
			(xy 22.00148 -141.996922) (xy 22.036698 -142.015829) (xy 22.103942 -142.059056) (xy 22.167036 -142.108142)
			(xy 22.196552 -142.135098) (xy 22.204426 -142.14221) (xy 22.223984 -142.149322) (xy 22.319234 -142.142972)
			(xy 22.337776 -142.13332) (xy 22.34438 -142.124938) (xy 22.372487 -142.091429) (xy 22.434276 -142.029523)
			(xy 22.501845 -141.973982) (xy 22.57454 -141.925343) (xy 22.651659 -141.884076) (xy 22.732458 -141.85058)
			(xy 22.816154 -141.825179) (xy 22.90194 -141.808118) (xy 22.988987 -141.799562) (xy 23.03272 -141.799056)
			(xy 23.075069 -141.799552) (xy 23.159383 -141.807603) (xy 23.242549 -141.823632) (xy 23.323816 -141.847494)
			(xy 23.402446 -141.878973) (xy 23.477728 -141.917783) (xy 23.54898 -141.963574) (xy 23.615557 -142.01593)
			(xy 23.676855 -142.074378) (xy 23.73232 -142.138388) (xy 23.78145 -142.207381) (xy 23.823798 -142.280731)
			(xy 23.858983 -142.357774) (xy 23.886685 -142.437813) (xy 23.906653 -142.520123) (xy 23.918706 -142.603959)
			(xy 23.922737 -142.68856) (xy 23.920885 -142.72743) (xy 24.638254 -142.72743) (xy 24.642284 -142.642829)
			(xy 24.654337 -142.558993) (xy 24.674305 -142.476683) (xy 24.702007 -142.396644) (xy 24.737192 -142.319601)
			(xy 24.77954 -142.246251) (xy 24.82867 -142.177258) (xy 24.884135 -142.113248) (xy 24.945433 -142.0548)
			(xy 25.01201 -142.002444) (xy 25.083262 -141.956653) (xy 25.158544 -141.917843) (xy 25.237174 -141.886364)
			(xy 25.318441 -141.862502) (xy 25.401607 -141.846473) (xy 25.485921 -141.838422) (xy 25.52827 -141.837918)
			(xy 25.571766 -141.838457) (xy 25.658341 -141.846955) (xy 25.743673 -141.863864) (xy 25.826947 -141.889022)
			(xy 25.907368 -141.922188) (xy 25.984167 -141.963046) (xy 26.056612 -142.011206) (xy 26.124009 -142.066208)
			(xy 26.185715 -142.127525) (xy 26.241141 -142.194573) (xy 26.265886 -142.230348) (xy 26.272998 -142.241016)
			(xy 26.29535 -142.2527) (xy 26.405078 -142.2527) (xy 26.42743 -142.241016) (xy 26.434542 -142.230348)
			(xy 26.459263 -142.194555) (xy 26.514685 -142.127499) (xy 26.576391 -142.066176) (xy 26.643789 -142.01117)
			(xy 26.716236 -141.963008) (xy 26.793039 -141.922149) (xy 26.873464 -141.888985) (xy 26.956743 -141.863832)
			(xy 27.042081 -141.846931) (xy 27.128661 -141.838442) (xy 27.172158 -141.837918) (xy 27.216985 -141.838477)
			(xy 27.306183 -141.847512) (xy 27.350212 -141.855952) (xy 27.365452 -141.859) (xy 27.3939 -141.847316)
			(xy 27.463496 -141.74343) (xy 27.463496 -141.712696) (xy 27.45486 -141.699742) (xy 27.430942 -141.663122)
			(xy 27.389644 -141.586011) (xy 27.356118 -141.505219) (xy 27.330686 -141.421524) (xy 27.313596 -141.335737)
			(xy 27.305012 -141.248686) (xy 27.304492 -141.20495) (xy 27.304976 -141.163025) (xy 27.312867 -141.079546)
			(xy 27.328579 -140.997181) (xy 27.351972 -140.916659) (xy 27.38284 -140.838697) (xy 27.420907 -140.763986)
			(xy 27.465837 -140.693188) (xy 27.517229 -140.626933) (xy 27.574629 -140.565809) (xy 27.637526 -140.510357)
			(xy 27.705363 -140.461071) (xy 27.777537 -140.418388) (xy 27.853407 -140.382686) (xy 27.9323 -140.354282)
			(xy 28.013517 -140.333429) (xy 28.096335 -140.320312) (xy 28.18002 -140.315047) (xy 28.26383 -140.317681)
			(xy 28.347019 -140.32819) (xy 28.42885 -140.346482) (xy 28.508597 -140.372393) (xy 28.585551 -140.405694)
			(xy 28.65903 -140.44609) (xy 28.728382 -140.493221) (xy 28.79299 -140.546669) (xy 28.852281 -140.60596)
			(xy 28.905729 -140.670568) (xy 28.95286 -140.73992) (xy 28.993256 -140.813399) (xy 29.026557 -140.890353)
			(xy 29.052468 -140.9701) (xy 29.07076 -141.051931) (xy 29.081269 -141.13512) (xy 29.083903 -141.21893)
			(xy 29.078638 -141.302615) (xy 29.065521 -141.385433) (xy 29.044668 -141.46665) (xy 29.016264 -141.545543)
			(xy 28.988285 -141.605) (xy 29.971492 -141.605) (xy 29.971996 -141.562652) (xy 29.980047 -141.478338)
			(xy 29.996076 -141.395172) (xy 30.019937 -141.313905) (xy 30.051416 -141.235275) (xy 30.090227 -141.159994)
			(xy 30.136017 -141.088742) (xy 30.188373 -141.022166) (xy 30.246821 -140.960868) (xy 30.310831 -140.905403)
			(xy 30.379823 -140.856274) (xy 30.453173 -140.813925) (xy 30.530216 -140.778741) (xy 30.610255 -140.751039)
			(xy 30.692564 -140.731071) (xy 30.776399 -140.719018) (xy 30.861 -140.714988) (xy 30.945601 -140.719018)
			(xy 31.029436 -140.731071) (xy 31.111745 -140.751039) (xy 31.191784 -140.778741) (xy 31.268827 -140.813925)
			(xy 31.342177 -140.856274) (xy 31.411169 -140.905403) (xy 31.475179 -140.960868) (xy 31.506101 -140.993298)
			(xy 31.749996 -140.993298) (xy 31.749996 -140.908602) (xy 31.758047 -140.824288) (xy 31.774076 -140.741122)
			(xy 31.797937 -140.659855) (xy 31.829416 -140.581225) (xy 31.868227 -140.505944) (xy 31.914017 -140.434692)
			(xy 31.966373 -140.368116) (xy 32.024821 -140.306818) (xy 32.088831 -140.251353) (xy 32.157823 -140.202224)
			(xy 32.231173 -140.159875) (xy 32.308216 -140.124691) (xy 32.388255 -140.096989) (xy 32.470564 -140.077021)
			(xy 32.554399 -140.064968) (xy 32.639 -140.060938) (xy 32.723601 -140.064968) (xy 32.807436 -140.077021)
			(xy 32.889745 -140.096989) (xy 32.969784 -140.124691) (xy 33.046827 -140.159875) (xy 33.120177 -140.202224)
			(xy 33.189169 -140.251353) (xy 33.253179 -140.306818) (xy 33.311627 -140.368116) (xy 33.363983 -140.434692)
			(xy 33.409773 -140.505944) (xy 33.448584 -140.581225) (xy 33.480063 -140.659855) (xy 33.503924 -140.741122)
			(xy 33.519953 -140.824288) (xy 33.528004 -140.908602) (xy 33.528508 -140.95095) (xy 33.528004 -140.993298)
			(xy 33.519953 -141.077612) (xy 33.503924 -141.160778) (xy 33.480063 -141.242045) (xy 33.448584 -141.320675)
			(xy 33.409773 -141.395956) (xy 33.363983 -141.467208) (xy 33.311627 -141.533784) (xy 33.253179 -141.595082)
			(xy 33.189169 -141.650547) (xy 33.120177 -141.699676) (xy 33.046827 -141.742025) (xy 32.969784 -141.777209)
			(xy 32.889745 -141.804911) (xy 32.807436 -141.824879) (xy 32.723601 -141.836932) (xy 32.639 -141.840963)
			(xy 32.554399 -141.836932) (xy 32.470564 -141.824879) (xy 32.388255 -141.804911) (xy 32.308216 -141.777209)
			(xy 32.231173 -141.742025) (xy 32.157823 -141.699676) (xy 32.088831 -141.650547) (xy 32.024821 -141.595082)
			(xy 31.966373 -141.533784) (xy 31.914017 -141.467208) (xy 31.868227 -141.395956) (xy 31.829416 -141.320675)
			(xy 31.797937 -141.242045) (xy 31.774076 -141.160778) (xy 31.758047 -141.077612) (xy 31.749996 -140.993298)
			(xy 31.506101 -140.993298) (xy 31.533627 -141.022166) (xy 31.585983 -141.088742) (xy 31.631773 -141.159994)
			(xy 31.670584 -141.235275) (xy 31.702063 -141.313905) (xy 31.725924 -141.395172) (xy 31.741953 -141.478338)
			(xy 31.750004 -141.562652) (xy 31.750508 -141.605) (xy 31.749978 -141.647589) (xy 31.741794 -141.732374)
			(xy 31.72554 -141.815988) (xy 31.713932 -141.856968) (xy 31.710203 -141.871754) (xy 31.710592 -141.902227)
			(xy 31.719935 -141.931235) (xy 31.737405 -141.956205) (xy 31.761453 -141.974925) (xy 31.789947 -141.985735)
			(xy 31.805118 -141.98727) (xy 31.846962 -141.990275) (xy 31.929839 -142.003328) (xy 32.011119 -142.024128)
			(xy 32.090079 -142.05249) (xy 32.166017 -142.088161) (xy 32.238258 -142.130826) (xy 32.30616 -142.180104)
			(xy 32.36912 -142.235558) (xy 32.426578 -142.296694) (xy 32.478023 -142.36297) (xy 32.478969 -142.36446)
			(xy 33.017206 -142.36446) (xy 33.017628 -142.323356) (xy 33.025217 -142.2415) (xy 33.040326 -142.160694)
			(xy 33.062826 -142.081625) (xy 33.092526 -142.004971) (xy 33.129171 -141.931383) (xy 33.17245 -141.861491)
			(xy 33.221993 -141.79589) (xy 33.277378 -141.73514) (xy 33.338131 -141.679759) (xy 33.403735 -141.63022)
			(xy 33.47363 -141.586945) (xy 33.54722 -141.550304) (xy 33.623877 -141.520609) (xy 33.702946 -141.498114)
			(xy 33.783754 -141.48301) (xy 33.86561 -141.475426) (xy 33.906714 -141.474952) (xy 33.950441 -141.475519)
			(xy 34.037474 -141.484096) (xy 34.123244 -141.501176) (xy 34.206923 -141.526593) (xy 34.287702 -141.560103)
			(xy 34.364802 -141.601381) (xy 34.437476 -141.650028) (xy 34.505024 -141.705576) (xy 34.566793 -141.767486)
			(xy 34.622185 -141.835161) (xy 34.670666 -141.907947) (xy 34.711767 -141.985141) (xy 34.728912 -142.02537)
			(xy 34.733291 -142.034401) (xy 34.74752 -142.048525) (xy 34.756598 -142.052802) (xy 34.796784 -142.070005)
			(xy 34.873914 -142.111155) (xy 34.946636 -142.15967) (xy 35.014249 -142.215085) (xy 35.076101 -142.276863)
			(xy 35.131596 -142.34441) (xy 35.180199 -142.417074) (xy 35.22144 -142.494154) (xy 35.254923 -142.574908)
			(xy 35.280324 -142.658556) (xy 35.297399 -142.744292) (xy 35.305983 -142.83129) (xy 35.306508 -142.875)
			(xy 35.306033 -142.916102) (xy 35.298448 -142.997957) (xy 35.283343 -143.078762) (xy 35.260847 -143.157829)
			(xy 35.231151 -143.234483) (xy 35.194509 -143.30807) (xy 35.151234 -143.377962) (xy 35.101694 -143.443563)
			(xy 35.046313 -143.504313) (xy 34.985563 -143.559694) (xy 34.919962 -143.609234) (xy 34.85007 -143.652509)
			(xy 34.776483 -143.689151) (xy 34.699829 -143.718847) (xy 34.620762 -143.741343) (xy 34.539957 -143.756448)
			(xy 34.458102 -143.764033) (xy 34.417 -143.764508) (xy 34.373272 -143.763953) (xy 34.286239 -143.755377)
			(xy 34.200468 -143.738298) (xy 34.116788 -143.71288) (xy 34.036007 -143.67937) (xy 33.958907 -143.638091)
			(xy 33.886232 -143.589443) (xy 33.818684 -143.533894) (xy 33.756916 -143.471982) (xy 33.701524 -143.404305)
			(xy 33.653045 -143.331516) (xy 33.611945 -143.25432) (xy 33.594802 -143.21409) (xy 33.590431 -143.205055)
			(xy 33.576196 -143.190934) (xy 33.567116 -143.186658) (xy 33.526918 -143.16948) (xy 33.449787 -143.12833)
			(xy 33.377064 -143.079812) (xy 33.309451 -143.024396) (xy 33.247598 -142.962616) (xy 33.192104 -142.895066)
			(xy 33.143502 -142.8224) (xy 33.102261 -142.745316) (xy 33.06878 -142.66456) (xy 33.043381 -142.580909)
			(xy 33.026309 -142.495171) (xy 33.017729 -142.408171) (xy 33.017206 -142.36446) (xy 32.478969 -142.36446)
			(xy 32.522998 -142.433796) (xy 32.561103 -142.508542) (xy 32.592 -142.586545) (xy 32.615414 -142.667111)
			(xy 32.631136 -142.749523) (xy 32.639028 -142.83305) (xy 32.639508 -142.875) (xy 32.639004 -142.917348)
			(xy 32.630953 -143.001662) (xy 32.614924 -143.084828) (xy 32.591063 -143.166095) (xy 32.559584 -143.244725)
			(xy 32.520773 -143.320006) (xy 32.474983 -143.391258) (xy 32.422627 -143.457834) (xy 32.364179 -143.519132)
			(xy 32.300169 -143.574597) (xy 32.231177 -143.623726) (xy 32.157827 -143.666075) (xy 32.080784 -143.701259)
			(xy 32.000745 -143.728961) (xy 31.918436 -143.748929) (xy 31.834601 -143.760982) (xy 31.75 -143.765013)
			(xy 31.665399 -143.760982) (xy 31.581564 -143.748929) (xy 31.499255 -143.728961) (xy 31.419216 -143.701259)
			(xy 31.342173 -143.666075) (xy 31.268823 -143.623726) (xy 31.199831 -143.574597) (xy 31.135821 -143.519132)
			(xy 31.077373 -143.457834) (xy 31.025017 -143.391258) (xy 30.979227 -143.320006) (xy 30.940416 -143.244725)
			(xy 30.908937 -143.166095) (xy 30.885076 -143.084828) (xy 30.869047 -143.001662) (xy 30.860996 -142.917348)
			(xy 30.860492 -142.875) (xy 30.861022 -142.832411) (xy 30.869206 -142.747626) (xy 30.88546 -142.664012)
			(xy 30.897068 -142.623032) (xy 30.900797 -142.608246) (xy 30.900408 -142.577773) (xy 30.891065 -142.548765)
			(xy 30.873595 -142.523795) (xy 30.849547 -142.505075) (xy 30.821053 -142.494265) (xy 30.805882 -142.49273)
			(xy 30.764045 -142.489649) (xy 30.681171 -142.4766) (xy 30.599894 -142.455804) (xy 30.520937 -142.427447)
			(xy 30.445001 -142.39178) (xy 30.372761 -142.34912) (xy 30.30486 -142.299847) (xy 30.2419 -142.244399)
			(xy 30.184442 -142.183268) (xy 30.132996 -142.116998) (xy 30.08802 -142.046178) (xy 30.049913 -141.971437)
			(xy 30.019013 -141.893439) (xy 29.995597 -141.812878) (xy 29.97987 -141.73047) (xy 29.971974 -141.646948)
			(xy 29.971492 -141.605) (xy 28.988285 -141.605) (xy 28.980562 -141.621413) (xy 28.937879 -141.693587)
			(xy 28.888593 -141.761424) (xy 28.833141 -141.824321) (xy 28.772017 -141.881721) (xy 28.705762 -141.933113)
			(xy 28.634964 -141.978043) (xy 28.560253 -142.01611) (xy 28.482291 -142.046978) (xy 28.401769 -142.070371)
			(xy 28.319404 -142.086083) (xy 28.235925 -142.093974) (xy 28.194 -142.094458) (xy 28.149173 -142.093904)
			(xy 28.059975 -142.084866) (xy 28.015946 -142.076424) (xy 28.000706 -142.073376) (xy 27.972258 -142.08506)
			(xy 27.902662 -142.188946) (xy 27.902662 -142.21968) (xy 27.911298 -142.232634) (xy 27.935213 -142.269256)
			(xy 27.97651 -142.346367) (xy 28.010036 -142.427159) (xy 28.035468 -142.510853) (xy 28.052559 -142.59664)
			(xy 28.061145 -142.68369) (xy 28.061666 -142.727426) (xy 28.061273 -142.768531) (xy 28.053685 -142.85039)
			(xy 28.038576 -142.931199) (xy 28.016076 -143.01027) (xy 27.986376 -143.086927) (xy 27.949729 -143.160517)
			(xy 27.906449 -143.230411) (xy 27.856904 -143.296014) (xy 27.801518 -143.356766) (xy 27.740762 -143.412148)
			(xy 27.675155 -143.461687) (xy 27.605257 -143.504962) (xy 27.531665 -143.541603) (xy 27.455005 -143.571298)
			(xy 27.375933 -143.593792) (xy 27.295122 -143.608894) (xy 27.213263 -143.616476) (xy 27.172158 -143.616934)
			(xy 27.128662 -143.616428) (xy 27.042086 -143.607924) (xy 26.956754 -143.591009) (xy 26.87348 -143.565846)
			(xy 26.793059 -143.532676) (xy 26.716261 -143.491814) (xy 26.643817 -143.443651) (xy 26.57642 -143.388648)
			(xy 26.514714 -143.327329) (xy 26.459288 -143.260279) (xy 26.434542 -143.224504) (xy 26.42743 -143.213836)
			(xy 26.405078 -143.202152) (xy 26.29535 -143.202152) (xy 26.272998 -143.213836) (xy 26.265886 -143.224504)
			(xy 26.241131 -143.260273) (xy 26.185714 -143.327331) (xy 26.124013 -143.388656) (xy 26.05662 -143.443664)
			(xy 25.984177 -143.491829) (xy 25.907378 -143.53269) (xy 25.826955 -143.565857) (xy 25.743679 -143.591013)
			(xy 25.658344 -143.607917) (xy 25.571767 -143.616408) (xy 25.52827 -143.616934) (xy 25.485921 -143.616438)
			(xy 25.401607 -143.608387) (xy 25.318441 -143.592358) (xy 25.237174 -143.568496) (xy 25.158544 -143.537017)
			(xy 25.083262 -143.498207) (xy 25.01201 -143.452416) (xy 24.945433 -143.40006) (xy 24.884135 -143.341612)
			(xy 24.82867 -143.277602) (xy 24.77954 -143.208609) (xy 24.737192 -143.135259) (xy 24.702007 -143.058216)
			(xy 24.674305 -142.978177) (xy 24.654337 -142.895867) (xy 24.642284 -142.812031) (xy 24.638254 -142.72743)
			(xy 23.920885 -142.72743) (xy 23.918706 -142.773161) (xy 23.906653 -142.856997) (xy 23.886685 -142.939307)
			(xy 23.858983 -143.019346) (xy 23.823798 -143.096389) (xy 23.78145 -143.169739) (xy 23.73232 -143.238732)
			(xy 23.676855 -143.302742) (xy 23.615557 -143.36119) (xy 23.54898 -143.413546) (xy 23.477728 -143.459337)
			(xy 23.402446 -143.498147) (xy 23.323816 -143.529626) (xy 23.242549 -143.553488) (xy 23.159383 -143.569517)
			(xy 23.075069 -143.577568) (xy 23.03272 -143.578072) (xy 22.990996 -143.577547) (xy 22.907917 -143.569702)
			(xy 22.825937 -143.554115) (xy 22.745776 -143.530924) (xy 22.668137 -143.500333) (xy 22.593701 -143.462609)
			(xy 22.523124 -143.418084) (xy 22.457023 -143.36715) (xy 22.426168 -143.339058) (xy 22.418294 -143.331946)
			(xy 22.398736 -143.324834) (xy 22.303486 -143.331184) (xy 22.284944 -143.340836) (xy 22.27834 -143.349218)
			(xy 22.250236 -143.382729) (xy 22.188445 -143.444634) (xy 22.120875 -143.500173) (xy 22.048179 -143.548811)
			(xy 21.97106 -143.590077) (xy 21.890262 -143.623572) (xy 21.806565 -143.648974) (xy 21.72078 -143.666035)
			(xy 21.633733 -143.674593) (xy 21.59 -143.6751) (xy 21.548897 -143.674648) (xy 21.46704 -143.667063)
			(xy 21.386233 -143.651957) (xy 21.307165 -143.62946) (xy 21.230509 -143.599763) (xy 21.156921 -143.56312)
			(xy 21.087027 -143.519844) (xy 21.021425 -143.470303) (xy 20.960674 -143.41492) (xy 20.905292 -143.354169)
			(xy 20.855752 -143.288566) (xy 20.812476 -143.218672) (xy 20.775833 -143.145083) (xy 20.746137 -143.068428)
			(xy 20.723641 -142.989359) (xy 20.708536 -142.908552) (xy 20.700952 -142.826695) (xy 20.700492 -142.785592)
			(xy 20.701017 -142.741831) (xy 20.709624 -142.654734) (xy 20.726745 -142.568904) (xy 20.752213 -142.48517)
			(xy 20.785783 -142.404342) (xy 20.82713 -142.327203) (xy 20.875853 -142.254498) (xy 20.931483 -142.186931)
			(xy 20.962112 -142.155672) (xy 20.970748 -142.147036) (xy 20.978114 -142.124176) (xy 20.962112 -142.018766)
			(xy 20.948142 -141.999208) (xy 20.93722 -141.99362) (xy 20.898389 -141.972758) (xy 20.824657 -141.924438)
			(xy 20.756065 -141.869062) (xy 20.693285 -141.807175) (xy 20.636935 -141.739382) (xy 20.587565 -141.666348)
			(xy 20.54566 -141.58879) (xy 20.511632 -141.507468) (xy 20.485813 -141.423179) (xy 20.468456 -141.33675)
			(xy 20.459733 -141.249027) (xy 20.459192 -141.20495) (xy 11.480922 -141.20495) (xy 11.612461 -141.224738)
			(xy 11.797209 -141.260484) (xy 11.980301 -141.303921) (xy 12.161418 -141.354972) (xy 12.340243 -141.413548)
			(xy 12.516463 -141.479547) (xy 12.689772 -141.552854) (xy 12.859864 -141.63334) (xy 13.026445 -141.720865)
			(xy 13.189221 -141.815276) (xy 13.34791 -141.916407) (xy 13.502232 -142.024082) (xy 13.65192 -142.138114)
			(xy 13.796711 -142.258302) (xy 13.936352 -142.384436) (xy 14.0706 -142.516297) (xy 14.199218 -142.653653)
			(xy 14.321984 -142.796265) (xy 14.357466 -142.841148) (xy 17.779996 -142.841148) (xy 17.779996 -142.756452)
			(xy 17.788047 -142.672138) (xy 17.804076 -142.588972) (xy 17.827937 -142.507705) (xy 17.859416 -142.429075)
			(xy 17.898227 -142.353794) (xy 17.944017 -142.282542) (xy 17.996373 -142.215966) (xy 18.054821 -142.154668)
			(xy 18.118831 -142.099203) (xy 18.187823 -142.050074) (xy 18.261173 -142.007725) (xy 18.338216 -141.972541)
			(xy 18.418255 -141.944839) (xy 18.500564 -141.924871) (xy 18.584399 -141.912818) (xy 18.669 -141.908788)
			(xy 18.753601 -141.912818) (xy 18.837436 -141.924871) (xy 18.919745 -141.944839) (xy 18.999784 -141.972541)
			(xy 19.076827 -142.007725) (xy 19.150177 -142.050074) (xy 19.219169 -142.099203) (xy 19.283179 -142.154668)
			(xy 19.341627 -142.215966) (xy 19.393983 -142.282542) (xy 19.439773 -142.353794) (xy 19.478584 -142.429075)
			(xy 19.510063 -142.507705) (xy 19.533924 -142.588972) (xy 19.549953 -142.672138) (xy 19.558004 -142.756452)
			(xy 19.558508 -142.7988) (xy 19.558004 -142.841148) (xy 19.549953 -142.925462) (xy 19.533924 -143.008628)
			(xy 19.510063 -143.089895) (xy 19.478584 -143.168525) (xy 19.439773 -143.243806) (xy 19.393983 -143.315058)
			(xy 19.341627 -143.381634) (xy 19.283179 -143.442932) (xy 19.219169 -143.498397) (xy 19.150177 -143.547526)
			(xy 19.076827 -143.589875) (xy 18.999784 -143.625059) (xy 18.919745 -143.652761) (xy 18.837436 -143.672729)
			(xy 18.753601 -143.684782) (xy 18.669 -143.688813) (xy 18.584399 -143.684782) (xy 18.500564 -143.672729)
			(xy 18.418255 -143.652761) (xy 18.338216 -143.625059) (xy 18.261173 -143.589875) (xy 18.187823 -143.547526)
			(xy 18.118831 -143.498397) (xy 18.054821 -143.442932) (xy 17.996373 -143.381634) (xy 17.944017 -143.315058)
			(xy 17.898227 -143.243806) (xy 17.859416 -143.168525) (xy 17.827937 -143.089895) (xy 17.804076 -143.008628)
			(xy 17.788047 -142.925462) (xy 17.779996 -142.841148) (xy 14.357466 -142.841148) (xy 14.438682 -142.943884)
			(xy 14.549108 -143.096251) (xy 14.653069 -143.2531) (xy 14.750384 -143.414157) (xy 14.840882 -143.57914)
			(xy 14.924406 -143.747762) (xy 15.00081 -143.919727) (xy 15.069959 -144.094736) (xy 15.131733 -144.272482)
			(xy 15.186024 -144.452654) (xy 15.232738 -144.634938) (xy 15.271792 -144.819015) (xy 15.303016 -145.003958)
			(xy 17.842734 -145.003958) (xy 17.842734 -144.919262) (xy 17.850785 -144.834948) (xy 17.866814 -144.751782)
			(xy 17.890675 -144.670515) (xy 17.922154 -144.591885) (xy 17.960965 -144.516604) (xy 18.006755 -144.445352)
			(xy 18.059111 -144.378776) (xy 18.117559 -144.317478) (xy 18.181569 -144.262013) (xy 18.250561 -144.212884)
			(xy 18.323911 -144.170535) (xy 18.400954 -144.135351) (xy 18.480993 -144.107649) (xy 18.563302 -144.087681)
			(xy 18.647137 -144.075628) (xy 18.731738 -144.071598) (xy 18.816339 -144.075628) (xy 18.900174 -144.087681)
			(xy 18.982483 -144.107649) (xy 19.062522 -144.135351) (xy 19.139565 -144.170535) (xy 19.212915 -144.212884)
			(xy 19.281907 -144.262013) (xy 19.345917 -144.317478) (xy 19.404365 -144.378776) (xy 19.456721 -144.445352)
			(xy 19.502511 -144.516604) (xy 19.541322 -144.591885) (xy 19.547457 -144.60721) (xy 23.748996 -144.60721)
			(xy 23.748996 -144.522514) (xy 23.757047 -144.4382) (xy 23.773076 -144.355034) (xy 23.796937 -144.273767)
			(xy 23.828416 -144.195137) (xy 23.867227 -144.119856) (xy 23.913017 -144.048604) (xy 23.965373 -143.982028)
			(xy 24.023821 -143.92073) (xy 24.087831 -143.865265) (xy 24.156823 -143.816136) (xy 24.230173 -143.773787)
			(xy 24.307216 -143.738603) (xy 24.387255 -143.710901) (xy 24.469564 -143.690933) (xy 24.553399 -143.67888)
			(xy 24.638 -143.67485) (xy 24.722601 -143.67888) (xy 24.806436 -143.690933) (xy 24.888745 -143.710901)
			(xy 24.968784 -143.738603) (xy 25.045827 -143.773787) (xy 25.119177 -143.816136) (xy 25.188169 -143.865265)
			(xy 25.252179 -143.92073) (xy 25.310627 -143.982028) (xy 25.362983 -144.048604) (xy 25.408773 -144.119856)
			(xy 25.447584 -144.195137) (xy 25.479063 -144.273767) (xy 25.502924 -144.355034) (xy 25.518953 -144.4382)
			(xy 25.527004 -144.522514) (xy 25.527508 -144.564862) (xy 25.527004 -144.60721) (xy 25.518953 -144.691524)
			(xy 25.502924 -144.77469) (xy 25.479063 -144.855957) (xy 25.447584 -144.934587) (xy 25.408773 -145.009868)
			(xy 25.362983 -145.08112) (xy 25.310627 -145.147696) (xy 25.252179 -145.208994) (xy 25.188169 -145.264459)
			(xy 25.119177 -145.313588) (xy 25.045827 -145.355937) (xy 24.968784 -145.391121) (xy 24.888745 -145.418823)
			(xy 24.806436 -145.438791) (xy 24.722601 -145.450844) (xy 24.638 -145.454875) (xy 24.553399 -145.450844)
			(xy 24.469564 -145.438791) (xy 24.387255 -145.418823) (xy 24.307216 -145.391121) (xy 24.230173 -145.355937)
			(xy 24.156823 -145.313588) (xy 24.087831 -145.264459) (xy 24.023821 -145.208994) (xy 23.965373 -145.147696)
			(xy 23.913017 -145.08112) (xy 23.867227 -145.009868) (xy 23.828416 -144.934587) (xy 23.796937 -144.855957)
			(xy 23.773076 -144.77469) (xy 23.757047 -144.691524) (xy 23.748996 -144.60721) (xy 19.547457 -144.60721)
			(xy 19.572801 -144.670515) (xy 19.596662 -144.751782) (xy 19.612691 -144.834948) (xy 19.620742 -144.919262)
			(xy 19.621246 -144.96161) (xy 19.620742 -145.003958) (xy 19.612691 -145.088272) (xy 19.596662 -145.171438)
			(xy 19.572801 -145.252705) (xy 19.541322 -145.331335) (xy 19.502511 -145.406616) (xy 19.456721 -145.477868)
			(xy 19.404365 -145.544444) (xy 19.345917 -145.605742) (xy 19.281907 -145.661207) (xy 19.212915 -145.710336)
			(xy 19.139565 -145.752685) (xy 19.070455 -145.784246) (xy 28.521148 -145.784246) (xy 28.521148 -145.69955)
			(xy 28.529199 -145.615236) (xy 28.545228 -145.53207) (xy 28.569089 -145.450803) (xy 28.600568 -145.372173)
			(xy 28.639379 -145.296892) (xy 28.685169 -145.22564) (xy 28.737525 -145.159064) (xy 28.795973 -145.097766)
			(xy 28.859983 -145.042301) (xy 28.928975 -144.993172) (xy 29.002325 -144.950823) (xy 29.079368 -144.915639)
			(xy 29.159407 -144.887937) (xy 29.241716 -144.867969) (xy 29.325551 -144.855916) (xy 29.410152 -144.851886)
			(xy 29.494753 -144.855916) (xy 29.578588 -144.867969) (xy 29.660897 -144.887937) (xy 29.740936 -144.915639)
			(xy 29.817979 -144.950823) (xy 29.891329 -144.993172) (xy 29.960321 -145.042301) (xy 30.024331 -145.097766)
			(xy 30.082779 -145.159064) (xy 30.135135 -145.22564) (xy 30.180925 -145.296892) (xy 30.219736 -145.372173)
			(xy 30.251215 -145.450803) (xy 30.275076 -145.53207) (xy 30.291105 -145.615236) (xy 30.299156 -145.69955)
			(xy 30.29966 -145.741898) (xy 30.299156 -145.784246) (xy 30.291105 -145.86856) (xy 30.275076 -145.951726)
			(xy 30.251215 -146.032993) (xy 30.219736 -146.111623) (xy 30.180925 -146.186904) (xy 30.135135 -146.258156)
			(xy 30.082779 -146.324732) (xy 30.024331 -146.38603) (xy 29.960321 -146.441495) (xy 29.891329 -146.490624)
			(xy 29.817979 -146.532973) (xy 29.740936 -146.568157) (xy 29.660897 -146.595859) (xy 29.578588 -146.615827)
			(xy 29.494753 -146.62788) (xy 29.410152 -146.631911) (xy 29.325551 -146.62788) (xy 29.241716 -146.615827)
			(xy 29.159407 -146.595859) (xy 29.079368 -146.568157) (xy 29.002325 -146.532973) (xy 28.928975 -146.490624)
			(xy 28.859983 -146.441495) (xy 28.795973 -146.38603) (xy 28.737525 -146.324732) (xy 28.685169 -146.258156)
			(xy 28.639379 -146.186904) (xy 28.600568 -146.111623) (xy 28.569089 -146.032993) (xy 28.545228 -145.951726)
			(xy 28.529199 -145.86856) (xy 28.521148 -145.784246) (xy 19.070455 -145.784246) (xy 19.062522 -145.787869)
			(xy 18.982483 -145.815571) (xy 18.900174 -145.835539) (xy 18.816339 -145.847592) (xy 18.731738 -145.851623)
			(xy 18.647137 -145.847592) (xy 18.563302 -145.835539) (xy 18.480993 -145.815571) (xy 18.400954 -145.787869)
			(xy 18.323911 -145.752685) (xy 18.250561 -145.710336) (xy 18.181569 -145.661207) (xy 18.117559 -145.605742)
			(xy 18.059111 -145.544444) (xy 18.006755 -145.477868) (xy 17.960965 -145.406616) (xy 17.922154 -145.331335)
			(xy 17.890675 -145.252705) (xy 17.866814 -145.171438) (xy 17.850785 -145.088272) (xy 17.842734 -145.003958)
			(xy 15.303016 -145.003958) (xy 15.303118 -145.004563) (xy 15.326662 -145.191259) (xy 15.342383 -145.378775)
			(xy 15.350252 -145.566785) (xy 15.350744 -145.660872) (xy 15.350744 -147.743348) (xy 29.590996 -147.743348)
			(xy 29.590996 -147.658652) (xy 29.599047 -147.574338) (xy 29.615076 -147.491172) (xy 29.638937 -147.409905)
			(xy 29.670416 -147.331275) (xy 29.709227 -147.255994) (xy 29.755017 -147.184742) (xy 29.807373 -147.118166)
			(xy 29.865821 -147.056868) (xy 29.929831 -147.001403) (xy 29.998823 -146.952274) (xy 30.072173 -146.909925)
			(xy 30.149216 -146.874741) (xy 30.229255 -146.847039) (xy 30.311564 -146.827071) (xy 30.395399 -146.815018)
			(xy 30.48 -146.810988) (xy 30.564601 -146.815018) (xy 30.648436 -146.827071) (xy 30.730745 -146.847039)
			(xy 30.810784 -146.874741) (xy 30.887827 -146.909925) (xy 30.961177 -146.952274) (xy 31.030169 -147.001403)
			(xy 31.094179 -147.056868) (xy 31.152627 -147.118166) (xy 31.204983 -147.184742) (xy 31.250773 -147.255994)
			(xy 31.289584 -147.331275) (xy 31.321063 -147.409905) (xy 31.344924 -147.491172) (xy 31.360953 -147.574338)
			(xy 31.369004 -147.658652) (xy 31.369508 -147.701) (xy 31.369004 -147.743348) (xy 31.360953 -147.827662)
			(xy 31.344924 -147.910828) (xy 31.321063 -147.992095) (xy 31.289584 -148.070725) (xy 31.250773 -148.146006)
			(xy 31.204983 -148.217258) (xy 31.152627 -148.283834) (xy 31.094179 -148.345132) (xy 31.030169 -148.400597)
			(xy 30.961177 -148.449726) (xy 30.887827 -148.492075) (xy 30.810784 -148.527259) (xy 30.730745 -148.554961)
			(xy 30.648436 -148.574929) (xy 30.564601 -148.586982) (xy 30.48 -148.591013) (xy 30.395399 -148.586982)
			(xy 30.311564 -148.574929) (xy 30.229255 -148.554961) (xy 30.149216 -148.527259) (xy 30.072173 -148.492075)
			(xy 29.998823 -148.449726) (xy 29.929831 -148.400597) (xy 29.865821 -148.345132) (xy 29.807373 -148.283834)
			(xy 29.755017 -148.217258) (xy 29.709227 -148.146006) (xy 29.670416 -148.070725) (xy 29.638937 -147.992095)
			(xy 29.615076 -147.910828) (xy 29.599047 -147.827662) (xy 29.590996 -147.743348) (xy 15.350744 -147.743348)
			(xy 15.350744 -150.156348) (xy 28.066996 -150.156348) (xy 28.066996 -150.071652) (xy 28.075047 -149.987338)
			(xy 28.091076 -149.904172) (xy 28.114937 -149.822905) (xy 28.146416 -149.744275) (xy 28.185227 -149.668994)
			(xy 28.231017 -149.597742) (xy 28.283373 -149.531166) (xy 28.341821 -149.469868) (xy 28.405831 -149.414403)
			(xy 28.474823 -149.365274) (xy 28.548173 -149.322925) (xy 28.625216 -149.287741) (xy 28.705255 -149.260039)
			(xy 28.787564 -149.240071) (xy 28.871399 -149.228018) (xy 28.956 -149.223988) (xy 29.040601 -149.228018)
			(xy 29.124436 -149.240071) (xy 29.206745 -149.260039) (xy 29.286784 -149.287741) (xy 29.363827 -149.322925)
			(xy 29.437177 -149.365274) (xy 29.506169 -149.414403) (xy 29.570179 -149.469868) (xy 29.628627 -149.531166)
			(xy 29.680983 -149.597742) (xy 29.726773 -149.668994) (xy 29.765584 -149.744275) (xy 29.797063 -149.822905)
			(xy 29.820924 -149.904172) (xy 29.836953 -149.987338) (xy 29.845004 -150.071652) (xy 29.845508 -150.114)
			(xy 29.845004 -150.156348) (xy 29.836953 -150.240662) (xy 29.820924 -150.323828) (xy 29.797063 -150.405095)
			(xy 29.765584 -150.483725) (xy 29.726773 -150.559006) (xy 29.680983 -150.630258) (xy 29.628627 -150.696834)
			(xy 29.570179 -150.758132) (xy 29.506169 -150.813597) (xy 29.437177 -150.862726) (xy 29.363827 -150.905075)
			(xy 29.286784 -150.940259) (xy 29.206745 -150.967961) (xy 29.124436 -150.987929) (xy 29.040601 -150.999982)
			(xy 28.956 -151.004013) (xy 28.871399 -150.999982) (xy 28.787564 -150.987929) (xy 28.705255 -150.967961)
			(xy 28.625216 -150.940259) (xy 28.548173 -150.905075) (xy 28.474823 -150.862726) (xy 28.405831 -150.813597)
			(xy 28.341821 -150.758132) (xy 28.283373 -150.696834) (xy 28.231017 -150.630258) (xy 28.185227 -150.559006)
			(xy 28.146416 -150.483725) (xy 28.114937 -150.405095) (xy 28.091076 -150.323828) (xy 28.075047 -150.240662)
			(xy 28.066996 -150.156348) (xy 15.350744 -150.156348) (xy 15.350744 -154.53995) (xy 17.906492 -154.53995)
			(xy 17.906996 -154.497602) (xy 17.915047 -154.413288) (xy 17.931076 -154.330122) (xy 17.954937 -154.248855)
			(xy 17.986416 -154.170225) (xy 18.025227 -154.094944) (xy 18.071017 -154.023692) (xy 18.123373 -153.957116)
			(xy 18.181821 -153.895818) (xy 18.245831 -153.840353) (xy 18.314823 -153.791224) (xy 18.388173 -153.748875)
			(xy 18.465216 -153.713691) (xy 18.545255 -153.685989) (xy 18.627564 -153.666021) (xy 18.711399 -153.653968)
			(xy 18.796 -153.649938) (xy 18.880601 -153.653968) (xy 18.964436 -153.666021) (xy 19.046745 -153.685989)
			(xy 19.126784 -153.713691) (xy 19.203827 -153.748875) (xy 19.277177 -153.791224) (xy 19.346169 -153.840353)
			(xy 19.410179 -153.895818) (xy 19.468627 -153.957116) (xy 19.520983 -154.023692) (xy 19.566773 -154.094944)
			(xy 19.605584 -154.170225) (xy 19.637063 -154.248855) (xy 19.660924 -154.330122) (xy 19.676953 -154.413288)
			(xy 19.685004 -154.497602) (xy 19.685508 -154.53995) (xy 19.684996 -154.582445) (xy 19.676849 -154.667046)
			(xy 19.669252 -154.70886) (xy 19.667683 -154.720435) (xy 19.673886 -154.742926) (xy 19.68119 -154.75204)
			(xy 19.707409 -154.782459) (xy 19.754838 -154.847272) (xy 19.796231 -154.916096) (xy 19.831253 -154.988371)
			(xy 19.859618 -155.063509) (xy 19.881095 -155.140897) (xy 19.895509 -155.219907) (xy 19.902744 -155.299893)
			(xy 19.903186 -155.34005) (xy 19.902682 -155.382398) (xy 19.894631 -155.466712) (xy 19.878602 -155.549878)
			(xy 19.854741 -155.631145) (xy 19.823262 -155.709775) (xy 19.784451 -155.785056) (xy 19.738661 -155.856308)
			(xy 19.686305 -155.922884) (xy 19.627857 -155.984182) (xy 19.563847 -156.039647) (xy 19.494855 -156.088776)
			(xy 19.421505 -156.131125) (xy 19.344462 -156.166309) (xy 19.264423 -156.194011) (xy 19.182114 -156.213979)
			(xy 19.098279 -156.226032) (xy 19.013678 -156.230063) (xy 18.929077 -156.226032) (xy 18.845242 -156.213979)
			(xy 18.762933 -156.194011) (xy 18.682894 -156.166309) (xy 18.605851 -156.131125) (xy 18.532501 -156.088776)
			(xy 18.463509 -156.039647) (xy 18.399499 -155.984182) (xy 18.341051 -155.922884) (xy 18.288695 -155.856308)
			(xy 18.242905 -155.785056) (xy 18.204094 -155.709775) (xy 18.172615 -155.631145) (xy 18.148754 -155.549878)
			(xy 18.132725 -155.466712) (xy 18.124674 -155.382398) (xy 18.12417 -155.34005) (xy 18.124683 -155.297555)
			(xy 18.132829 -155.212954) (xy 18.140426 -155.17114) (xy 18.142 -155.159565) (xy 18.135795 -155.137073)
			(xy 18.128488 -155.12796) (xy 18.102265 -155.097545) (xy 18.054837 -155.03273) (xy 18.013445 -154.963905)
			(xy 17.978424 -154.89163) (xy 17.950059 -154.816492) (xy 17.928583 -154.739103) (xy 17.914169 -154.660094)
			(xy 17.906934 -154.580107) (xy 17.906492 -154.53995) (xy 15.350744 -154.53995) (xy 15.350744 -156.760348)
			(xy 24.201116 -156.760348) (xy 24.201116 -156.675652) (xy 24.209167 -156.591338) (xy 24.225196 -156.508172)
			(xy 24.249057 -156.426905) (xy 24.280536 -156.348275) (xy 24.319347 -156.272994) (xy 24.365137 -156.201742)
			(xy 24.417493 -156.135166) (xy 24.475941 -156.073868) (xy 24.539951 -156.018403) (xy 24.608943 -155.969274)
			(xy 24.682293 -155.926925) (xy 24.759336 -155.891741) (xy 24.839375 -155.864039) (xy 24.921684 -155.844071)
			(xy 25.005519 -155.832018) (xy 25.09012 -155.827988) (xy 25.174721 -155.832018) (xy 25.258556 -155.844071)
			(xy 25.340865 -155.864039) (xy 25.420904 -155.891741) (xy 25.497947 -155.926925) (xy 25.571297 -155.969274)
			(xy 25.640289 -156.018403) (xy 25.704299 -156.073868) (xy 25.762747 -156.135166) (xy 25.815103 -156.201742)
			(xy 25.860893 -156.272994) (xy 25.899704 -156.348275) (xy 25.931183 -156.426905) (xy 25.955044 -156.508172)
			(xy 25.971073 -156.591338) (xy 25.979124 -156.675652) (xy 25.979628 -156.718) (xy 25.979124 -156.760348)
			(xy 25.971073 -156.844662) (xy 25.955044 -156.927828) (xy 25.931183 -157.009095) (xy 25.899704 -157.087725)
			(xy 25.860893 -157.163006) (xy 25.815103 -157.234258) (xy 25.762747 -157.300834) (xy 25.704299 -157.362132)
			(xy 25.640289 -157.417597) (xy 25.571297 -157.466726) (xy 25.497947 -157.509075) (xy 25.420904 -157.544259)
			(xy 25.340865 -157.571961) (xy 25.258556 -157.591929) (xy 25.174721 -157.603982) (xy 25.09012 -157.608013)
			(xy 25.005519 -157.603982) (xy 24.921684 -157.591929) (xy 24.839375 -157.571961) (xy 24.759336 -157.544259)
			(xy 24.682293 -157.509075) (xy 24.608943 -157.466726) (xy 24.539951 -157.417597) (xy 24.475941 -157.362132)
			(xy 24.417493 -157.300834) (xy 24.365137 -157.234258) (xy 24.319347 -157.163006) (xy 24.280536 -157.087725)
			(xy 24.249057 -157.009095) (xy 24.225196 -156.927828) (xy 24.209167 -156.844662) (xy 24.201116 -156.760348)
			(xy 15.350744 -156.760348) (xy 15.350744 -157.661102) (xy 15.35025 -157.755366) (xy 15.342356 -157.94373)
			(xy 15.32658 -158.131597) (xy 15.302951 -158.318639) (xy 15.27151 -158.504528) (xy 15.258923 -158.563748)
			(xy 20.269196 -158.563748) (xy 20.269196 -158.479052) (xy 20.277247 -158.394738) (xy 20.293276 -158.311572)
			(xy 20.317137 -158.230305) (xy 20.348616 -158.151675) (xy 20.387427 -158.076394) (xy 20.433217 -158.005142)
			(xy 20.485573 -157.938566) (xy 20.544021 -157.877268) (xy 20.608031 -157.821803) (xy 20.677023 -157.772674)
			(xy 20.750373 -157.730325) (xy 20.827416 -157.695141) (xy 20.907455 -157.667439) (xy 20.989764 -157.647471)
			(xy 21.073599 -157.635418) (xy 21.1582 -157.631388) (xy 21.242801 -157.635418) (xy 21.326636 -157.647471)
			(xy 21.382824 -157.661102) (xy 36.349432 -157.661102) (xy 36.349432 -145.660872) (xy 36.349926 -145.566608)
			(xy 36.35782 -145.378244) (xy 36.373596 -145.190377) (xy 36.397225 -145.003335) (xy 36.428666 -144.817446)
			(xy 36.467863 -144.633037) (xy 36.514748 -144.450432) (xy 36.569239 -144.26995) (xy 36.63124 -144.091908)
			(xy 36.700642 -143.916618) (xy 36.777323 -143.744389) (xy 36.86115 -143.575521) (xy 36.951974 -143.410312)
			(xy 37.049637 -143.249052) (xy 37.153967 -143.092022) (xy 37.264782 -142.939499) (xy 37.381886 -142.79175)
			(xy 37.505074 -142.649035) (xy 37.634131 -142.511604) (xy 37.76883 -142.379697) (xy 37.908934 -142.253547)
			(xy 38.054198 -142.133374) (xy 38.204366 -142.01939) (xy 38.359177 -141.911794) (xy 38.518357 -141.810775)
			(xy 38.681627 -141.716511) (xy 38.848702 -141.629166) (xy 39.019288 -141.548895) (xy 39.193085 -141.475837)
			(xy 39.36979 -141.410121) (xy 39.549091 -141.351863) (xy 39.730675 -141.301163) (xy 39.914223 -141.258113)
			(xy 40.099412 -141.222786) (xy 40.285918 -141.195245) (xy 40.473414 -141.175539) (xy 40.661571 -141.163701)
			(xy 40.850058 -141.159753) (xy 41.038545 -141.163701) (xy 41.226702 -141.175539) (xy 41.414198 -141.195245)
			(xy 41.600704 -141.222786) (xy 41.785893 -141.258113) (xy 41.969441 -141.301163) (xy 42.151025 -141.351863)
			(xy 42.330326 -141.410121) (xy 42.507031 -141.475837) (xy 42.680828 -141.548895) (xy 42.851414 -141.629166)
			(xy 43.018489 -141.716511) (xy 43.181759 -141.810775) (xy 43.340939 -141.911794) (xy 43.49575 -142.01939)
			(xy 43.645918 -142.133374) (xy 43.791182 -142.253547) (xy 43.931286 -142.379697) (xy 44.065985 -142.511604)
			(xy 44.195042 -142.649035) (xy 44.31823 -142.79175) (xy 44.435334 -142.939499) (xy 44.546149 -143.092022)
			(xy 44.650479 -143.249052) (xy 44.748142 -143.410312) (xy 44.838966 -143.575521) (xy 44.922793 -143.744389)
			(xy 44.999474 -143.916618) (xy 45.068876 -144.091908) (xy 45.130877 -144.26995) (xy 45.185368 -144.450432)
			(xy 45.232253 -144.633037) (xy 45.27145 -144.817446) (xy 45.302891 -145.003335) (xy 45.32652 -145.190377)
			(xy 45.342296 -145.378244) (xy 45.35019 -145.566608) (xy 45.350684 -145.660872) (xy 45.350684 -157.661102)
			(xy 45.35019 -157.755366) (xy 45.342296 -157.94373) (xy 45.32652 -158.131597) (xy 45.302891 -158.318639)
			(xy 45.27145 -158.504528) (xy 45.232253 -158.688937) (xy 45.185368 -158.871542) (xy 45.130877 -159.052024)
			(xy 45.068876 -159.230066) (xy 44.999474 -159.405356) (xy 44.922793 -159.577585) (xy 44.838966 -159.746453)
			(xy 44.748142 -159.911662) (xy 44.650479 -160.072922) (xy 44.546149 -160.229952) (xy 44.435334 -160.382475)
			(xy 44.31823 -160.530224) (xy 44.195042 -160.672939) (xy 44.065985 -160.81037) (xy 43.931286 -160.942277)
			(xy 43.791182 -161.068427) (xy 43.645918 -161.1886) (xy 43.49575 -161.302584) (xy 43.340939 -161.41018)
			(xy 43.181759 -161.511199) (xy 43.018489 -161.605463) (xy 42.851414 -161.692808) (xy 42.680828 -161.773079)
			(xy 42.507031 -161.846137) (xy 42.330326 -161.911853) (xy 42.151025 -161.970111) (xy 41.969441 -162.020811)
			(xy 41.785893 -162.063861) (xy 41.600704 -162.099188) (xy 41.414198 -162.126729) (xy 41.226702 -162.146435)
			(xy 41.038545 -162.158273) (xy 40.850058 -162.162222) (xy 40.661571 -162.158273) (xy 40.473414 -162.146435)
			(xy 40.285918 -162.126729) (xy 40.099412 -162.099188) (xy 39.914223 -162.063861) (xy 39.730675 -162.020811)
			(xy 39.549091 -161.970111) (xy 39.36979 -161.911853) (xy 39.193085 -161.846137) (xy 39.019288 -161.773079)
			(xy 38.848702 -161.692808) (xy 38.681627 -161.605463) (xy 38.518357 -161.511199) (xy 38.359177 -161.41018)
			(xy 38.204366 -161.302584) (xy 38.054198 -161.1886) (xy 37.908934 -161.068427) (xy 37.76883 -160.942277)
			(xy 37.634131 -160.81037) (xy 37.505074 -160.672939) (xy 37.381886 -160.530224) (xy 37.264782 -160.382475)
			(xy 37.153967 -160.229952) (xy 37.049637 -160.072922) (xy 36.951974 -159.911662) (xy 36.86115 -159.746453)
			(xy 36.777323 -159.577585) (xy 36.700642 -159.405356) (xy 36.63124 -159.230066) (xy 36.569239 -159.052024)
			(xy 36.514748 -158.871542) (xy 36.467863 -158.688937) (xy 36.428666 -158.504528) (xy 36.397225 -158.318639)
			(xy 36.373596 -158.131597) (xy 36.35782 -157.94373) (xy 36.349926 -157.755366) (xy 36.349432 -157.661102)
			(xy 21.382824 -157.661102) (xy 21.408945 -157.667439) (xy 21.488984 -157.695141) (xy 21.566027 -157.730325)
			(xy 21.639377 -157.772674) (xy 21.708369 -157.821803) (xy 21.772379 -157.877268) (xy 21.830827 -157.938566)
			(xy 21.883183 -158.005142) (xy 21.928973 -158.076394) (xy 21.967784 -158.151675) (xy 21.999263 -158.230305)
			(xy 22.023124 -158.311572) (xy 22.039153 -158.394738) (xy 22.047204 -158.479052) (xy 22.047708 -158.5214)
			(xy 22.047204 -158.563748) (xy 22.042468 -158.61335) (xy 25.281385 -158.61335) (xy 25.285416 -158.528749)
			(xy 25.297469 -158.444914) (xy 25.317437 -158.362604) (xy 25.345139 -158.282565) (xy 25.380323 -158.205522)
			(xy 25.422672 -158.132172) (xy 25.471801 -158.06318) (xy 25.527266 -157.99917) (xy 25.588564 -157.940723)
			(xy 25.65514 -157.888366) (xy 25.726392 -157.842576) (xy 25.801673 -157.803765) (xy 25.880303 -157.772286)
			(xy 25.961569 -157.748424) (xy 26.044736 -157.732395) (xy 26.129049 -157.724344) (xy 26.171398 -157.72384)
			(xy 26.214242 -157.72433) (xy 26.299536 -157.732552) (xy 26.383643 -157.74894) (xy 26.465784 -157.773341)
			(xy 26.545197 -157.805529) (xy 26.621146 -157.845205) (xy 26.692927 -157.892003) (xy 26.759875 -157.945487)
			(xy 26.821368 -158.005163) (xy 26.876836 -158.070476) (xy 26.925765 -158.140821) (xy 26.967702 -158.215546)
			(xy 27.002258 -158.293958) (xy 27.029111 -158.37533) (xy 27.039062 -158.417006) (xy 27.041602 -158.428436)
			(xy 27.05608 -158.446724) (xy 27.15006 -158.49092) (xy 27.173174 -158.490666) (xy 27.183842 -158.485332)
			(xy 27.221185 -158.467022) (xy 27.298611 -158.436632) (xy 27.378533 -158.413596) (xy 27.460256 -158.398116)
			(xy 27.543066 -158.390326) (xy 27.584654 -158.389828) (xy 27.627002 -158.39034) (xy 27.711315 -158.398391)
			(xy 27.794481 -158.41442) (xy 27.875746 -158.438282) (xy 27.954376 -158.469761) (xy 28.029657 -158.508571)
			(xy 28.100908 -158.554362) (xy 28.167483 -158.606718) (xy 28.228781 -158.665165) (xy 28.284245 -158.729175)
			(xy 28.333374 -158.798166) (xy 28.375722 -158.871516) (xy 28.410906 -158.948558) (xy 28.438607 -159.028596)
			(xy 28.458575 -159.110905) (xy 28.470628 -159.19474) (xy 28.474659 -159.27934) (xy 28.470628 -159.36394)
			(xy 28.458575 -159.447775) (xy 28.438607 -159.530084) (xy 28.410906 -159.610122) (xy 28.375722 -159.687164)
			(xy 28.333374 -159.760514) (xy 28.284245 -159.829505) (xy 28.228781 -159.893515) (xy 28.167483 -159.951962)
			(xy 28.100908 -160.004318) (xy 28.029657 -160.050109) (xy 27.954376 -160.088919) (xy 27.875746 -160.120398)
			(xy 27.794481 -160.14426) (xy 27.711315 -160.160289) (xy 27.627002 -160.16834) (xy 27.584654 -160.168844)
			(xy 27.541808 -160.168411) (xy 27.456513 -160.160184) (xy 27.372404 -160.143792) (xy 27.290262 -160.119386)
			(xy 27.210848 -160.087193) (xy 27.134898 -160.047512) (xy 27.063117 -160.00071) (xy 26.996169 -159.947221)
			(xy 26.934677 -159.887542) (xy 26.879209 -159.822224) (xy 26.830281 -159.751875) (xy 26.788346 -159.677147)
			(xy 26.753792 -159.598731) (xy 26.72694 -159.517355) (xy 26.71699 -159.475678) (xy 26.71445 -159.464248)
			(xy 26.699972 -159.44596) (xy 26.605992 -159.401764) (xy 26.582878 -159.402018) (xy 26.57221 -159.407352)
			(xy 26.534874 -159.425679) (xy 26.457447 -159.456066) (xy 26.377522 -159.479098) (xy 26.295798 -159.494574)
			(xy 26.212986 -159.502361) (xy 26.171398 -159.502856) (xy 26.129049 -159.502356) (xy 26.044736 -159.494305)
			(xy 25.961569 -159.478276) (xy 25.880303 -159.454414) (xy 25.801673 -159.422935) (xy 25.726392 -159.384124)
			(xy 25.65514 -159.338334) (xy 25.588564 -159.285977) (xy 25.527266 -159.22753) (xy 25.471801 -159.16352)
			(xy 25.422672 -159.094528) (xy 25.380323 -159.021178) (xy 25.345139 -158.944135) (xy 25.317437 -158.864096)
			(xy 25.297469 -158.781786) (xy 25.285416 -158.697951) (xy 25.281385 -158.61335) (xy 22.042468 -158.61335)
			(xy 22.039153 -158.648062) (xy 22.023124 -158.731228) (xy 21.999263 -158.812495) (xy 21.967784 -158.891125)
			(xy 21.928973 -158.966406) (xy 21.883183 -159.037658) (xy 21.830827 -159.104234) (xy 21.772379 -159.165532)
			(xy 21.708369 -159.220997) (xy 21.639377 -159.270126) (xy 21.566027 -159.312475) (xy 21.488984 -159.347659)
			(xy 21.408945 -159.375361) (xy 21.326636 -159.395329) (xy 21.242801 -159.407382) (xy 21.1582 -159.411413)
			(xy 21.073599 -159.407382) (xy 20.989764 -159.395329) (xy 20.907455 -159.375361) (xy 20.827416 -159.347659)
			(xy 20.750373 -159.312475) (xy 20.677023 -159.270126) (xy 20.608031 -159.220997) (xy 20.544021 -159.165532)
			(xy 20.485573 -159.104234) (xy 20.433217 -159.037658) (xy 20.387427 -158.966406) (xy 20.348616 -158.891125)
			(xy 20.317137 -158.812495) (xy 20.293276 -158.731228) (xy 20.277247 -158.648062) (xy 20.269196 -158.563748)
			(xy 15.258923 -158.563748) (xy 15.232313 -158.688937) (xy 15.185428 -158.871542) (xy 15.130937 -159.052024)
			(xy 15.068936 -159.230066) (xy 14.999534 -159.405356) (xy 14.922853 -159.577585) (xy 14.839026 -159.746453)
			(xy 14.748202 -159.911662) (xy 14.650539 -160.072922) (xy 14.546209 -160.229952) (xy 14.435394 -160.382475)
			(xy 14.31829 -160.530224) (xy 14.195102 -160.672939) (xy 14.066045 -160.81037) (xy 13.931346 -160.942277)
			(xy 13.824435 -161.03854) (xy 19.03857 -161.03854) (xy 19.039074 -160.996192) (xy 19.047125 -160.911878)
			(xy 19.063154 -160.828712) (xy 19.087015 -160.747445) (xy 19.118494 -160.668815) (xy 19.157305 -160.593534)
			(xy 19.203095 -160.522282) (xy 19.255451 -160.455706) (xy 19.313899 -160.394408) (xy 19.377909 -160.338943)
			(xy 19.446901 -160.289814) (xy 19.520251 -160.247465) (xy 19.597294 -160.212281) (xy 19.677333 -160.184579)
			(xy 19.759642 -160.164611) (xy 19.843477 -160.152558) (xy 19.928078 -160.148528) (xy 20.012679 -160.152558)
			(xy 20.096514 -160.164611) (xy 20.178823 -160.184579) (xy 20.258862 -160.212281) (xy 20.335905 -160.247465)
			(xy 20.409255 -160.289814) (xy 20.478247 -160.338943) (xy 20.542257 -160.394408) (xy 20.600705 -160.455706)
			(xy 20.653061 -160.522282) (xy 20.698851 -160.593534) (xy 20.737662 -160.668815) (xy 20.769141 -160.747445)
			(xy 20.793002 -160.828712) (xy 20.809031 -160.911878) (xy 20.817082 -160.996192) (xy 20.817586 -161.03854)
			(xy 20.817044 -161.082726) (xy 20.808277 -161.170661) (xy 20.799585 -161.2138) (xy 21.335492 -161.2138)
			(xy 21.335996 -161.171452) (xy 21.344047 -161.087138) (xy 21.360076 -161.003972) (xy 21.383937 -160.922705)
			(xy 21.415416 -160.844075) (xy 21.454227 -160.768794) (xy 21.500017 -160.697542) (xy 21.552373 -160.630966)
			(xy 21.610821 -160.569668) (xy 21.674831 -160.514203) (xy 21.743823 -160.465074) (xy 21.817173 -160.422725)
			(xy 21.894216 -160.387541) (xy 21.974255 -160.359839) (xy 22.056564 -160.339871) (xy 22.140399 -160.327818)
			(xy 22.225 -160.323788) (xy 22.309601 -160.327818) (xy 22.393436 -160.339871) (xy 22.475745 -160.359839)
			(xy 22.555784 -160.387541) (xy 22.632827 -160.422725) (xy 22.706177 -160.465074) (xy 22.775169 -160.514203)
			(xy 22.839179 -160.569668) (xy 22.897627 -160.630966) (xy 22.949983 -160.697542) (xy 22.995773 -160.768794)
			(xy 23.034584 -160.844075) (xy 23.066063 -160.922705) (xy 23.089924 -161.003972) (xy 23.105953 -161.087138)
			(xy 23.114004 -161.171452) (xy 23.114508 -161.2138) (xy 23.113961 -161.257813) (xy 23.109482 -161.30295)
			(xy 24.268926 -161.30295) (xy 24.272956 -161.218348) (xy 24.28501 -161.134511) (xy 24.304978 -161.052201)
			(xy 24.332681 -160.972161) (xy 24.367866 -160.895116) (xy 24.410215 -160.821765) (xy 24.459345 -160.752772)
			(xy 24.514811 -160.688762) (xy 24.57611 -160.630313) (xy 24.642687 -160.577956) (xy 24.71394 -160.532165)
			(xy 24.789223 -160.493354) (xy 24.867855 -160.461876) (xy 24.949122 -160.438014) (xy 25.03229 -160.421985)
			(xy 25.116605 -160.413934) (xy 25.158954 -160.413446) (xy 25.200421 -160.413912) (xy 25.282995 -160.421619)
			(xy 25.364492 -160.436981) (xy 25.444206 -160.459862) (xy 25.521444 -160.490066) (xy 25.595534 -160.527329)
			(xy 25.665833 -160.571328) (xy 25.73173 -160.62168) (xy 25.792654 -160.677949) (xy 25.848075 -160.739645)
			(xy 25.897511 -160.806233) (xy 25.91943 -160.841436) (xy 25.92705 -160.853882) (xy 25.95245 -160.866836)
			(xy 26.07183 -160.857438) (xy 26.094944 -160.840674) (xy 26.100278 -160.827212) (xy 26.117304 -160.786764)
			(xy 26.158284 -160.709154) (xy 26.206708 -160.635957) (xy 26.262104 -160.567885) (xy 26.323935 -160.505598)
			(xy 26.391598 -160.449702) (xy 26.464438 -160.400742) (xy 26.541744 -160.359192) (xy 26.622766 -160.325457)
			(xy 26.706717 -160.299865) (xy 26.792779 -160.282663) (xy 26.880118 -160.274021) (xy 26.924 -160.273492)
			(xy 26.966348 -160.273996) (xy 27.050662 -160.282047) (xy 27.133828 -160.298076) (xy 27.215095 -160.321937)
			(xy 27.293725 -160.353416) (xy 27.369006 -160.392227) (xy 27.440258 -160.438017) (xy 27.506834 -160.490373)
			(xy 27.568132 -160.548821) (xy 27.623597 -160.612831) (xy 27.672726 -160.681823) (xy 27.715075 -160.755173)
			(xy 27.750259 -160.832216) (xy 27.777961 -160.912255) (xy 27.797929 -160.994564) (xy 27.809982 -161.078399)
			(xy 27.814013 -161.163) (xy 32.511492 -161.163) (xy 32.511967 -161.121898) (xy 32.519552 -161.040043)
			(xy 32.534657 -160.959238) (xy 32.557153 -160.880171) (xy 32.586849 -160.803517) (xy 32.623491 -160.72993)
			(xy 32.666766 -160.660038) (xy 32.716306 -160.594437) (xy 32.771687 -160.533687) (xy 32.832437 -160.478306)
			(xy 32.898038 -160.428766) (xy 32.96793 -160.385491) (xy 33.041517 -160.348849) (xy 33.118171 -160.319153)
			(xy 33.197238 -160.296657) (xy 33.278043 -160.281552) (xy 33.359898 -160.273967) (xy 33.401 -160.273492)
			(xy 33.441943 -160.274018) (xy 33.523483 -160.281536) (xy 33.603988 -160.296517) (xy 33.682774 -160.318834)
			(xy 33.759175 -160.348298) (xy 33.832545 -160.384661) (xy 33.902262 -160.427613) (xy 33.967735 -160.476792)
			(xy 34.028411 -160.531781) (xy 34.083776 -160.592114) (xy 34.13336 -160.657281) (xy 34.176745 -160.72673)
			(xy 34.213562 -160.799872) (xy 34.243501 -160.876089) (xy 34.266307 -160.954736) (xy 34.274506 -160.994852)
			(xy 34.277192 -161.006001) (xy 34.290806 -161.024422) (xy 34.311083 -161.035078) (xy 34.322512 -161.036)
			(xy 34.365121 -161.038064) (xy 34.449685 -161.049347) (xy 34.53278 -161.068673) (xy 34.613643 -161.095865)
			(xy 34.691533 -161.130671) (xy 34.765733 -161.172774) (xy 34.835562 -161.221786) (xy 34.900379 -161.277258)
			(xy 34.959588 -161.338679) (xy 35.012646 -161.405485) (xy 35.059065 -161.477064) (xy 35.09842 -161.552757)
			(xy 35.130349 -161.63187) (xy 35.154558 -161.713676) (xy 35.170825 -161.797423) (xy 35.179001 -161.882344)
			(xy 35.179508 -161.925) (xy 35.179033 -161.966102) (xy 35.171448 -162.047957) (xy 35.156343 -162.128762)
			(xy 35.133847 -162.207829) (xy 35.104151 -162.284483) (xy 35.067509 -162.35807) (xy 35.024234 -162.427962)
			(xy 34.974694 -162.493563) (xy 34.919313 -162.554313) (xy 34.858563 -162.609694) (xy 34.792962 -162.659234)
			(xy 34.72307 -162.702509) (xy 34.649483 -162.739151) (xy 34.572829 -162.768847) (xy 34.493762 -162.791343)
			(xy 34.412957 -162.806448) (xy 34.331102 -162.814033) (xy 34.29 -162.814508) (xy 34.249057 -162.813982)
			(xy 34.167517 -162.806464) (xy 34.087012 -162.791483) (xy 34.008226 -162.769166) (xy 33.931825 -162.739702)
			(xy 33.858455 -162.703339) (xy 33.788738 -162.660387) (xy 33.723265 -162.611208) (xy 33.662589 -162.556219)
			(xy 33.607224 -162.495886) (xy 33.55764 -162.430719) (xy 33.514255 -162.36127) (xy 33.477438 -162.288128)
			(xy 33.447499 -162.211911) (xy 33.424693 -162.133264) (xy 33.416494 -162.093148) (xy 33.413808 -162.081999)
			(xy 33.400194 -162.063578) (xy 33.379917 -162.052922) (xy 33.368488 -162.052) (xy 33.325879 -162.049936)
			(xy 33.241315 -162.038653) (xy 33.15822 -162.019327) (xy 33.077357 -161.992135) (xy 32.999467 -161.957329)
			(xy 32.925267 -161.915226) (xy 32.855438 -161.866214) (xy 32.790621 -161.810742) (xy 32.731412 -161.749321)
			(xy 32.678354 -161.682515) (xy 32.631935 -161.610936) (xy 32.59258 -161.535243) (xy 32.560651 -161.45613)
			(xy 32.536442 -161.374324) (xy 32.520175 -161.290577) (xy 32.511999 -161.205656) (xy 32.511492 -161.163)
			(xy 27.814013 -161.163) (xy 27.809982 -161.247601) (xy 27.797929 -161.331436) (xy 27.777961 -161.413745)
			(xy 27.750259 -161.493784) (xy 27.715075 -161.570827) (xy 27.672726 -161.644177) (xy 27.623597 -161.713169)
			(xy 27.568132 -161.777179) (xy 27.506834 -161.835627) (xy 27.440258 -161.887983) (xy 27.369006 -161.933773)
			(xy 27.293725 -161.972584) (xy 27.215095 -162.004063) (xy 27.133828 -162.027924) (xy 27.050662 -162.043953)
			(xy 26.966348 -162.052004) (xy 26.924 -162.052508) (xy 26.882534 -162.05202) (xy 26.79996 -162.044317)
			(xy 26.718462 -162.02896) (xy 26.638748 -162.006081) (xy 26.56151 -161.975881) (xy 26.48742 -161.93862)
			(xy 26.41712 -161.894623) (xy 26.351222 -161.844272) (xy 26.290299 -161.788004) (xy 26.234878 -161.726308)
			(xy 26.185443 -161.659721) (xy 26.163524 -161.624518) (xy 26.155904 -161.612072) (xy 26.130504 -161.599118)
			(xy 26.011124 -161.608516) (xy 25.98801 -161.62528) (xy 25.982676 -161.638742) (xy 25.965581 -161.67916)
			(xy 25.924608 -161.756769) (xy 25.876191 -161.829966) (xy 25.820802 -161.89804) (xy 25.758978 -161.960328)
			(xy 25.691321 -162.016225) (xy 25.618489 -162.065189) (xy 25.541188 -162.106742) (xy 25.460172 -162.14048)
			(xy 25.376226 -162.166077) (xy 25.290168 -162.183283) (xy 25.202834 -162.191931) (xy 25.158954 -162.192462)
			(xy 25.116605 -162.191966) (xy 25.03229 -162.183915) (xy 24.949122 -162.167886) (xy 24.867855 -162.144024)
			(xy 24.789223 -162.112546) (xy 24.71394 -162.073735) (xy 24.642687 -162.027944) (xy 24.57611 -161.975587)
			(xy 24.514811 -161.917138) (xy 24.459345 -161.853128) (xy 24.410215 -161.784135) (xy 24.367866 -161.710784)
			(xy 24.332681 -161.633739) (xy 24.304978 -161.553699) (xy 24.28501 -161.471389) (xy 24.272956 -161.387552)
			(xy 24.268926 -161.30295) (xy 23.109482 -161.30295) (xy 23.105269 -161.345408) (xy 23.08797 -161.431716)
			(xy 23.062233 -161.515895) (xy 23.028309 -161.59712) (xy 22.986531 -161.674599) (xy 22.962362 -161.711386)
			(xy 22.957307 -161.719518) (xy 22.953142 -161.738194) (xy 22.954234 -161.747708) (xy 22.958806 -161.77768)
			(xy 22.960785 -161.787002) (xy 22.970419 -161.803423) (xy 22.977602 -161.809684) (xy 23.008962 -161.834932)
			(xy 23.067536 -161.890173) (xy 23.120877 -161.950482) (xy 23.168548 -162.015367) (xy 23.210158 -162.084295)
			(xy 23.245367 -162.156703) (xy 23.273887 -162.231997) (xy 23.295483 -162.30956) (xy 23.30998 -162.388758)
			(xy 23.317258 -162.468943) (xy 23.317708 -162.5092) (xy 23.317204 -162.551548) (xy 23.313469 -162.590664)
			(xy 29.103062 -162.590664) (xy 29.103062 -162.505968) (xy 29.111113 -162.421654) (xy 29.127142 -162.338488)
			(xy 29.151003 -162.257221) (xy 29.182482 -162.178591) (xy 29.221293 -162.10331) (xy 29.267083 -162.032058)
			(xy 29.319439 -161.965482) (xy 29.377887 -161.904184) (xy 29.441897 -161.848719) (xy 29.510889 -161.79959)
			(xy 29.584239 -161.757241) (xy 29.661282 -161.722057) (xy 29.741321 -161.694355) (xy 29.82363 -161.674387)
			(xy 29.907465 -161.662334) (xy 29.992066 -161.658304) (xy 30.076667 -161.662334) (xy 30.160502 -161.674387)
			(xy 30.242811 -161.694355) (xy 30.32285 -161.722057) (xy 30.399893 -161.757241) (xy 30.473243 -161.79959)
			(xy 30.542235 -161.848719) (xy 30.606245 -161.904184) (xy 30.664693 -161.965482) (xy 30.717049 -162.032058)
			(xy 30.762839 -162.10331) (xy 30.80165 -162.178591) (xy 30.833129 -162.257221) (xy 30.85699 -162.338488)
			(xy 30.873019 -162.421654) (xy 30.88107 -162.505968) (xy 30.881574 -162.548316) (xy 30.88107 -162.590664)
			(xy 30.873019 -162.674978) (xy 30.85699 -162.758144) (xy 30.833129 -162.839411) (xy 30.80165 -162.918041)
			(xy 30.776719 -162.9664) (xy 45.464988 -162.9664) (xy 45.469018 -162.881799) (xy 45.481071 -162.797964)
			(xy 45.501039 -162.715655) (xy 45.528741 -162.635616) (xy 45.563925 -162.558573) (xy 45.606274 -162.485223)
			(xy 45.655403 -162.416231) (xy 45.710868 -162.352221) (xy 45.772166 -162.293773) (xy 45.838742 -162.241417)
			(xy 45.909994 -162.195627) (xy 45.985275 -162.156816) (xy 46.063905 -162.125337) (xy 46.145172 -162.101476)
			(xy 46.228338 -162.085447) (xy 46.312652 -162.077396) (xy 46.355 -162.076892) (xy 46.396457 -162.077419)
			(xy 46.479012 -162.085141) (xy 46.56049 -162.10051) (xy 46.640186 -162.123392) (xy 46.717407 -162.153587)
			(xy 46.791484 -162.190836) (xy 46.861775 -162.234814) (xy 46.92767 -162.28514) (xy 46.988598 -162.341378)
			(xy 47.04403 -162.40304) (xy 47.093486 -162.469591) (xy 47.136536 -162.540454) (xy 47.1551 -162.577526)
			(xy 47.159164 -162.586162) (xy 47.173642 -162.59937) (xy 47.2567 -162.630866) (xy 47.276258 -162.630612)
			(xy 47.285148 -162.627056) (xy 47.32564 -162.61088) (xy 47.409094 -162.585596) (xy 47.494621 -162.568595)
			(xy 47.5814 -162.560038) (xy 47.625 -162.559492) (xy 47.667348 -162.559996) (xy 47.751662 -162.568047)
			(xy 47.834828 -162.584076) (xy 47.916095 -162.607937) (xy 47.994725 -162.639416) (xy 48.070006 -162.678227)
			(xy 48.141258 -162.724017) (xy 48.207834 -162.776373) (xy 48.269132 -162.834821) (xy 48.324597 -162.898831)
			(xy 48.373726 -162.967823) (xy 48.416075 -163.041173) (xy 48.451259 -163.118216) (xy 48.478961 -163.198255)
			(xy 48.498929 -163.280564) (xy 48.510982 -163.364399) (xy 48.515013 -163.449) (xy 48.510982 -163.533601)
			(xy 48.498929 -163.617436) (xy 48.478961 -163.699745) (xy 48.451259 -163.779784) (xy 48.416075 -163.856827)
			(xy 48.373726 -163.930177) (xy 48.324597 -163.999169) (xy 48.269132 -164.063179) (xy 48.207834 -164.121627)
			(xy 48.141258 -164.173983) (xy 48.070006 -164.219773) (xy 47.994725 -164.258584) (xy 47.916095 -164.290063)
			(xy 47.834828 -164.313924) (xy 47.751662 -164.329953) (xy 47.667348 -164.338004) (xy 47.625 -164.338508)
			(xy 47.583543 -164.337981) (xy 47.500988 -164.330259) (xy 47.41951 -164.31489) (xy 47.339814 -164.292008)
			(xy 47.262593 -164.261813) (xy 47.188516 -164.224564) (xy 47.118225 -164.180586) (xy 47.05233 -164.13026)
			(xy 46.991402 -164.074022) (xy 46.93597 -164.01236) (xy 46.886514 -163.945809) (xy 46.843464 -163.874946)
			(xy 46.8249 -163.837874) (xy 46.820836 -163.829238) (xy 46.806358 -163.81603) (xy 46.7233 -163.784534)
			(xy 46.703742 -163.784788) (xy 46.694852 -163.788344) (xy 46.65436 -163.80452) (xy 46.570906 -163.829804)
			(xy 46.485379 -163.846805) (xy 46.3986 -163.855362) (xy 46.355 -163.855908) (xy 46.312652 -163.855404)
			(xy 46.228338 -163.847353) (xy 46.145172 -163.831324) (xy 46.063905 -163.807463) (xy 45.985275 -163.775984)
			(xy 45.909994 -163.737173) (xy 45.838742 -163.691383) (xy 45.772166 -163.639027) (xy 45.710868 -163.580579)
			(xy 45.655403 -163.516569) (xy 45.606274 -163.447577) (xy 45.563925 -163.374227) (xy 45.528741 -163.297184)
			(xy 45.501039 -163.217145) (xy 45.481071 -163.134836) (xy 45.469018 -163.051001) (xy 45.464988 -162.9664)
			(xy 30.776719 -162.9664) (xy 30.762839 -162.993322) (xy 30.717049 -163.064574) (xy 30.664693 -163.13115)
			(xy 30.606245 -163.192448) (xy 30.542235 -163.247913) (xy 30.473243 -163.297042) (xy 30.399893 -163.339391)
			(xy 30.32285 -163.374575) (xy 30.242811 -163.402277) (xy 30.160502 -163.422245) (xy 30.076667 -163.434298)
			(xy 29.992066 -163.438329) (xy 29.907465 -163.434298) (xy 29.82363 -163.422245) (xy 29.741321 -163.402277)
			(xy 29.661282 -163.374575) (xy 29.584239 -163.339391) (xy 29.510889 -163.297042) (xy 29.441897 -163.247913)
			(xy 29.377887 -163.192448) (xy 29.319439 -163.13115) (xy 29.267083 -163.064574) (xy 29.221293 -162.993322)
			(xy 29.182482 -162.918041) (xy 29.151003 -162.839411) (xy 29.127142 -162.758144) (xy 29.111113 -162.674978)
			(xy 29.103062 -162.590664) (xy 23.313469 -162.590664) (xy 23.309153 -162.635862) (xy 23.293124 -162.719028)
			(xy 23.269263 -162.800295) (xy 23.237784 -162.878925) (xy 23.198973 -162.954206) (xy 23.153183 -163.025458)
			(xy 23.100827 -163.092034) (xy 23.042379 -163.153332) (xy 22.978369 -163.208797) (xy 22.909377 -163.257926)
			(xy 22.836027 -163.300275) (xy 22.758984 -163.335459) (xy 22.678945 -163.363161) (xy 22.596636 -163.383129)
			(xy 22.512801 -163.395182) (xy 22.4282 -163.399213) (xy 22.343599 -163.395182) (xy 22.259764 -163.383129)
			(xy 22.177455 -163.363161) (xy 22.097416 -163.335459) (xy 22.020373 -163.300275) (xy 21.947023 -163.257926)
			(xy 21.878031 -163.208797) (xy 21.814021 -163.153332) (xy 21.755573 -163.092034) (xy 21.703217 -163.025458)
			(xy 21.657427 -162.954206) (xy 21.618616 -162.878925) (xy 21.587137 -162.800295) (xy 21.563276 -162.719028)
			(xy 21.547247 -162.635862) (xy 21.539196 -162.551548) (xy 21.538692 -162.5092) (xy 21.539239 -162.465187)
			(xy 21.547931 -162.377592) (xy 21.56523 -162.291284) (xy 21.590967 -162.207105) (xy 21.624891 -162.12588)
			(xy 21.666669 -162.048401) (xy 21.690838 -162.011614) (xy 21.695893 -162.003482) (xy 21.700058 -161.984806)
			(xy 21.698966 -161.975292) (xy 21.694394 -161.94532) (xy 21.692415 -161.935998) (xy 21.682781 -161.919577)
			(xy 21.675598 -161.913316) (xy 21.644238 -161.888068) (xy 21.585664 -161.832827) (xy 21.532323 -161.772518)
			(xy 21.484652 -161.707633) (xy 21.443042 -161.638705) (xy 21.407833 -161.566297) (xy 21.379313 -161.491003)
			(xy 21.357717 -161.41344) (xy 21.34322 -161.334242) (xy 21.335942 -161.254057) (xy 21.335492 -161.2138)
			(xy 20.799585 -161.2138) (xy 20.790822 -161.257292) (xy 20.764854 -161.341761) (xy 20.748244 -161.38271)
			(xy 20.744248 -161.393912) (xy 20.74583 -161.417612) (xy 20.751292 -161.428176) (xy 20.770804 -161.462304)
			(xy 20.804434 -161.533368) (xy 20.831659 -161.607123) (xy 20.852265 -161.682994) (xy 20.866093 -161.760388)
			(xy 20.873033 -161.8387) (xy 20.873466 -161.87801) (xy 20.872962 -161.920358) (xy 20.864911 -162.004672)
			(xy 20.848882 -162.087838) (xy 20.825021 -162.169105) (xy 20.793542 -162.247735) (xy 20.754731 -162.323016)
			(xy 20.708941 -162.394268) (xy 20.656585 -162.460844) (xy 20.598137 -162.522142) (xy 20.534127 -162.577607)
			(xy 20.465135 -162.626736) (xy 20.391785 -162.669085) (xy 20.314742 -162.704269) (xy 20.234703 -162.731971)
			(xy 20.152394 -162.751939) (xy 20.068559 -162.763992) (xy 19.983958 -162.768023) (xy 19.899357 -162.763992)
			(xy 19.815522 -162.751939) (xy 19.733213 -162.731971) (xy 19.653174 -162.704269) (xy 19.576131 -162.669085)
			(xy 19.502781 -162.626736) (xy 19.433789 -162.577607) (xy 19.369779 -162.522142) (xy 19.311331 -162.460844)
			(xy 19.258975 -162.394268) (xy 19.213185 -162.323016) (xy 19.174374 -162.247735) (xy 19.142895 -162.169105)
			(xy 19.119034 -162.087838) (xy 19.103005 -162.004672) (xy 19.094954 -161.920358) (xy 19.09445 -161.87801)
			(xy 19.095006 -161.833825) (xy 19.103769 -161.74589) (xy 19.121219 -161.659259) (xy 19.147184 -161.574789)
			(xy 19.163792 -161.53384) (xy 19.167817 -161.522646) (xy 19.166215 -161.498938) (xy 19.160744 -161.488374)
			(xy 19.141246 -161.454238) (xy 19.107615 -161.383176) (xy 19.080389 -161.309422) (xy 19.05978 -161.233553)
			(xy 19.045949 -161.156161) (xy 19.039005 -161.077849) (xy 19.03857 -161.03854) (xy 13.824435 -161.03854)
			(xy 13.791242 -161.068427) (xy 13.645978 -161.1886) (xy 13.49581 -161.302584) (xy 13.340999 -161.41018)
			(xy 13.181819 -161.511199) (xy 13.018549 -161.605463) (xy 12.851474 -161.692808) (xy 12.680888 -161.773079)
			(xy 12.507091 -161.846137) (xy 12.330386 -161.911853) (xy 12.151085 -161.970111) (xy 11.969501 -162.020811)
			(xy 11.785953 -162.063861) (xy 11.600764 -162.099188) (xy 11.414258 -162.126729) (xy 11.226762 -162.146435)
			(xy 11.038605 -162.158273) (xy 10.850118 -162.162222) (xy 10.661631 -162.158273) (xy 10.473474 -162.146435)
			(xy 10.285978 -162.126729) (xy 10.099472 -162.099188) (xy 9.914283 -162.063861) (xy 9.730735 -162.020811)
			(xy 9.549151 -161.970111) (xy 9.36985 -161.911853) (xy 9.193145 -161.846137) (xy 9.019348 -161.773079)
			(xy 8.848762 -161.692808) (xy 8.681687 -161.605463) (xy 8.518417 -161.511199) (xy 8.359237 -161.41018)
			(xy 8.204426 -161.302584) (xy 8.054258 -161.1886) (xy 7.908994 -161.068427) (xy 7.76889 -160.942277)
			(xy 7.634191 -160.81037) (xy 7.505134 -160.672939) (xy 7.381946 -160.530224) (xy 7.264842 -160.382475)
			(xy 7.154027 -160.229952) (xy 7.049697 -160.072922) (xy 6.952034 -159.911662) (xy 6.86121 -159.746453)
			(xy 6.777383 -159.577585) (xy 6.700702 -159.405356) (xy 6.6313 -159.230066) (xy 6.569299 -159.052024)
			(xy 6.514808 -158.871542) (xy 6.467923 -158.688937) (xy 6.428726 -158.504528) (xy 6.397285 -158.318639)
			(xy 6.373656 -158.131597) (xy 6.35788 -157.94373) (xy 6.349986 -157.755366) (xy 6.349492 -157.661102)
			(xy 1.651254 -157.661102) (xy 1.651254 -160.140904) (xy 1.652778 -160.19145) (xy 1.651254 -160.241996)
			(xy 1.651254 -162.814) (xy 2.158492 -162.814) (xy 2.158996 -162.771652) (xy 2.167047 -162.687338)
			(xy 2.183076 -162.604172) (xy 2.206937 -162.522905) (xy 2.238416 -162.444275) (xy 2.277227 -162.368994)
			(xy 2.323017 -162.297742) (xy 2.375373 -162.231166) (xy 2.433821 -162.169868) (xy 2.497831 -162.114403)
			(xy 2.566823 -162.065274) (xy 2.640173 -162.022925) (xy 2.717216 -161.987741) (xy 2.797255 -161.960039)
			(xy 2.879564 -161.940071) (xy 2.963399 -161.928018) (xy 3.048 -161.923988) (xy 3.132601 -161.928018)
			(xy 3.216436 -161.940071) (xy 3.298745 -161.960039) (xy 3.378784 -161.987741) (xy 3.455827 -162.022925)
			(xy 3.529177 -162.065274) (xy 3.598169 -162.114403) (xy 3.662179 -162.169868) (xy 3.720627 -162.231166)
			(xy 3.772983 -162.297742) (xy 3.818773 -162.368994) (xy 3.857584 -162.444275) (xy 3.889063 -162.522905)
			(xy 3.912924 -162.604172) (xy 3.928953 -162.687338) (xy 3.937004 -162.771652) (xy 3.937508 -162.814)
			(xy 3.936987 -162.858437) (xy 3.928115 -162.946866) (xy 3.91047 -163.033971) (xy 3.884228 -163.118882)
			(xy 3.84965 -163.200753) (xy 3.807081 -163.278768) (xy 3.756945 -163.35215) (xy 3.699743 -163.420167)
			(xy 3.668268 -163.45154) (xy 3.659886 -163.459668) (xy 3.652266 -163.48075) (xy 3.660648 -163.582096)
			(xy 3.672078 -163.6014) (xy 3.68173 -163.608004) (xy 3.696408 -163.618348) (xy 4.444996 -163.618348)
			(xy 4.444996 -163.533652) (xy 4.453047 -163.449338) (xy 4.469076 -163.366172) (xy 4.492937 -163.284905)
			(xy 4.524416 -163.206275) (xy 4.563227 -163.130994) (xy 4.609017 -163.059742) (xy 4.661373 -162.993166)
			(xy 4.719821 -162.931868) (xy 4.783831 -162.876403) (xy 4.852823 -162.827274) (xy 4.926173 -162.784925)
			(xy 5.003216 -162.749741) (xy 5.083255 -162.722039) (xy 5.165564 -162.702071) (xy 5.249399 -162.690018)
			(xy 5.334 -162.685988) (xy 5.418601 -162.690018) (xy 5.502436 -162.702071) (xy 5.584745 -162.722039)
			(xy 5.664784 -162.749741) (xy 5.741827 -162.784925) (xy 5.815177 -162.827274) (xy 5.884169 -162.876403)
			(xy 5.948179 -162.931868) (xy 6.006627 -162.993166) (xy 6.058983 -163.059742) (xy 6.104773 -163.130994)
			(xy 6.143584 -163.206275) (xy 6.175063 -163.284905) (xy 6.198924 -163.366172) (xy 6.214953 -163.449338)
			(xy 6.223004 -163.533652) (xy 6.223508 -163.576) (xy 6.223004 -163.618348) (xy 6.214953 -163.702662)
			(xy 6.198924 -163.785828) (xy 6.175063 -163.867095) (xy 6.143584 -163.945725) (xy 6.104773 -164.021006)
			(xy 6.058983 -164.092258) (xy 6.006627 -164.158834) (xy 5.948179 -164.220132) (xy 5.884169 -164.275597)
			(xy 5.815177 -164.324726) (xy 5.741827 -164.367075) (xy 5.664784 -164.402259) (xy 5.584745 -164.429961)
			(xy 5.502436 -164.449929) (xy 5.418601 -164.461982) (xy 5.334 -164.466013) (xy 5.249399 -164.461982)
			(xy 5.165564 -164.449929) (xy 5.083255 -164.429961) (xy 5.003216 -164.402259) (xy 4.926173 -164.367075)
			(xy 4.852823 -164.324726) (xy 4.783831 -164.275597) (xy 4.719821 -164.220132) (xy 4.661373 -164.158834)
			(xy 4.609017 -164.092258) (xy 4.563227 -164.021006) (xy 4.524416 -163.945725) (xy 4.492937 -163.867095)
			(xy 4.469076 -163.785828) (xy 4.453047 -163.702662) (xy 4.444996 -163.618348) (xy 3.696408 -163.618348)
			(xy 3.716967 -163.632837) (xy 3.782961 -163.688306) (xy 3.843281 -163.749898) (xy 3.897361 -163.817036)
			(xy 3.944694 -163.889089) (xy 3.984836 -163.965382) (xy 4.017411 -164.045201) (xy 4.042113 -164.127795)
			(xy 4.058711 -164.212392) (xy 4.067048 -164.298197) (xy 4.067556 -164.341302) (xy 4.067077 -164.381852)
			(xy 4.059695 -164.462615) (xy 4.044991 -164.542372) (xy 4.023088 -164.620458) (xy 4.002927 -164.67328)
			(xy 6.827012 -164.67328) (xy 6.827473 -164.632673) (xy 6.834884 -164.551799) (xy 6.849634 -164.471936)
			(xy 6.871599 -164.39375) (xy 6.900597 -164.31789) (xy 6.936386 -164.244988) (xy 6.97867 -164.175651)
			(xy 7.027095 -164.110455) (xy 7.08126 -164.049942) (xy 7.140713 -163.994617) (xy 7.20496 -163.944939)
			(xy 7.273467 -163.901322) (xy 7.309358 -163.882324) (xy 7.318559 -163.877054) (xy 7.331951 -163.860646)
			(xy 7.335266 -163.850574) (xy 7.346652 -163.810693) (xy 7.375761 -163.733026) (xy 7.411976 -163.658407)
			(xy 7.454981 -163.587484) (xy 7.504404 -163.520873) (xy 7.559814 -163.459155) (xy 7.620731 -163.402863)
			(xy 7.686624 -163.352489) (xy 7.756921 -163.308469) (xy 7.831013 -163.271185) (xy 7.908253 -163.240963)
			(xy 7.987973 -163.218064) (xy 8.069478 -163.202688) (xy 8.152061 -163.194968) (xy 8.193532 -163.194492)
			(xy 8.234635 -163.194965) (xy 8.316489 -163.20255) (xy 8.397294 -163.217655) (xy 8.476361 -163.240152)
			(xy 8.553015 -163.269848) (xy 8.626602 -163.30649) (xy 8.696494 -163.349765) (xy 8.762095 -163.399305)
			(xy 8.822845 -163.454686) (xy 8.878226 -163.515437) (xy 8.927766 -163.581038) (xy 8.971041 -163.65093)
			(xy 9.007683 -163.724517) (xy 9.037379 -163.801171) (xy 9.059875 -163.880238) (xy 9.07498 -163.961043)
			(xy 9.082565 -164.042897) (xy 9.08304 -164.084) (xy 10.667492 -164.084) (xy 10.667967 -164.042898)
			(xy 10.675552 -163.961043) (xy 10.690657 -163.880238) (xy 10.713153 -163.801171) (xy 10.742849 -163.724517)
			(xy 10.779491 -163.65093) (xy 10.822766 -163.581038) (xy 10.872306 -163.515437) (xy 10.927687 -163.454687)
			(xy 10.988437 -163.399306) (xy 11.054038 -163.349766) (xy 11.12393 -163.306491) (xy 11.197517 -163.269849)
			(xy 11.274171 -163.240153) (xy 11.353238 -163.217657) (xy 11.434043 -163.202552) (xy 11.515898 -163.194967)
			(xy 11.557 -163.194492) (xy 11.59847 -163.194976) (xy 11.68105 -163.202697) (xy 11.762553 -163.218072)
			(xy 11.84227 -163.240967) (xy 11.91951 -163.271184) (xy 11.993602 -163.30846) (xy 12.063902 -163.352472)
			(xy 12.129799 -163.402836) (xy 12.190722 -163.459117) (xy 12.246141 -163.520824) (xy 12.295575 -163.587422)
			(xy 12.338595 -163.658333) (xy 12.374827 -163.732941) (xy 12.403956 -163.810598) (xy 12.425729 -163.890629)
			(xy 12.439958 -163.97234) (xy 12.443714 -164.013642) (xy 12.444743 -164.022224) (xy 12.451739 -164.038014)
			(xy 12.463612 -164.050555) (xy 12.471146 -164.05479) (xy 12.507091 -164.073755) (xy 12.575704 -164.117327)
			(xy 12.640054 -164.166977) (xy 12.699606 -164.222292) (xy 12.753863 -164.28281) (xy 12.802372 -164.348025)
			(xy 12.844728 -164.417395) (xy 12.880578 -164.490339) (xy 12.909624 -164.566251) (xy 12.931622 -164.644496)
			(xy 12.946389 -164.724421) (xy 12.953802 -164.805361) (xy 12.954254 -164.846) (xy 12.953798 -164.887103)
			(xy 12.946213 -164.968959) (xy 12.931107 -165.049766) (xy 12.90861 -165.128834) (xy 12.878914 -165.20549)
			(xy 12.842271 -165.279078) (xy 12.798995 -165.348971) (xy 12.749454 -165.414573) (xy 12.694072 -165.475325)
			(xy 12.63332 -165.530707) (xy 12.567718 -165.580247) (xy 12.497824 -165.623523) (xy 12.424236 -165.660165)
			(xy 12.347581 -165.689862) (xy 12.268512 -165.712358) (xy 12.187705 -165.727463) (xy 12.105849 -165.735048)
			(xy 12.064746 -165.735508) (xy 12.023275 -165.735075) (xy 11.940694 -165.727349) (xy 11.85919 -165.71197)
			(xy 11.779472 -165.68907) (xy 11.702231 -165.658849) (xy 11.62814 -165.621569) (xy 11.55784 -165.577553)
			(xy 11.491943 -165.527185) (xy 11.43102 -165.470902) (xy 11.375602 -165.409191) (xy 11.326168 -165.34259)
			(xy 11.283149 -165.271676) (xy 11.246918 -165.197066) (xy 11.217789 -165.119407) (xy 11.196016 -165.039374)
			(xy 11.181788 -164.957661) (xy 11.178032 -164.916358) (xy 11.177031 -164.907771) (xy 11.170026 -164.891978)
			(xy 11.15814 -164.87944) (xy 11.1506 -164.87521) (xy 11.114656 -164.856242) (xy 11.046044 -164.812671)
			(xy 10.981693 -164.763021) (xy 10.922141 -164.707706) (xy 10.867884 -164.647189) (xy 10.819375 -164.581974)
			(xy 10.777018 -164.512605) (xy 10.741168 -164.43966) (xy 10.712122 -164.363749) (xy 10.690124 -164.285504)
			(xy 10.675357 -164.205579) (xy 10.667944 -164.124639) (xy 10.667492 -164.084) (xy 9.08304 -164.084)
			(xy 9.082587 -164.124607) (xy 9.075177 -164.205482) (xy 9.060429 -164.285346) (xy 9.038464 -164.363533)
			(xy 9.009466 -164.439394) (xy 8.973676 -164.512296) (xy 8.931392 -164.581634) (xy 8.882965 -164.64683)
			(xy 8.828799 -164.707343) (xy 8.769344 -164.762667) (xy 8.705095 -164.812344) (xy 8.636586 -164.855959)
			(xy 8.600694 -164.874956) (xy 8.591489 -164.880221) (xy 8.578101 -164.896633) (xy 8.574786 -164.906706)
			(xy 8.563497 -164.946616) (xy 8.534379 -165.024284) (xy 8.498155 -165.098904) (xy 8.455141 -165.169827)
			(xy 8.40571 -165.236436) (xy 8.350291 -165.298154) (xy 8.289367 -165.354443) (xy 8.223466 -165.404815)
			(xy 8.153162 -165.448833) (xy 8.079064 -165.486113) (xy 8.001817 -165.516331) (xy 7.922092 -165.539226)
			(xy 7.840581 -165.554598) (xy 7.757994 -165.562314) (xy 7.71652 -165.562788) (xy 7.675418 -165.562313)
			(xy 7.593563 -165.554728) (xy 7.512758 -165.539623) (xy 7.433691 -165.517127) (xy 7.357037 -165.487431)
			(xy 7.28345 -165.450789) (xy 7.213558 -165.407514) (xy 7.147957 -165.357974) (xy 7.087207 -165.302593)
			(xy 7.031826 -165.241843) (xy 6.982286 -165.176242) (xy 6.939011 -165.10635) (xy 6.902369 -165.032763)
			(xy 6.872673 -164.956109) (xy 6.850177 -164.877042) (xy 6.835072 -164.796237) (xy 6.827487 -164.714382)
			(xy 6.827012 -164.67328) (xy 4.002927 -164.67328) (xy 3.994168 -164.696227) (xy 3.958471 -164.769048)
			(xy 3.916293 -164.838317) (xy 3.867985 -164.90346) (xy 3.813947 -164.963935) (xy 3.754629 -165.019239)
			(xy 3.690523 -165.068915) (xy 3.656584 -165.09111) (xy 3.645662 -165.097968) (xy 3.63347 -165.119812)
			(xy 3.631438 -165.230556) (xy 3.642868 -165.252908) (xy 3.653536 -165.260274) (xy 3.688514 -165.285137)
			(xy 3.754017 -165.34059) (xy 3.813874 -165.402094) (xy 3.867527 -165.469079) (xy 3.914478 -165.540921)
			(xy 3.954289 -165.616952) (xy 3.986591 -165.696464) (xy 4.011083 -165.778719) (xy 4.027538 -165.86295)
			(xy 4.035801 -165.948374) (xy 4.036314 -165.991286) (xy 4.03581 -166.033634) (xy 4.027759 -166.117948)
			(xy 4.01173 -166.201114) (xy 3.987869 -166.282381) (xy 3.95639 -166.361011) (xy 3.917579 -166.436292)
			(xy 3.871789 -166.507544) (xy 3.819433 -166.57412) (xy 3.760985 -166.635418) (xy 3.696975 -166.690883)
			(xy 3.627983 -166.740012) (xy 3.554633 -166.782361) (xy 3.47759 -166.817545) (xy 3.397551 -166.845247)
			(xy 3.315242 -166.865215) (xy 3.231407 -166.877268) (xy 3.146806 -166.881299) (xy 3.062205 -166.877268)
			(xy 2.97837 -166.865215) (xy 2.896061 -166.845247) (xy 2.816022 -166.817545) (xy 2.738979 -166.782361)
			(xy 2.665629 -166.740012) (xy 2.596637 -166.690883) (xy 2.532627 -166.635418) (xy 2.474179 -166.57412)
			(xy 2.421823 -166.507544) (xy 2.376033 -166.436292) (xy 2.337222 -166.361011) (xy 2.305743 -166.282381)
			(xy 2.281882 -166.201114) (xy 2.265853 -166.117948) (xy 2.257802 -166.033634) (xy 2.257298 -165.991286)
			(xy 2.257748 -165.950735) (xy 2.265133 -165.869971) (xy 2.279839 -165.790214) (xy 2.301745 -165.712126)
			(xy 2.330667 -165.636357) (xy 2.366367 -165.563536) (xy 2.408548 -165.494266) (xy 2.456859 -165.429124)
			(xy 2.510899 -165.36865) (xy 2.57022 -165.313347) (xy 2.634329 -165.263673) (xy 2.66827 -165.241478)
			(xy 2.679192 -165.23462) (xy 2.691384 -165.212776) (xy 2.693416 -165.102032) (xy 2.681986 -165.07968)
			(xy 2.671318 -165.072314) (xy 2.63634 -165.047451) (xy 2.570836 -164.991998) (xy 2.51098 -164.930494)
			(xy 2.457326 -164.863509) (xy 2.410376 -164.791667) (xy 2.370564 -164.715636) (xy 2.338262 -164.636124)
			(xy 2.31377 -164.553869) (xy 2.297316 -164.469638) (xy 2.289053 -164.384214) (xy 2.28854 -164.341302)
			(xy 2.289083 -164.296866) (xy 2.297952 -164.208437) (xy 2.315593 -164.121333) (xy 2.341832 -164.036423)
			(xy 2.376407 -163.954551) (xy 2.418973 -163.876536) (xy 2.469106 -163.803153) (xy 2.526307 -163.735135)
			(xy 2.55778 -163.703762) (xy 2.566162 -163.695634) (xy 2.573782 -163.674552) (xy 2.5654 -163.573206)
			(xy 2.55397 -163.553902) (xy 2.544318 -163.547298) (xy 2.509082 -163.522465) (xy 2.443088 -163.466995)
			(xy 2.382768 -163.405403) (xy 2.328688 -163.338266) (xy 2.281355 -163.266213) (xy 2.241213 -163.189919)
			(xy 2.208638 -163.110101) (xy 2.183936 -163.027507) (xy 2.167338 -162.94291) (xy 2.159 -162.857105)
			(xy 2.158492 -162.814) (xy 1.651254 -162.814) (xy 1.651254 -165.220904) (xy 1.652778 -165.27145)
			(xy 1.651254 -165.321996) (xy 1.651254 -169.926) (xy 2.901442 -169.926) (xy 2.901946 -169.882653)
			(xy 2.910377 -169.79637) (xy 2.927168 -169.711318) (xy 2.952159 -169.628305) (xy 2.985114 -169.548119)
			(xy 3.025719 -169.471522) (xy 3.073589 -169.399243) (xy 3.128268 -169.331967) (xy 3.189237 -169.270335)
			(xy 3.222244 -169.242232) (xy 3.23088 -169.234866) (xy 3.240532 -169.214546) (xy 3.240532 -169.113454)
			(xy 3.23088 -169.093134) (xy 3.222244 -169.085768) (xy 3.189241 -169.057663) (xy 3.128283 -168.996023)
			(xy 3.073614 -168.928743) (xy 3.025751 -168.856462) (xy 2.98515 -168.779866) (xy 2.952196 -168.699683)
			(xy 2.927202 -168.616673) (xy 2.910405 -168.531625) (xy 2.901964 -168.445346) (xy 2.901442 -168.402)
			(xy 2.901917 -168.360898) (xy 2.909502 -168.279043) (xy 2.924607 -168.198238) (xy 2.947103 -168.119171)
			(xy 2.976799 -168.042517) (xy 3.013441 -167.96893) (xy 3.056716 -167.899038) (xy 3.106256 -167.833437)
			(xy 3.161637 -167.772687) (xy 3.222387 -167.717306) (xy 3.287988 -167.667766) (xy 3.35788 -167.624491)
			(xy 3.431467 -167.587849) (xy 3.508121 -167.558153) (xy 3.587188 -167.535657) (xy 3.667993 -167.520552)
			(xy 3.749848 -167.512967) (xy 3.79095 -167.512492) (xy 3.833486 -167.512991) (xy 3.918169 -167.521125)
			(xy 4.001688 -167.537307) (xy 4.08328 -167.56139) (xy 4.1622 -167.593153) (xy 4.237726 -167.632308)
			(xy 4.309169 -167.678494) (xy 4.375876 -167.731292) (xy 4.4069 -167.760396) (xy 4.41833 -167.771318)
			(xy 4.449064 -167.776398) (xy 4.563364 -167.724328) (xy 4.57962 -167.697912) (xy 4.578858 -167.682164)
			(xy 4.577842 -167.64) (xy 4.578346 -167.596653) (xy 4.586777 -167.51037) (xy 4.603568 -167.425318)
			(xy 4.628559 -167.342305) (xy 4.661514 -167.262119) (xy 4.702119 -167.185522) (xy 4.749989 -167.113243)
			(xy 4.804668 -167.045967) (xy 4.865637 -166.984335) (xy 4.898644 -166.956232) (xy 4.90728 -166.948866)
			(xy 4.916932 -166.928546) (xy 4.916932 -166.827454) (xy 4.90728 -166.807134) (xy 4.898644 -166.799768)
			(xy 4.865641 -166.771663) (xy 4.804683 -166.710023) (xy 4.750014 -166.642743) (xy 4.702151 -166.570462)
			(xy 4.66155 -166.493866) (xy 4.628596 -166.413683) (xy 4.603602 -166.330673) (xy 4.586805 -166.245625)
			(xy 4.578364 -166.159346) (xy 4.577842 -166.116) (xy 4.578346 -166.073652) (xy 4.586397 -165.989338)
			(xy 4.602426 -165.906172) (xy 4.626287 -165.824905) (xy 4.657766 -165.746275) (xy 4.696577 -165.670994)
			(xy 4.742367 -165.599742) (xy 4.794723 -165.533166) (xy 4.853171 -165.471868) (xy 4.917181 -165.416403)
			(xy 4.986173 -165.367274) (xy 5.059523 -165.324925) (xy 5.136566 -165.289741) (xy 5.216605 -165.262039)
			(xy 5.298914 -165.242071) (xy 5.382749 -165.230018) (xy 5.46735 -165.225988) (xy 5.551951 -165.230018)
			(xy 5.635786 -165.242071) (xy 5.718095 -165.262039) (xy 5.798134 -165.289741) (xy 5.875177 -165.324925)
			(xy 5.948527 -165.367274) (xy 6.017519 -165.416403) (xy 6.081529 -165.471868) (xy 6.139977 -165.533166)
			(xy 6.192333 -165.599742) (xy 6.238123 -165.670994) (xy 6.276934 -165.746275) (xy 6.308413 -165.824905)
			(xy 6.332274 -165.906172) (xy 6.348303 -165.989338) (xy 6.356354 -166.073652) (xy 6.356858 -166.116)
			(xy 6.356354 -166.159347) (xy 6.347923 -166.24563) (xy 6.331132 -166.330682) (xy 6.306141 -166.413695)
			(xy 6.273186 -166.493881) (xy 6.232581 -166.570478) (xy 6.184711 -166.642757) (xy 6.130032 -166.710033)
			(xy 6.069063 -166.771665) (xy 6.036056 -166.799768) (xy 6.02742 -166.807134) (xy 6.017768 -166.827454)
			(xy 6.017768 -166.928546) (xy 6.02742 -166.948866) (xy 6.036056 -166.956232) (xy 6.069059 -166.984337)
			(xy 6.130017 -167.045977) (xy 6.184686 -167.113257) (xy 6.232549 -167.185538) (xy 6.27315 -167.262134)
			(xy 6.306104 -167.342317) (xy 6.331098 -167.425327) (xy 6.347895 -167.510375) (xy 6.356336 -167.596654)
			(xy 6.356858 -167.64) (xy 7.421372 -167.64) (xy 7.421779 -167.601685) (xy 7.428398 -167.525342) (xy 7.441553 -167.449849)
			(xy 7.461146 -167.375766) (xy 7.487032 -167.303641) (xy 7.502652 -167.268652) (xy 7.506674 -167.258777)
			(xy 7.50694 -167.237474) (xy 7.50316 -167.227504) (xy 7.486024 -167.185988) (xy 7.459219 -167.100261)
			(xy 7.441186 -167.01227) (xy 7.432108 -166.92291) (xy 7.431532 -166.878) (xy 7.432036 -166.835652)
			(xy 7.440087 -166.751338) (xy 7.456116 -166.668172) (xy 7.479977 -166.586905) (xy 7.511456 -166.508275)
			(xy 7.550267 -166.432994) (xy 7.596057 -166.361742) (xy 7.648413 -166.295166) (xy 7.706861 -166.233868)
			(xy 7.770871 -166.178403) (xy 7.839863 -166.129274) (xy 7.913213 -166.086925) (xy 7.990256 -166.051741)
			(xy 8.070295 -166.024039) (xy 8.152604 -166.004071) (xy 8.236439 -165.992018) (xy 8.32104 -165.987988)
			(xy 8.405641 -165.992018) (xy 8.489476 -166.004071) (xy 8.571785 -166.024039) (xy 8.651824 -166.051741)
			(xy 8.728867 -166.086925) (xy 8.802217 -166.129274) (xy 8.871209 -166.178403) (xy 8.935219 -166.233868)
			(xy 8.993667 -166.295166) (xy 9.046023 -166.361742) (xy 9.091813 -166.432994) (xy 9.130624 -166.508275)
			(xy 9.162103 -166.586905) (xy 9.185964 -166.668172) (xy 9.201993 -166.751338) (xy 9.210044 -166.835652)
			(xy 9.210548 -166.878) (xy 9.210139 -166.916315) (xy 9.209789 -166.920348) (xy 10.601956 -166.920348)
			(xy 10.601956 -166.835652) (xy 10.610007 -166.751338) (xy 10.626036 -166.668172) (xy 10.649897 -166.586905)
			(xy 10.681376 -166.508275) (xy 10.720187 -166.432994) (xy 10.765977 -166.361742) (xy 10.818333 -166.295166)
			(xy 10.876781 -166.233868) (xy 10.940791 -166.178403) (xy 11.009783 -166.129274) (xy 11.083133 -166.086925)
			(xy 11.160176 -166.051741) (xy 11.240215 -166.024039) (xy 11.322524 -166.004071) (xy 11.406359 -165.992018)
			(xy 11.49096 -165.987988) (xy 11.575561 -165.992018) (xy 11.659396 -166.004071) (xy 11.741705 -166.024039)
			(xy 11.821744 -166.051741) (xy 11.898787 -166.086925) (xy 11.972137 -166.129274) (xy 12.041129 -166.178403)
			(xy 12.105139 -166.233868) (xy 12.163587 -166.295166) (xy 12.215943 -166.361742) (xy 12.261733 -166.432994)
			(xy 12.300544 -166.508275) (xy 12.332023 -166.586905) (xy 12.355884 -166.668172) (xy 12.371913 -166.751338)
			(xy 12.379964 -166.835652) (xy 12.380468 -166.878) (xy 12.379964 -166.920348) (xy 12.371913 -167.004662)
			(xy 12.355884 -167.087828) (xy 12.332023 -167.169095) (xy 12.300544 -167.247725) (xy 12.261733 -167.323006)
			(xy 12.215943 -167.394258) (xy 12.163587 -167.460834) (xy 12.105139 -167.522132) (xy 12.041129 -167.577597)
			(xy 11.972137 -167.626726) (xy 11.898787 -167.669075) (xy 11.821744 -167.704259) (xy 11.741705 -167.731961)
			(xy 11.659396 -167.751929) (xy 11.575561 -167.763982) (xy 11.49096 -167.768013) (xy 11.406359 -167.763982)
			(xy 11.322524 -167.751929) (xy 11.240215 -167.731961) (xy 11.160176 -167.704259) (xy 11.083133 -167.669075)
			(xy 11.009783 -167.626726) (xy 10.940791 -167.577597) (xy 10.876781 -167.522132) (xy 10.818333 -167.460834)
			(xy 10.765977 -167.394258) (xy 10.720187 -167.323006) (xy 10.681376 -167.247725) (xy 10.649897 -167.169095)
			(xy 10.626036 -167.087828) (xy 10.610007 -167.004662) (xy 10.601956 -166.920348) (xy 9.209789 -166.920348)
			(xy 9.20352 -166.992658) (xy 9.190366 -167.068151) (xy 9.170773 -167.142234) (xy 9.144888 -167.214359)
			(xy 9.129268 -167.249348) (xy 9.125245 -167.259223) (xy 9.124979 -167.280526) (xy 9.12876 -167.290496)
			(xy 9.145897 -167.332012) (xy 9.172701 -167.417739) (xy 9.190734 -167.50573) (xy 9.199812 -167.59509)
			(xy 9.200388 -167.64) (xy 9.199884 -167.682348) (xy 9.191833 -167.766662) (xy 9.175804 -167.849828)
			(xy 9.151943 -167.931095) (xy 9.120464 -168.009725) (xy 9.081653 -168.085006) (xy 9.035863 -168.156258)
			(xy 8.983507 -168.222834) (xy 8.925059 -168.284132) (xy 8.861049 -168.339597) (xy 8.792057 -168.388726)
			(xy 8.718707 -168.431075) (xy 8.641664 -168.466259) (xy 8.561625 -168.493961) (xy 8.479316 -168.513929)
			(xy 8.395481 -168.525982) (xy 8.31088 -168.530013) (xy 8.226279 -168.525982) (xy 8.142444 -168.513929)
			(xy 8.060135 -168.493961) (xy 7.980096 -168.466259) (xy 7.903053 -168.431075) (xy 7.829703 -168.388726)
			(xy 7.760711 -168.339597) (xy 7.696701 -168.284132) (xy 7.638253 -168.222834) (xy 7.585897 -168.156258)
			(xy 7.540107 -168.085006) (xy 7.501296 -168.009725) (xy 7.469817 -167.931095) (xy 7.445956 -167.849828)
			(xy 7.429927 -167.766662) (xy 7.421876 -167.682348) (xy 7.421372 -167.64) (xy 6.356858 -167.64) (xy 6.356604 -167.657018)
			(xy 6.356839 -167.666655) (xy 6.363624 -167.684679) (xy 6.369812 -167.69207) (xy 6.390386 -167.714422)
			(xy 6.397149 -167.721253) (xy 6.414375 -167.729747) (xy 6.423914 -167.730932) (xy 6.465298 -167.734592)
			(xy 6.547184 -167.748658) (xy 6.627402 -167.770298) (xy 6.705253 -167.799323) (xy 6.780059 -167.83548)
			(xy 6.851167 -167.878455) (xy 6.917959 -167.927873) (xy 6.979852 -167.983303) (xy 7.036307 -168.044262)
			(xy 7.086833 -168.11022) (xy 7.130988 -168.180601) (xy 7.168389 -168.254792) (xy 7.198709 -168.332148)
			(xy 7.221685 -168.411994) (xy 7.237116 -168.493634) (xy 7.244867 -168.576357) (xy 7.24535 -168.6179)
			(xy 7.244849 -168.661247) (xy 7.236418 -168.74753) (xy 7.219627 -168.832582) (xy 7.194635 -168.915596)
			(xy 7.16168 -168.995782) (xy 7.121074 -169.072378) (xy 7.073204 -169.144658) (xy 7.018525 -169.211933)
			(xy 6.957555 -169.273566) (xy 6.924548 -169.301668) (xy 6.915912 -169.309034) (xy 6.90626 -169.329354)
			(xy 6.90626 -169.430446) (xy 6.915912 -169.450766) (xy 6.924548 -169.458132) (xy 6.957549 -169.486239)
			(xy 7.018507 -169.547879) (xy 7.073177 -169.615158) (xy 7.12104 -169.687439) (xy 7.161641 -169.764034)
			(xy 7.194595 -169.844218) (xy 7.21959 -169.927227) (xy 7.236387 -170.012275) (xy 7.244514 -170.095348)
			(xy 7.432036 -170.095348) (xy 7.432036 -170.010652) (xy 7.440087 -169.926338) (xy 7.456116 -169.843172)
			(xy 7.479977 -169.761905) (xy 7.511456 -169.683275) (xy 7.550267 -169.607994) (xy 7.596057 -169.536742)
			(xy 7.648413 -169.470166) (xy 7.706861 -169.408868) (xy 7.770871 -169.353403) (xy 7.839863 -169.304274)
			(xy 7.913213 -169.261925) (xy 7.990256 -169.226741) (xy 8.070295 -169.199039) (xy 8.152604 -169.179071)
			(xy 8.236439 -169.167018) (xy 8.32104 -169.162988) (xy 8.405641 -169.167018) (xy 8.489476 -169.179071)
			(xy 8.571785 -169.199039) (xy 8.651824 -169.226741) (xy 8.728867 -169.261925) (xy 8.802217 -169.304274)
			(xy 8.871209 -169.353403) (xy 8.935219 -169.408868) (xy 8.993667 -169.470166) (xy 9.046023 -169.536742)
			(xy 9.091813 -169.607994) (xy 9.130624 -169.683275) (xy 9.162103 -169.761905) (xy 9.185964 -169.843172)
			(xy 9.201993 -169.926338) (xy 9.210044 -170.010652) (xy 9.210548 -170.053) (xy 10.60088 -170.053)
			(xy 10.604941 -169.968077) (xy 10.61709 -169.883929) (xy 10.637213 -169.801324) (xy 10.665129 -169.721017)
			(xy 10.700581 -169.643741) (xy 10.743247 -169.570201) (xy 10.792737 -169.501069) (xy 10.848598 -169.436976)
			(xy 10.910322 -169.378506) (xy 10.977344 -169.326195) (xy 11.012932 -169.302938) (xy 11.023076 -169.295763)
			(xy 11.035324 -169.274177) (xy 11.0363 -169.26179) (xy 11.038183 -169.21907) (xy 11.049182 -169.134262)
			(xy 11.068269 -169.050901) (xy 11.095269 -168.969756) (xy 11.129931 -168.891578) (xy 11.171937 -168.817087)
			(xy 11.220898 -168.746971) (xy 11.276362 -168.681878) (xy 11.337817 -168.622409) (xy 11.404697 -168.569112)
			(xy 11.476382 -168.52248) (xy 11.552213 -168.482943) (xy 11.631487 -168.450867) (xy 11.713474 -168.426547)
			(xy 11.797417 -168.410207) (xy 11.882541 -168.402) (xy 11.9253 -168.401492) (xy 11.969084 -168.402004)
			(xy 12.056228 -168.410615) (xy 12.142104 -168.427743) (xy 12.225883 -168.453223) (xy 12.306755 -168.486809)
			(xy 12.383936 -168.528175) (xy 12.4206 -168.552114) (xy 12.4333 -168.56075) (xy 12.463526 -168.561004)
			(xy 12.567666 -168.494456) (xy 12.579858 -168.467024) (xy 12.577572 -168.452038) (xy 12.57246 -168.417531)
			(xy 12.566991 -168.347982) (xy 12.56665 -168.3131) (xy 12.567213 -168.269814) (xy 12.575605 -168.183649)
			(xy 12.59233 -168.098708) (xy 12.617229 -168.015793) (xy 12.650067 -167.93569) (xy 12.690532 -167.859157)
			(xy 12.738242 -167.786918) (xy 12.792746 -167.719656) (xy 12.853527 -167.658009) (xy 12.920011 -167.602559)
			(xy 12.991567 -167.553831) (xy 13.06752 -167.512286) (xy 13.14715 -167.478318) (xy 13.229704 -167.452248)
			(xy 13.3144 -167.434323) (xy 13.400437 -167.424712) (xy 13.443712 -167.423592) (xy 13.454504 -167.422967)
			(xy 13.474083 -167.413848) (xy 13.488181 -167.397486) (xy 13.491718 -167.38727) (xy 13.504668 -167.345569)
			(xy 13.537598 -167.264691) (xy 13.578293 -167.187428) (xy 13.626362 -167.114525) (xy 13.681344 -167.046682)
			(xy 13.742708 -166.984552) (xy 13.775944 -166.956232) (xy 13.78458 -166.948866) (xy 13.794232 -166.928546)
			(xy 13.794232 -166.827454) (xy 13.78458 -166.807134) (xy 13.775944 -166.799768) (xy 13.742941 -166.771663)
			(xy 13.681983 -166.710023) (xy 13.627314 -166.642743) (xy 13.579451 -166.570462) (xy 13.53885 -166.493866)
			(xy 13.505896 -166.413683) (xy 13.480902 -166.330673) (xy 13.464105 -166.245625) (xy 13.455664 -166.159346)
			(xy 13.455142 -166.116) (xy 13.455588 -166.074747) (xy 13.463246 -165.992597) (xy 13.478476 -165.911509)
			(xy 13.501149 -165.832179) (xy 13.531069 -165.755289) (xy 13.567979 -165.6815) (xy 13.611562 -165.611444)
			(xy 13.661445 -165.545725) (xy 13.717198 -165.484907) (xy 13.778342 -165.429512) (xy 13.844353 -165.380015)
			(xy 13.914662 -165.336843) (xy 13.951458 -165.318186) (xy 13.959761 -165.313616) (xy 13.972514 -165.299614)
			(xy 13.97931 -165.281937) (xy 13.979652 -165.272466) (xy 13.979652 -165.181534) (xy 13.979277 -165.172066)
			(xy 13.972493 -165.15439) (xy 13.959761 -165.140377) (xy 13.951458 -165.135814) (xy 13.914658 -165.117162)
			(xy 13.844338 -165.074002) (xy 13.778318 -165.024515) (xy 13.717165 -164.969124) (xy 13.661407 -164.908307)
			(xy 13.611521 -164.842587) (xy 13.567938 -164.772529) (xy 13.531032 -164.698734) (xy 13.501119 -164.621839)
			(xy 13.478459 -164.542503) (xy 13.463244 -164.461409) (xy 13.455607 -164.379254) (xy 13.455142 -164.338)
			(xy 13.455646 -164.294653) (xy 13.464077 -164.20837) (xy 13.480868 -164.123318) (xy 13.505859 -164.040305)
			(xy 13.538814 -163.960119) (xy 13.579419 -163.883522) (xy 13.627289 -163.811243) (xy 13.681968 -163.743967)
			(xy 13.742937 -163.682335) (xy 13.775944 -163.654232) (xy 13.78458 -163.646866) (xy 13.794232 -163.626546)
			(xy 13.794232 -163.525454) (xy 13.78458 -163.505134) (xy 13.775944 -163.497768) (xy 13.742941 -163.469663)
			(xy 13.681983 -163.408023) (xy 13.627314 -163.340743) (xy 13.579451 -163.268462) (xy 13.53885 -163.191866)
			(xy 13.505896 -163.111683) (xy 13.480902 -163.028673) (xy 13.464105 -162.943625) (xy 13.455664 -162.857346)
			(xy 13.455142 -162.814) (xy 13.455646 -162.771652) (xy 13.463697 -162.687338) (xy 13.479726 -162.604172)
			(xy 13.503587 -162.522905) (xy 13.535066 -162.444275) (xy 13.573877 -162.368994) (xy 13.619667 -162.297742)
			(xy 13.672023 -162.231166) (xy 13.730471 -162.169868) (xy 13.794481 -162.114403) (xy 13.863473 -162.065274)
			(xy 13.936823 -162.022925) (xy 14.013866 -161.987741) (xy 14.093905 -161.960039) (xy 14.176214 -161.940071)
			(xy 14.260049 -161.928018) (xy 14.34465 -161.923988) (xy 14.429251 -161.928018) (xy 14.513086 -161.940071)
			(xy 14.595395 -161.960039) (xy 14.675434 -161.987741) (xy 14.752477 -162.022925) (xy 14.825827 -162.065274)
			(xy 14.894819 -162.114403) (xy 14.958829 -162.169868) (xy 15.017277 -162.231166) (xy 15.069633 -162.297742)
			(xy 15.115423 -162.368994) (xy 15.154234 -162.444275) (xy 15.185713 -162.522905) (xy 15.209574 -162.604172)
			(xy 15.225603 -162.687338) (xy 15.233654 -162.771652) (xy 15.234158 -162.814) (xy 15.233654 -162.857347)
			(xy 15.225223 -162.94363) (xy 15.208432 -163.028682) (xy 15.183441 -163.111695) (xy 15.150486 -163.191881)
			(xy 15.109881 -163.268478) (xy 15.062011 -163.340757) (xy 15.007332 -163.408033) (xy 14.946363 -163.469665)
			(xy 14.913356 -163.497768) (xy 14.90472 -163.505134) (xy 14.895068 -163.525454) (xy 14.895068 -163.626546)
			(xy 14.90472 -163.646866) (xy 14.913356 -163.654232) (xy 14.946359 -163.682337) (xy 15.007317 -163.743977)
			(xy 15.061986 -163.811257) (xy 15.109849 -163.883538) (xy 15.15045 -163.960134) (xy 15.183404 -164.040317)
			(xy 15.208398 -164.123327) (xy 15.225195 -164.208375) (xy 15.233636 -164.294654) (xy 15.234158 -164.338)
			(xy 15.233712 -164.379253) (xy 15.226054 -164.461403) (xy 15.210824 -164.542491) (xy 15.188151 -164.621821)
			(xy 15.158231 -164.698711) (xy 15.121321 -164.7725) (xy 15.077738 -164.842556) (xy 15.027855 -164.908275)
			(xy 14.972102 -164.969093) (xy 14.910958 -165.024488) (xy 14.844947 -165.073985) (xy 14.774638 -165.117157)
			(xy 14.737842 -165.135814) (xy 14.729539 -165.140384) (xy 14.716786 -165.154386) (xy 14.70999 -165.172063)
			(xy 14.709648 -165.181534) (xy 14.709648 -165.272466) (xy 14.710023 -165.281934) (xy 14.716807 -165.29961)
			(xy 14.729539 -165.313623) (xy 14.737842 -165.318186) (xy 14.773426 -165.336191) (xy 14.841527 -165.377701)
			(xy 14.905634 -165.425147) (xy 14.96523 -165.478149) (xy 14.992858 -165.506908) (xy 15.002256 -165.516814)
			(xy 15.028418 -165.524688) (xy 15.141194 -165.497256) (xy 15.160752 -165.47846) (xy 15.164562 -165.465252)
			(xy 15.176233 -165.426036) (xy 15.205831 -165.349749) (xy 15.242312 -165.276504) (xy 15.285367 -165.20692)
			(xy 15.334632 -165.141585) (xy 15.389691 -165.081053) (xy 15.450078 -165.025834) (xy 15.515282 -164.976396)
			(xy 15.584753 -164.933157) (xy 15.657901 -164.896483) (xy 15.734109 -164.866684) (xy 15.812733 -164.844012)
			(xy 15.893107 -164.828658) (xy 15.974551 -164.820753) (xy 16.015462 -164.820092) (xy 16.031718 -164.820092)
			(xy 16.057626 -164.801804) (xy 16.100806 -164.681408) (xy 16.092424 -164.650928) (xy 16.079978 -164.640514)
			(xy 16.04713 -164.612377) (xy 15.98644 -164.550748) (xy 15.932018 -164.483519) (xy 15.88438 -164.411324)
			(xy 15.843974 -164.334846) (xy 15.811182 -164.254808) (xy 15.786314 -164.171964) (xy 15.769605 -164.087097)
			(xy 15.761213 -164.00101) (xy 15.7607 -163.957762) (xy 15.761204 -163.915414) (xy 15.769255 -163.8311)
			(xy 15.785284 -163.747934) (xy 15.809145 -163.666667) (xy 15.840624 -163.588037) (xy 15.879435 -163.512756)
			(xy 15.925225 -163.441504) (xy 15.977581 -163.374928) (xy 16.036029 -163.31363) (xy 16.100039 -163.258165)
			(xy 16.169031 -163.209036) (xy 16.242381 -163.166687) (xy 16.319424 -163.131503) (xy 16.399463 -163.103801)
			(xy 16.481772 -163.083833) (xy 16.565607 -163.07178) (xy 16.650208 -163.06775) (xy 16.734809 -163.07178)
			(xy 16.818644 -163.083833) (xy 16.900953 -163.103801) (xy 16.980992 -163.131503) (xy 17.058035 -163.166687)
			(xy 17.131385 -163.209036) (xy 17.200377 -163.258165) (xy 17.264387 -163.31363) (xy 17.322835 -163.374928)
			(xy 17.375191 -163.441504) (xy 17.420981 -163.512756) (xy 17.459792 -163.588037) (xy 17.491271 -163.666667)
			(xy 17.515132 -163.747934) (xy 17.531161 -163.8311) (xy 17.539212 -163.915414) (xy 17.539716 -163.957762)
			(xy 17.539486 -163.976488) (xy 35.153596 -163.976488) (xy 35.153596 -163.891792) (xy 35.161647 -163.807478)
			(xy 35.177676 -163.724312) (xy 35.201537 -163.643045) (xy 35.233016 -163.564415) (xy 35.271827 -163.489134)
			(xy 35.317617 -163.417882) (xy 35.369973 -163.351306) (xy 35.428421 -163.290008) (xy 35.492431 -163.234543)
			(xy 35.561423 -163.185414) (xy 35.634773 -163.143065) (xy 35.711816 -163.107881) (xy 35.791855 -163.080179)
			(xy 35.874164 -163.060211) (xy 35.957999 -163.048158) (xy 36.0426 -163.044128) (xy 36.127201 -163.048158)
			(xy 36.211036 -163.060211) (xy 36.293345 -163.080179) (xy 36.373384 -163.107881) (xy 36.450427 -163.143065)
			(xy 36.523777 -163.185414) (xy 36.592769 -163.234543) (xy 36.656779 -163.290008) (xy 36.715227 -163.351306)
			(xy 36.767583 -163.417882) (xy 36.813373 -163.489134) (xy 36.852184 -163.564415) (xy 36.883663 -163.643045)
			(xy 36.907524 -163.724312) (xy 36.923553 -163.807478) (xy 36.931604 -163.891792) (xy 36.932108 -163.93414)
			(xy 36.931604 -163.976488) (xy 36.923553 -164.060802) (xy 36.915815 -164.100948) (xy 37.287196 -164.100948)
			(xy 37.287196 -164.016252) (xy 37.295247 -163.931938) (xy 37.311276 -163.848772) (xy 37.335137 -163.767505)
			(xy 37.366616 -163.688875) (xy 37.405427 -163.613594) (xy 37.451217 -163.542342) (xy 37.503573 -163.475766)
			(xy 37.562021 -163.414468) (xy 37.626031 -163.359003) (xy 37.695023 -163.309874) (xy 37.768373 -163.267525)
			(xy 37.845416 -163.232341) (xy 37.925455 -163.204639) (xy 38.007764 -163.184671) (xy 38.091599 -163.172618)
			(xy 38.1762 -163.168588) (xy 38.260801 -163.172618) (xy 38.344636 -163.184671) (xy 38.426945 -163.204639)
			(xy 38.506984 -163.232341) (xy 38.584027 -163.267525) (xy 38.657377 -163.309874) (xy 38.726369 -163.359003)
			(xy 38.790379 -163.414468) (xy 38.848827 -163.475766) (xy 38.901183 -163.542342) (xy 38.946973 -163.613594)
			(xy 38.985784 -163.688875) (xy 39.017263 -163.767505) (xy 39.041124 -163.848772) (xy 39.057153 -163.931938)
			(xy 39.065204 -164.016252) (xy 39.065708 -164.0586) (xy 39.065204 -164.100948) (xy 39.057153 -164.185262)
			(xy 39.041124 -164.268428) (xy 39.017263 -164.349695) (xy 38.985784 -164.428325) (xy 38.946973 -164.503606)
			(xy 38.901183 -164.574858) (xy 38.848827 -164.641434) (xy 38.790379 -164.702732) (xy 38.726369 -164.758197)
			(xy 38.657377 -164.807326) (xy 38.584027 -164.849675) (xy 38.506984 -164.884859) (xy 38.426945 -164.912561)
			(xy 38.344636 -164.932529) (xy 38.260801 -164.944582) (xy 38.1762 -164.948613) (xy 38.091599 -164.944582)
			(xy 38.007764 -164.932529) (xy 37.925455 -164.912561) (xy 37.845416 -164.884859) (xy 37.768373 -164.849675)
			(xy 37.695023 -164.807326) (xy 37.626031 -164.758197) (xy 37.562021 -164.702732) (xy 37.503573 -164.641434)
			(xy 37.451217 -164.574858) (xy 37.405427 -164.503606) (xy 37.366616 -164.428325) (xy 37.335137 -164.349695)
			(xy 37.311276 -164.268428) (xy 37.295247 -164.185262) (xy 37.287196 -164.100948) (xy 36.915815 -164.100948)
			(xy 36.907524 -164.143968) (xy 36.883663 -164.225235) (xy 36.852184 -164.303865) (xy 36.813373 -164.379146)
			(xy 36.767583 -164.450398) (xy 36.715227 -164.516974) (xy 36.656779 -164.578272) (xy 36.592769 -164.633737)
			(xy 36.523777 -164.682866) (xy 36.450427 -164.725215) (xy 36.373384 -164.760399) (xy 36.293345 -164.788101)
			(xy 36.211036 -164.808069) (xy 36.127201 -164.820122) (xy 36.0426 -164.824153) (xy 35.957999 -164.820122)
			(xy 35.874164 -164.808069) (xy 35.791855 -164.788101) (xy 35.711816 -164.760399) (xy 35.634773 -164.725215)
			(xy 35.561423 -164.682866) (xy 35.492431 -164.633737) (xy 35.428421 -164.578272) (xy 35.369973 -164.516974)
			(xy 35.317617 -164.450398) (xy 35.271827 -164.379146) (xy 35.233016 -164.303865) (xy 35.201537 -164.225235)
			(xy 35.177676 -164.143968) (xy 35.161647 -164.060802) (xy 35.153596 -163.976488) (xy 17.539486 -163.976488)
			(xy 17.539213 -163.998737) (xy 17.531679 -164.08034) (xy 17.516669 -164.160905) (xy 17.494313 -164.239747)
			(xy 17.464799 -164.316198) (xy 17.428378 -164.38961) (xy 17.385358 -164.459361) (xy 17.336105 -164.524858)
			(xy 17.281035 -164.585548) (xy 17.220617 -164.640915) (xy 17.155361 -164.690489) (xy 17.085823 -164.73385)
			(xy 17.01259 -164.770631) (xy 16.936285 -164.80052) (xy 16.857553 -164.823263) (xy 16.777064 -164.838667)
			(xy 16.695498 -164.846602) (xy 16.654526 -164.84727) (xy 16.63827 -164.84727) (xy 16.612362 -164.865558)
			(xy 16.569182 -164.985954) (xy 16.577564 -165.016434) (xy 16.59001 -165.026848) (xy 16.623223 -165.055263)
			(xy 16.684495 -165.117606) (xy 16.739357 -165.185659) (xy 16.787279 -165.258764) (xy 16.827799 -165.336218)
			(xy 16.860527 -165.417273) (xy 16.885146 -165.501147) (xy 16.893794 -165.543992) (xy 16.896351 -165.554782)
			(xy 16.909232 -165.572806) (xy 16.928516 -165.583708) (xy 16.939514 -165.58514) (xy 16.980697 -165.588988)
			(xy 17.062137 -165.603494) (xy 17.141878 -165.625498) (xy 17.219232 -165.654809) (xy 17.293531 -165.691175)
			(xy 17.364133 -165.734281) (xy 17.430428 -165.783756) (xy 17.491844 -165.839171) (xy 17.547851 -165.900049)
			(xy 17.597964 -165.965862) (xy 17.641751 -166.036044) (xy 17.678833 -166.109988) (xy 17.708891 -166.187055)
			(xy 17.731664 -166.26658) (xy 17.746957 -166.347875) (xy 17.754636 -166.430239) (xy 17.755108 -166.4716)
			(xy 17.754633 -166.512702) (xy 17.747048 -166.594557) (xy 17.731943 -166.675362) (xy 17.709447 -166.754429)
			(xy 17.679751 -166.831083) (xy 17.643109 -166.90467) (xy 17.599834 -166.974562) (xy 17.550294 -167.040163)
			(xy 17.494913 -167.100913) (xy 17.434163 -167.156294) (xy 17.368562 -167.205834) (xy 17.29867 -167.249109)
			(xy 17.225083 -167.285751) (xy 17.148429 -167.315447) (xy 17.069362 -167.337943) (xy 16.988557 -167.353048)
			(xy 16.906702 -167.360633) (xy 16.8656 -167.361108) (xy 16.824567 -167.360682) (xy 16.74285 -167.353131)
			(xy 16.662175 -167.338085) (xy 16.58323 -167.315671) (xy 16.506684 -167.28608) (xy 16.433191 -167.249564)
			(xy 16.363373 -167.206433) (xy 16.297826 -167.157054) (xy 16.237106 -167.101846) (xy 16.18173 -167.04128)
			(xy 16.132168 -166.975871) (xy 16.088843 -166.906173) (xy 16.052122 -166.832782) (xy 16.022318 -166.756319)
			(xy 15.999685 -166.677436) (xy 15.991586 -166.637208) (xy 15.988965 -166.626439) (xy 15.976108 -166.608422)
			(xy 15.956852 -166.597506) (xy 15.945866 -166.59606) (xy 15.90527 -166.592223) (xy 15.824968 -166.578015)
			(xy 15.746302 -166.55652) (xy 15.669933 -166.527918) (xy 15.596501 -166.492449) (xy 15.526621 -166.450411)
			(xy 15.46088 -166.402157) (xy 15.39983 -166.34809) (xy 15.371572 -166.318692) (xy 15.362174 -166.308786)
			(xy 15.336012 -166.300912) (xy 15.223236 -166.328344) (xy 15.203678 -166.34714) (xy 15.199868 -166.360348)
			(xy 15.187145 -166.402874) (xy 15.154373 -166.485372) (xy 15.113543 -166.564194) (xy 15.065061 -166.638554)
			(xy 15.00941 -166.707713) (xy 14.947144 -166.770981) (xy 14.913356 -166.799768) (xy 14.90472 -166.807134)
			(xy 14.895068 -166.827454) (xy 14.895068 -166.928546) (xy 14.90472 -166.948866) (xy 14.913356 -166.956232)
			(xy 14.946359 -166.984337) (xy 15.007317 -167.045977) (xy 15.061986 -167.113257) (xy 15.109849 -167.185538)
			(xy 15.15045 -167.262134) (xy 15.183404 -167.342317) (xy 15.208398 -167.425327) (xy 15.225195 -167.510375)
			(xy 15.233636 -167.596654) (xy 15.234158 -167.64) (xy 15.233604 -167.68379) (xy 15.225006 -167.770948)
			(xy 15.207882 -167.856838) (xy 15.1824 -167.94063) (xy 15.148805 -168.021511) (xy 15.107423 -168.098698)
			(xy 15.058655 -168.171445) (xy 15.002973 -168.239045) (xy 14.940916 -168.300846) (xy 14.873086 -168.356248)
			(xy 14.836902 -168.380918) (xy 14.826234 -168.38803) (xy 14.814296 -168.410382) (xy 14.814296 -168.520618)
			(xy 14.826234 -168.54297) (xy 14.836902 -168.550082) (xy 14.873106 -168.574723) (xy 14.940932 -168.630133)
			(xy 15.002986 -168.69194) (xy 15.058666 -168.759545) (xy 15.107433 -168.832295) (xy 15.148815 -168.909484)
			(xy 15.182412 -168.990367) (xy 15.207898 -169.074159) (xy 15.225027 -169.16005) (xy 15.233634 -169.247209)
			(xy 15.234158 -169.291) (xy 15.233654 -169.334347) (xy 15.225223 -169.42063) (xy 15.208432 -169.505682)
			(xy 15.183441 -169.588695) (xy 15.150486 -169.668881) (xy 15.109881 -169.745478) (xy 15.062011 -169.817757)
			(xy 15.007332 -169.885033) (xy 14.946363 -169.946665) (xy 14.913356 -169.974768) (xy 14.90472 -169.982134)
			(xy 14.895068 -170.002454) (xy 14.895068 -170.103546) (xy 14.90472 -170.123866) (xy 14.913356 -170.131232)
			(xy 14.946359 -170.159337) (xy 15.007317 -170.220977) (xy 15.061986 -170.288257) (xy 15.109849 -170.360538)
			(xy 15.15045 -170.437134) (xy 15.183404 -170.517317) (xy 15.208398 -170.600327) (xy 15.225195 -170.685375)
			(xy 15.233636 -170.771654) (xy 15.234158 -170.815) (xy 15.233604 -170.85879) (xy 15.225006 -170.945948)
			(xy 15.207882 -171.031838) (xy 15.1824 -171.11563) (xy 15.148805 -171.196511) (xy 15.107423 -171.273698)
			(xy 15.058655 -171.346445) (xy 15.002973 -171.414045) (xy 14.940916 -171.475846) (xy 14.873086 -171.531248)
			(xy 14.836902 -171.555918) (xy 14.826234 -171.56303) (xy 14.814296 -171.585382) (xy 14.814296 -171.695618)
			(xy 14.826234 -171.71797) (xy 14.836902 -171.725082) (xy 14.873106 -171.749723) (xy 14.940932 -171.805133)
			(xy 15.002986 -171.86694) (xy 15.058666 -171.934545) (xy 15.107433 -172.007295) (xy 15.148815 -172.084484)
			(xy 15.182412 -172.165367) (xy 15.207898 -172.249159) (xy 15.225027 -172.33505) (xy 15.233634 -172.422209)
			(xy 15.234158 -172.466) (xy 15.233654 -172.509347) (xy 15.225223 -172.59563) (xy 15.208432 -172.680682)
			(xy 15.183441 -172.763695) (xy 15.150486 -172.843881) (xy 15.109881 -172.920478) (xy 15.062011 -172.992757)
			(xy 15.007332 -173.060033) (xy 14.946363 -173.121665) (xy 14.913356 -173.149768) (xy 14.90472 -173.157134)
			(xy 14.895068 -173.177454) (xy 14.895068 -173.278546) (xy 14.90472 -173.298866) (xy 14.913356 -173.306232)
			(xy 14.946359 -173.334337) (xy 15.007317 -173.395977) (xy 15.061986 -173.463257) (xy 15.109849 -173.535538)
			(xy 15.15045 -173.612134) (xy 15.183404 -173.692317) (xy 15.208398 -173.775327) (xy 15.225195 -173.860375)
			(xy 15.233636 -173.946654) (xy 15.234158 -173.99) (xy 15.234014 -174.010287) (xy 15.23211 -174.050816)
			(xy 15.230348 -174.071026) (xy 15.229866 -174.080465) (xy 15.235031 -174.098631) (xy 15.246437 -174.113684)
			(xy 15.262528 -174.123572) (xy 15.27175 -174.125636) (xy 15.315592 -174.134493) (xy 15.401377 -174.159836)
			(xy 15.484185 -174.193659) (xy 15.56318 -174.235622) (xy 15.60068 -174.260002) (xy 15.613634 -174.268638)
			(xy 15.64386 -174.268638) (xy 15.748 -174.199804) (xy 15.759684 -174.17161) (xy 15.75689 -174.15637)
			(xy 15.749516 -174.115173) (xy 15.741632 -174.031848) (xy 15.741142 -173.99) (xy 15.741646 -173.946653)
			(xy 15.750077 -173.86037) (xy 15.766868 -173.775318) (xy 15.791859 -173.692305) (xy 15.824814 -173.612119)
			(xy 15.865419 -173.535522) (xy 15.913289 -173.463243) (xy 15.967968 -173.395967) (xy 16.028937 -173.334335)
			(xy 16.061944 -173.306232) (xy 16.07058 -173.298866) (xy 16.080232 -173.278546) (xy 16.080232 -173.177454)
			(xy 16.07058 -173.157134) (xy 16.061944 -173.149768) (xy 16.02893 -173.121675) (xy 15.967972 -173.060034)
			(xy 15.913302 -172.992753) (xy 15.865439 -172.920471) (xy 15.824839 -172.843873) (xy 15.791887 -172.763688)
			(xy 15.766894 -172.680677) (xy 15.7501 -172.595627) (xy 15.741663 -172.509346) (xy 15.741142 -172.466)
			(xy 15.741631 -172.424977) (xy 15.749177 -172.34328) (xy 15.764216 -172.262626) (xy 15.786619 -172.183699)
			(xy 15.816196 -172.10717) (xy 15.852695 -172.033691) (xy 15.895806 -171.963885) (xy 15.945162 -171.898347)
			(xy 16.000345 -171.837633) (xy 16.060885 -171.782258) (xy 16.126267 -171.732695) (xy 16.195936 -171.689364)
			(xy 16.2693 -171.652633) (xy 16.345734 -171.622815) (xy 16.385032 -171.611036) (xy 16.393091 -171.608354)
			(xy 16.406965 -171.59858) (xy 16.41686 -171.584792) (xy 16.419576 -171.576746) (xy 16.432022 -171.538646)
			(xy 16.435324 -171.52874) (xy 16.434054 -171.508674) (xy 16.392144 -171.424854) (xy 16.376904 -171.411646)
			(xy 16.366744 -171.408598) (xy 16.32575 -171.394985) (xy 16.246385 -171.360877) (xy 16.1707 -171.319237)
			(xy 16.099407 -171.270457) (xy 16.033178 -171.214996) (xy 15.972637 -171.153378) (xy 15.918353 -171.086181)
			(xy 15.870837 -171.014039) (xy 15.830538 -170.937632) (xy 15.797834 -170.857678) (xy 15.773034 -170.774931)
			(xy 15.756371 -170.690169) (xy 15.748002 -170.604192) (xy 15.747492 -170.561) (xy 15.747919 -170.52124)
			(xy 15.75502 -170.442038) (xy 15.769164 -170.363786) (xy 15.790239 -170.287109) (xy 15.818077 -170.212621)
			(xy 15.852454 -170.140916) (xy 15.893097 -170.072567) (xy 15.939681 -170.00812) (xy 15.965424 -169.977816)
			(xy 15.97119 -169.970596) (xy 15.977569 -169.95327) (xy 15.97787 -169.944034) (xy 15.977616 -169.914316)
			(xy 15.977181 -169.905193) (xy 15.970662 -169.888143) (xy 15.964916 -169.881042) (xy 15.938503 -169.850568)
			(xy 15.890707 -169.785606) (xy 15.848986 -169.716586) (xy 15.813682 -169.644073) (xy 15.785085 -169.568663)
			(xy 15.763429 -169.490974) (xy 15.748892 -169.411645) (xy 15.741594 -169.331325) (xy 15.741142 -169.291)
			(xy 15.741631 -169.249977) (xy 15.749177 -169.16828) (xy 15.764216 -169.087626) (xy 15.786619 -169.008699)
			(xy 15.816196 -168.93217) (xy 15.852695 -168.858691) (xy 15.895806 -168.788885) (xy 15.945162 -168.723347)
			(xy 16.000345 -168.662633) (xy 16.060885 -168.607258) (xy 16.126267 -168.557695) (xy 16.195936 -168.514364)
			(xy 16.2693 -168.477633) (xy 16.345734 -168.447815) (xy 16.385032 -168.436036) (xy 16.393091 -168.433354)
			(xy 16.406965 -168.42358) (xy 16.41686 -168.409792) (xy 16.419576 -168.401746) (xy 16.431608 -168.362862)
			(xy 16.461912 -168.28731) (xy 16.498993 -168.214843) (xy 16.542538 -168.146067) (xy 16.592185 -168.081557)
			(xy 16.647518 -168.021852) (xy 16.708074 -167.967452) (xy 16.773347 -167.918812) (xy 16.842791 -167.876339)
			(xy 16.915824 -167.840388) (xy 16.991837 -167.811259) (xy 17.070193 -167.789197) (xy 17.150236 -167.774385)
			(xy 17.231299 -167.766948) (xy 17.272 -167.766492) (xy 17.313102 -167.766967) (xy 17.394957 -167.774552)
			(xy 17.475762 -167.789657) (xy 17.554829 -167.812153) (xy 17.631483 -167.841849) (xy 17.70507 -167.878491)
			(xy 17.774962 -167.921766) (xy 17.840563 -167.971306) (xy 17.901313 -168.026687) (xy 17.956694 -168.087437)
			(xy 18.006234 -168.153038) (xy 18.049509 -168.22293) (xy 18.086151 -168.296517) (xy 18.115847 -168.373171)
			(xy 18.138343 -168.452238) (xy 18.141344 -168.468294) (xy 22.35962 -168.468294) (xy 22.360095 -168.425948)
			(xy 22.368146 -168.341639) (xy 22.384174 -168.258476) (xy 22.408034 -168.177214) (xy 22.43951 -168.098588)
			(xy 22.478317 -168.02331) (xy 22.524103 -167.952061) (xy 22.576455 -167.885486) (xy 22.634897 -167.824189)
			(xy 22.698902 -167.768725) (xy 22.767888 -167.719595) (xy 22.841232 -167.677246) (xy 22.918269 -167.642059)
			(xy 22.998302 -167.614354) (xy 23.080606 -167.594382) (xy 23.164436 -167.582323) (xy 23.20671 -167.579802)
			(xy 23.215608 -167.578974) (xy 23.232046 -167.571993) (xy 23.245111 -167.559817) (xy 23.253232 -167.543912)
			(xy 23.254716 -167.535098) (xy 23.260314 -167.49238) (xy 23.278715 -167.408208) (xy 23.305167 -167.326208)
			(xy 23.339422 -167.24715) (xy 23.381159 -167.171773) (xy 23.429987 -167.100784) (xy 23.485449 -167.034848)
			(xy 23.547025 -166.974582) (xy 23.614138 -166.920551) (xy 23.686161 -166.873261) (xy 23.762417 -166.833154)
			(xy 23.842194 -166.800607) (xy 23.924743 -166.775925) (xy 24.009292 -166.759338) (xy 24.095048 -166.751002)
			(xy 24.138128 -166.750492) (xy 24.179231 -166.75094) (xy 24.261086 -166.758527) (xy 24.341892 -166.773635)
			(xy 24.420959 -166.796134) (xy 24.497613 -166.825832) (xy 24.5712 -166.862476) (xy 24.641092 -166.905753)
			(xy 24.706693 -166.955294) (xy 24.767443 -167.010677) (xy 24.822824 -167.071429) (xy 24.872363 -167.137031)
			(xy 24.915638 -167.206925) (xy 24.95228 -167.280513) (xy 24.981975 -167.357168) (xy 25.004472 -167.436236)
			(xy 25.019577 -167.517042) (xy 25.027161 -167.598897) (xy 25.027636 -167.64) (xy 25.027102 -167.682345)
			(xy 25.027102 -167.682348) (xy 30.733742 -167.682348) (xy 30.733742 -167.597652) (xy 30.741793 -167.513338)
			(xy 30.757822 -167.430172) (xy 30.781683 -167.348905) (xy 30.813162 -167.270275) (xy 30.851973 -167.194994)
			(xy 30.897763 -167.123742) (xy 30.950119 -167.057166) (xy 31.008567 -166.995868) (xy 31.072577 -166.940403)
			(xy 31.141569 -166.891274) (xy 31.214919 -166.848925) (xy 31.291962 -166.813741) (xy 31.372001 -166.786039)
			(xy 31.45431 -166.766071) (xy 31.538145 -166.754018) (xy 31.622746 -166.749988) (xy 31.707347 -166.754018)
			(xy 31.791182 -166.766071) (xy 31.873491 -166.786039) (xy 31.95353 -166.813741) (xy 32.030573 -166.848925)
			(xy 32.103923 -166.891274) (xy 32.172915 -166.940403) (xy 32.236925 -166.995868) (xy 32.295373 -167.057166)
			(xy 32.347729 -167.123742) (xy 32.393519 -167.194994) (xy 32.43233 -167.270275) (xy 32.463809 -167.348905)
			(xy 32.487134 -167.428348) (xy 33.293046 -167.428348) (xy 33.293046 -167.343652) (xy 33.301097 -167.259338)
			(xy 33.317126 -167.176172) (xy 33.340987 -167.094905) (xy 33.372466 -167.016275) (xy 33.411277 -166.940994)
			(xy 33.457067 -166.869742) (xy 33.509423 -166.803166) (xy 33.567871 -166.741868) (xy 33.631881 -166.686403)
			(xy 33.700873 -166.637274) (xy 33.774223 -166.594925) (xy 33.851266 -166.559741) (xy 33.931305 -166.532039)
			(xy 34.013614 -166.512071) (xy 34.097449 -166.500018) (xy 34.18205 -166.495988) (xy 34.266651 -166.500018)
			(xy 34.350486 -166.512071) (xy 34.432795 -166.532039) (xy 34.512834 -166.559741) (xy 34.589877 -166.594925)
			(xy 34.663227 -166.637274) (xy 34.732219 -166.686403) (xy 34.796229 -166.741868) (xy 34.854677 -166.803166)
			(xy 34.883565 -166.8399) (xy 42.79265 -166.8399) (xy 42.793166 -166.79694) (xy 42.801442 -166.711421)
			(xy 42.817925 -166.627098) (xy 42.842463 -166.544757) (xy 42.874827 -166.465167) (xy 42.914714 -166.389068)
			(xy 42.961754 -166.31717) (xy 43.015508 -166.250143) (xy 43.075475 -166.188612) (xy 43.141095 -166.13315)
			(xy 43.211758 -166.084275) (xy 43.286805 -166.042441) (xy 43.365536 -166.008039) (xy 43.447217 -165.981389)
			(xy 43.531088 -165.962739) (xy 43.616366 -165.952265) (xy 43.659298 -165.950646) (xy 43.671998 -165.950392)
			(xy 43.693588 -165.938454) (xy 43.753278 -165.847776) (xy 43.755818 -165.823138) (xy 43.751246 -165.811454)
			(xy 43.735985 -165.771966) (xy 43.71212 -165.690737) (xy 43.69608 -165.607608) (xy 43.688009 -165.523331)
			(xy 43.687492 -165.481) (xy 43.687996 -165.438652) (xy 43.696047 -165.354338) (xy 43.712076 -165.271172)
			(xy 43.735937 -165.189905) (xy 43.767416 -165.111275) (xy 43.806227 -165.035994) (xy 43.852017 -164.964742)
			(xy 43.904373 -164.898166) (xy 43.962821 -164.836868) (xy 44.026831 -164.781403) (xy 44.095823 -164.732274)
			(xy 44.169173 -164.689925) (xy 44.246216 -164.654741) (xy 44.326255 -164.627039) (xy 44.408564 -164.607071)
			(xy 44.492399 -164.595018) (xy 44.577 -164.590988) (xy 44.661601 -164.595018) (xy 44.745436 -164.607071)
			(xy 44.827745 -164.627039) (xy 44.907784 -164.654741) (xy 44.984827 -164.689925) (xy 45.058177 -164.732274)
			(xy 45.127169 -164.781403) (xy 45.191179 -164.836868) (xy 45.249627 -164.898166) (xy 45.301983 -164.964742)
			(xy 45.347773 -165.035994) (xy 45.386584 -165.111275) (xy 45.418063 -165.189905) (xy 45.441924 -165.271172)
			(xy 45.457953 -165.354338) (xy 45.466004 -165.438652) (xy 45.466508 -165.481) (xy 45.465935 -165.523958)
			(xy 45.45766 -165.609474) (xy 45.44967 -165.650348) (xy 46.621696 -165.650348) (xy 46.621696 -165.565652)
			(xy 46.629747 -165.481338) (xy 46.645776 -165.398172) (xy 46.669637 -165.316905) (xy 46.701116 -165.238275)
			(xy 46.739927 -165.162994) (xy 46.785717 -165.091742) (xy 46.838073 -165.025166) (xy 46.896521 -164.963868)
			(xy 46.960531 -164.908403) (xy 47.029523 -164.859274) (xy 47.102873 -164.816925) (xy 47.179916 -164.781741)
			(xy 47.259955 -164.754039) (xy 47.342264 -164.734071) (xy 47.426099 -164.722018) (xy 47.5107 -164.717988)
			(xy 47.595301 -164.722018) (xy 47.679136 -164.734071) (xy 47.761445 -164.754039) (xy 47.841484 -164.781741)
			(xy 47.918527 -164.816925) (xy 47.991877 -164.859274) (xy 48.060869 -164.908403) (xy 48.124879 -164.963868)
			(xy 48.183327 -165.025166) (xy 48.235683 -165.091742) (xy 48.281473 -165.162994) (xy 48.320284 -165.238275)
			(xy 48.351763 -165.316905) (xy 48.375624 -165.398172) (xy 48.391653 -165.481338) (xy 48.399704 -165.565652)
			(xy 48.400208 -165.608) (xy 48.399704 -165.650348) (xy 48.391653 -165.734662) (xy 48.375624 -165.817828)
			(xy 48.351763 -165.899095) (xy 48.320284 -165.977725) (xy 48.281473 -166.053006) (xy 48.235683 -166.124258)
			(xy 48.183327 -166.190834) (xy 48.124879 -166.252132) (xy 48.060869 -166.307597) (xy 47.991877 -166.356726)
			(xy 47.918527 -166.399075) (xy 47.841484 -166.434259) (xy 47.761445 -166.461961) (xy 47.679136 -166.481929)
			(xy 47.595301 -166.493982) (xy 47.5107 -166.498013) (xy 47.426099 -166.493982) (xy 47.342264 -166.481929)
			(xy 47.259955 -166.461961) (xy 47.179916 -166.434259) (xy 47.102873 -166.399075) (xy 47.029523 -166.356726)
			(xy 46.960531 -166.307597) (xy 46.896521 -166.252132) (xy 46.838073 -166.190834) (xy 46.785717 -166.124258)
			(xy 46.739927 -166.053006) (xy 46.701116 -165.977725) (xy 46.669637 -165.899095) (xy 46.645776 -165.817828)
			(xy 46.629747 -165.734662) (xy 46.621696 -165.650348) (xy 45.44967 -165.650348) (xy 45.441178 -165.693794)
			(xy 45.416642 -165.776131) (xy 45.384281 -165.855719) (xy 45.344397 -165.931816) (xy 45.297361 -166.003712)
			(xy 45.243611 -166.070738) (xy 45.183649 -166.132268) (xy 45.118033 -166.18773) (xy 45.047375 -166.236607)
			(xy 44.972333 -166.278442) (xy 44.893607 -166.312847) (xy 44.81193 -166.3395) (xy 44.728064 -166.358153)
			(xy 44.64279 -166.368633) (xy 44.59986 -166.370254) (xy 44.58716 -166.370508) (xy 44.56557 -166.382446)
			(xy 44.50588 -166.473124) (xy 44.50334 -166.497762) (xy 44.507912 -166.509446) (xy 44.516146 -166.530323)
			(xy 44.530756 -166.572762) (xy 44.537122 -166.594282) (xy 44.539938 -166.602853) (xy 44.55063 -166.617371)
			(xy 44.565689 -166.627287) (xy 44.58325 -166.631373) (xy 44.59224 -166.630604) (xy 44.620061 -166.627282)
			(xy 44.675983 -166.623725) (xy 44.704 -166.623492) (xy 44.746348 -166.623996) (xy 44.830662 -166.632047)
			(xy 44.913828 -166.648076) (xy 44.995095 -166.671937) (xy 45.073725 -166.703416) (xy 45.149006 -166.742227)
			(xy 45.220258 -166.788017) (xy 45.286834 -166.840373) (xy 45.348132 -166.898821) (xy 45.403597 -166.962831)
			(xy 45.452726 -167.031823) (xy 45.495075 -167.105173) (xy 45.530259 -167.182216) (xy 45.557961 -167.262255)
			(xy 45.577929 -167.344564) (xy 45.589982 -167.428399) (xy 45.594013 -167.513) (xy 45.589982 -167.597601)
			(xy 45.577929 -167.681436) (xy 45.557961 -167.763745) (xy 45.530259 -167.843784) (xy 45.495075 -167.920827)
			(xy 45.452726 -167.994177) (xy 45.403597 -168.063169) (xy 45.348132 -168.127179) (xy 45.286834 -168.185627)
			(xy 45.220258 -168.237983) (xy 45.149006 -168.283773) (xy 45.073725 -168.322584) (xy 44.995095 -168.354063)
			(xy 44.913828 -168.377924) (xy 44.830662 -168.393953) (xy 44.746348 -168.402004) (xy 44.704 -168.402508)
			(xy 44.662976 -168.402056) (xy 44.581277 -168.394508) (xy 44.50062 -168.379468) (xy 44.421692 -168.357064)
			(xy 44.345162 -168.327485) (xy 44.271681 -168.290984) (xy 44.201875 -168.24787) (xy 44.136336 -168.198511)
			(xy 44.075622 -168.143325) (xy 44.020248 -168.082781) (xy 43.970686 -168.017395) (xy 43.927357 -167.947723)
			(xy 43.890628 -167.874356) (xy 43.860813 -167.797918) (xy 43.849036 -167.758618) (xy 43.846165 -167.75007)
			(xy 43.835488 -167.735556) (xy 43.820447 -167.725637) (xy 43.802902 -167.721537) (xy 43.793918 -167.722296)
			(xy 43.766097 -167.725612) (xy 43.710175 -167.729173) (xy 43.682158 -167.729408) (xy 43.641055 -167.728973)
			(xy 43.559199 -167.721385) (xy 43.478393 -167.706276) (xy 43.399326 -167.683776) (xy 43.322672 -167.654077)
			(xy 43.249085 -167.617432) (xy 43.179193 -167.574154) (xy 43.113592 -167.524611) (xy 43.052842 -167.469228)
			(xy 42.997462 -167.408475) (xy 42.947923 -167.342872) (xy 42.904648 -167.272978) (xy 42.868006 -167.19939)
			(xy 42.838311 -167.122734) (xy 42.815814 -167.043666) (xy 42.800709 -166.962859) (xy 42.793125 -166.881003)
			(xy 42.79265 -166.8399) (xy 34.883565 -166.8399) (xy 34.907033 -166.869742) (xy 34.952823 -166.940994)
			(xy 34.991634 -167.016275) (xy 35.023113 -167.094905) (xy 35.046974 -167.176172) (xy 35.063003 -167.259338)
			(xy 35.071054 -167.343652) (xy 35.071558 -167.386) (xy 35.071054 -167.428348) (xy 35.063003 -167.512662)
			(xy 35.046974 -167.595828) (xy 35.023113 -167.677095) (xy 34.991634 -167.755725) (xy 34.952823 -167.831006)
			(xy 34.907033 -167.902258) (xy 34.854677 -167.968834) (xy 34.796229 -168.030132) (xy 34.732219 -168.085597)
			(xy 34.663227 -168.134726) (xy 34.589877 -168.177075) (xy 34.512834 -168.212259) (xy 34.432795 -168.239961)
			(xy 34.350486 -168.259929) (xy 34.266651 -168.271982) (xy 34.18205 -168.276013) (xy 34.097449 -168.271982)
			(xy 34.013614 -168.259929) (xy 33.931305 -168.239961) (xy 33.851266 -168.212259) (xy 33.774223 -168.177075)
			(xy 33.700873 -168.134726) (xy 33.631881 -168.085597) (xy 33.567871 -168.030132) (xy 33.509423 -167.968834)
			(xy 33.457067 -167.902258) (xy 33.411277 -167.831006) (xy 33.372466 -167.755725) (xy 33.340987 -167.677095)
			(xy 33.317126 -167.595828) (xy 33.301097 -167.512662) (xy 33.293046 -167.428348) (xy 32.487134 -167.428348)
			(xy 32.48767 -167.430172) (xy 32.503699 -167.513338) (xy 32.51175 -167.597652) (xy 32.512254 -167.64)
			(xy 32.51175 -167.682348) (xy 32.503699 -167.766662) (xy 32.48767 -167.849828) (xy 32.463809 -167.931095)
			(xy 32.43233 -168.009725) (xy 32.393519 -168.085006) (xy 32.347729 -168.156258) (xy 32.295373 -168.222834)
			(xy 32.236925 -168.284132) (xy 32.172915 -168.339597) (xy 32.103923 -168.388726) (xy 32.030573 -168.431075)
			(xy 31.95353 -168.466259) (xy 31.873491 -168.493961) (xy 31.791182 -168.513929) (xy 31.707347 -168.525982)
			(xy 31.622746 -168.530013) (xy 31.538145 -168.525982) (xy 31.45431 -168.513929) (xy 31.372001 -168.493961)
			(xy 31.291962 -168.466259) (xy 31.214919 -168.431075) (xy 31.141569 -168.388726) (xy 31.072577 -168.339597)
			(xy 31.008567 -168.284132) (xy 30.950119 -168.222834) (xy 30.897763 -168.156258) (xy 30.851973 -168.085006)
			(xy 30.813162 -168.009725) (xy 30.781683 -167.931095) (xy 30.757822 -167.849828) (xy 30.741793 -167.766662)
			(xy 30.733742 -167.682348) (xy 25.027102 -167.682348) (xy 25.019052 -167.76665) (xy 25.003026 -167.849809)
			(xy 24.979169 -167.931069) (xy 24.947696 -168.009692) (xy 24.908892 -168.084969) (xy 24.863109 -168.156216)
			(xy 24.810762 -168.222789) (xy 24.752324 -168.284086) (xy 24.688324 -168.33955) (xy 24.619343 -168.388681)
			(xy 24.546004 -168.431032) (xy 24.468972 -168.466221) (xy 24.388943 -168.493929) (xy 24.306644 -168.513905)
			(xy 24.222818 -168.525969) (xy 24.180546 -168.528492) (xy 24.171654 -168.529368) (xy 24.155218 -168.536331)
			(xy 24.14215 -168.548492) (xy 24.134025 -168.564387) (xy 24.132852 -168.571348) (xy 41.413934 -168.571348)
			(xy 41.413934 -168.486652) (xy 41.421985 -168.402338) (xy 41.438014 -168.319172) (xy 41.461875 -168.237905)
			(xy 41.493354 -168.159275) (xy 41.532165 -168.083994) (xy 41.577955 -168.012742) (xy 41.630311 -167.946166)
			(xy 41.688759 -167.884868) (xy 41.752769 -167.829403) (xy 41.821761 -167.780274) (xy 41.895111 -167.737925)
			(xy 41.972154 -167.702741) (xy 42.052193 -167.675039) (xy 42.134502 -167.655071) (xy 42.218337 -167.643018)
			(xy 42.302938 -167.638988) (xy 42.387539 -167.643018) (xy 42.471374 -167.655071) (xy 42.553683 -167.675039)
			(xy 42.633722 -167.702741) (xy 42.710765 -167.737925) (xy 42.784115 -167.780274) (xy 42.853107 -167.829403)
			(xy 42.917117 -167.884868) (xy 42.975565 -167.946166) (xy 43.027921 -168.012742) (xy 43.073711 -168.083994)
			(xy 43.112522 -168.159275) (xy 43.144001 -168.237905) (xy 43.167862 -168.319172) (xy 43.183891 -168.402338)
			(xy 43.191942 -168.486652) (xy 43.192446 -168.529) (xy 46.621192 -168.529) (xy 46.621695 -168.486685)
			(xy 46.629726 -168.402437) (xy 46.645724 -168.319334) (xy 46.669545 -168.238125) (xy 46.700972 -168.159548)
			(xy 46.739723 -168.084311) (xy 46.762162 -168.048432) (xy 46.767045 -168.040043) (xy 46.770717 -168.021)
			(xy 46.767045 -168.001957) (xy 46.762162 -167.993568) (xy 46.739716 -167.957694) (xy 46.700973 -167.882453)
			(xy 46.669549 -167.803874) (xy 46.64573 -167.722665) (xy 46.62973 -167.639562) (xy 46.621694 -167.555315)
			(xy 46.621192 -167.513) (xy 46.621696 -167.470652) (xy 46.629747 -167.386338) (xy 46.645776 -167.303172)
			(xy 46.669637 -167.221905) (xy 46.701116 -167.143275) (xy 46.739927 -167.067994) (xy 46.785717 -166.996742)
			(xy 46.838073 -166.930166) (xy 46.896521 -166.868868) (xy 46.960531 -166.813403) (xy 47.029523 -166.764274)
			(xy 47.102873 -166.721925) (xy 47.179916 -166.686741) (xy 47.259955 -166.659039) (xy 47.342264 -166.639071)
			(xy 47.426099 -166.627018) (xy 47.5107 -166.622988) (xy 47.595301 -166.627018) (xy 47.679136 -166.639071)
			(xy 47.761445 -166.659039) (xy 47.841484 -166.686741) (xy 47.918527 -166.721925) (xy 47.991877 -166.764274)
			(xy 48.060869 -166.813403) (xy 48.124879 -166.868868) (xy 48.183327 -166.930166) (xy 48.235683 -166.996742)
			(xy 48.281473 -167.067994) (xy 48.320284 -167.143275) (xy 48.351763 -167.221905) (xy 48.375624 -167.303172)
			(xy 48.391653 -167.386338) (xy 48.399704 -167.470652) (xy 48.400208 -167.513) (xy 48.399705 -167.555315)
			(xy 48.391674 -167.639563) (xy 48.375676 -167.722666) (xy 48.351855 -167.803875) (xy 48.320428 -167.882452)
			(xy 48.281677 -167.957689) (xy 48.259238 -167.993568) (xy 48.254355 -168.001957) (xy 48.250683 -168.021)
			(xy 48.254355 -168.040043) (xy 48.259238 -168.048432) (xy 48.281684 -168.084306) (xy 48.320427 -168.159547)
			(xy 48.351851 -168.238126) (xy 48.37567 -168.319335) (xy 48.39167 -168.402438) (xy 48.399706 -168.486685)
			(xy 48.400208 -168.529) (xy 48.399704 -168.571348) (xy 48.391653 -168.655662) (xy 48.375624 -168.738828)
			(xy 48.351763 -168.820095) (xy 48.320284 -168.898725) (xy 48.281473 -168.974006) (xy 48.235683 -169.045258)
			(xy 48.183327 -169.111834) (xy 48.124879 -169.173132) (xy 48.060869 -169.228597) (xy 47.991877 -169.277726)
			(xy 47.918527 -169.320075) (xy 47.841484 -169.355259) (xy 47.761445 -169.382961) (xy 47.679136 -169.402929)
			(xy 47.595301 -169.414982) (xy 47.5107 -169.419013) (xy 47.426099 -169.414982) (xy 47.342264 -169.402929)
			(xy 47.259955 -169.382961) (xy 47.179916 -169.355259) (xy 47.102873 -169.320075) (xy 47.029523 -169.277726)
			(xy 46.960531 -169.228597) (xy 46.896521 -169.173132) (xy 46.838073 -169.111834) (xy 46.785717 -169.045258)
			(xy 46.739927 -168.974006) (xy 46.701116 -168.898725) (xy 46.669637 -168.820095) (xy 46.645776 -168.738828)
			(xy 46.629747 -168.655662) (xy 46.621696 -168.571348) (xy 46.621192 -168.529) (xy 43.192446 -168.529)
			(xy 43.191942 -168.571348) (xy 43.183891 -168.655662) (xy 43.167862 -168.738828) (xy 43.144001 -168.820095)
			(xy 43.112522 -168.898725) (xy 43.073711 -168.974006) (xy 43.027921 -169.045258) (xy 42.975565 -169.111834)
			(xy 42.917117 -169.173132) (xy 42.853107 -169.228597) (xy 42.784115 -169.277726) (xy 42.710765 -169.320075)
			(xy 42.633722 -169.355259) (xy 42.553683 -169.382961) (xy 42.471374 -169.402929) (xy 42.387539 -169.414982)
			(xy 42.302938 -169.419013) (xy 42.218337 -169.414982) (xy 42.134502 -169.402929) (xy 42.052193 -169.382961)
			(xy 41.972154 -169.355259) (xy 41.895111 -169.320075) (xy 41.821761 -169.277726) (xy 41.752769 -169.228597)
			(xy 41.688759 -169.173132) (xy 41.630311 -169.111834) (xy 41.577955 -169.045258) (xy 41.532165 -168.974006)
			(xy 41.493354 -168.898725) (xy 41.461875 -168.820095) (xy 41.438014 -168.738828) (xy 41.421985 -168.655662)
			(xy 41.413934 -168.571348) (xy 24.132852 -168.571348) (xy 24.13254 -168.573196) (xy 24.126883 -168.615905)
			(xy 24.108484 -168.700075) (xy 24.082035 -168.782071) (xy 24.047783 -168.861127) (xy 24.00605 -168.936502)
			(xy 23.957226 -169.007489) (xy 23.901768 -169.073425) (xy 23.840197 -169.13369) (xy 23.773088 -169.187722)
			(xy 23.701071 -169.235014) (xy 23.624819 -169.275122) (xy 23.545047 -169.307672) (xy 23.462503 -169.332358)
			(xy 23.377959 -169.348949) (xy 23.292206 -169.357289) (xy 23.249128 -169.357802) (xy 23.208025 -169.357321)
			(xy 23.12617 -169.349739) (xy 23.045363 -169.334635) (xy 22.966295 -169.312141) (xy 22.88964 -169.282446)
			(xy 22.816052 -169.245806) (xy 22.746158 -169.202531) (xy 22.680556 -169.152992) (xy 22.619804 -169.097611)
			(xy 22.564422 -169.036861) (xy 22.514881 -168.97126) (xy 22.471605 -168.901368) (xy 22.434963 -168.82778)
			(xy 22.405266 -168.751126) (xy 22.38277 -168.672058) (xy 22.367665 -168.591252) (xy 22.36008 -168.509397)
			(xy 22.35962 -168.468294) (xy 18.141344 -168.468294) (xy 18.153448 -168.533043) (xy 18.161033 -168.614898)
			(xy 18.161508 -168.656) (xy 18.160991 -168.698673) (xy 18.152821 -168.783628) (xy 18.136556 -168.867411)
			(xy 18.112344 -168.949251) (xy 18.08041 -169.028398) (xy 18.041045 -169.104125) (xy 17.994612 -169.175735)
			(xy 17.968468 -169.209466) (xy 17.961356 -169.218102) (xy 17.956276 -169.23893) (xy 17.97304 -169.33545)
			(xy 17.984978 -169.35323) (xy 17.994376 -169.359072) (xy 18.029059 -169.381121) (xy 18.094648 -169.430652)
			(xy 18.155387 -169.486024) (xy 18.210758 -169.546764) (xy 18.260288 -169.612354) (xy 18.303555 -169.682234)
			(xy 18.340189 -169.755809) (xy 18.369878 -169.83245) (xy 18.392368 -169.911503) (xy 18.407468 -169.992295)
			(xy 18.415049 -170.074135) (xy 18.415508 -170.11523) (xy 18.415062 -170.156722) (xy 18.407315 -170.239344)
			(xy 18.39191 -170.320886) (xy 18.368981 -170.40064) (xy 18.338728 -170.477913) (xy 18.301412 -170.552034)
			(xy 18.295795 -170.561) (xy 24.836628 -170.561) (xy 24.837132 -170.518652) (xy 24.845183 -170.434338)
			(xy 24.861212 -170.351172) (xy 24.885073 -170.269905) (xy 24.916552 -170.191275) (xy 24.955363 -170.115994)
			(xy 25.001153 -170.044742) (xy 25.053509 -169.978166) (xy 25.111957 -169.916868) (xy 25.175967 -169.861403)
			(xy 25.244959 -169.812274) (xy 25.318309 -169.769925) (xy 25.395352 -169.734741) (xy 25.475391 -169.707039)
			(xy 25.5577 -169.687071) (xy 25.641535 -169.675018) (xy 25.726136 -169.670988) (xy 25.810737 -169.675018)
			(xy 25.894572 -169.687071) (xy 25.976881 -169.707039) (xy 26.05692 -169.734741) (xy 26.133963 -169.769925)
			(xy 26.207313 -169.812274) (xy 26.276305 -169.861403) (xy 26.340315 -169.916868) (xy 26.398763 -169.978166)
			(xy 26.411416 -169.994256) (xy 30.45485 -169.994256) (xy 30.45485 -169.90956) (xy 30.462901 -169.825246)
			(xy 30.47893 -169.74208) (xy 30.502791 -169.660813) (xy 30.53427 -169.582183) (xy 30.573081 -169.506902)
			(xy 30.618871 -169.43565) (xy 30.671227 -169.369074) (xy 30.729675 -169.307776) (xy 30.793685 -169.252311)
			(xy 30.862677 -169.203182) (xy 30.936027 -169.160833) (xy 31.01307 -169.125649) (xy 31.093109 -169.097947)
			(xy 31.175418 -169.077979) (xy 31.259253 -169.065926) (xy 31.343854 -169.061896) (xy 31.428455 -169.065926)
			(xy 31.51229 -169.077979) (xy 31.594599 -169.097947) (xy 31.674638 -169.125649) (xy 31.751681 -169.160833)
			(xy 31.825031 -169.203182) (xy 31.894023 -169.252311) (xy 31.958033 -169.307776) (xy 32.016481 -169.369074)
			(xy 32.068837 -169.43565) (xy 32.114627 -169.506902) (xy 32.153438 -169.582183) (xy 32.184917 -169.660813)
			(xy 32.208778 -169.74208) (xy 32.224807 -169.825246) (xy 32.232858 -169.90956) (xy 32.233362 -169.951908)
			(xy 32.232858 -169.994256) (xy 32.224807 -170.07857) (xy 32.208778 -170.161736) (xy 32.184917 -170.243003)
			(xy 32.153438 -170.321633) (xy 32.114627 -170.396914) (xy 32.068837 -170.468166) (xy 32.016481 -170.534742)
			(xy 31.958033 -170.59604) (xy 31.902405 -170.644242) (xy 39.50995 -170.644242) (xy 39.50995 -170.559546)
			(xy 39.518001 -170.475232) (xy 39.53403 -170.392066) (xy 39.557891 -170.310799) (xy 39.58937 -170.232169)
			(xy 39.628181 -170.156888) (xy 39.673971 -170.085636) (xy 39.726327 -170.01906) (xy 39.784775 -169.957762)
			(xy 39.848785 -169.902297) (xy 39.917777 -169.853168) (xy 39.991127 -169.810819) (xy 40.06817 -169.775635)
			(xy 40.148209 -169.747933) (xy 40.230518 -169.727965) (xy 40.314353 -169.715912) (xy 40.398954 -169.711882)
			(xy 40.483555 -169.715912) (xy 40.56739 -169.727965) (xy 40.649699 -169.747933) (xy 40.729738 -169.775635)
			(xy 40.780901 -169.799) (xy 43.681142 -169.799) (xy 43.681646 -169.756652) (xy 43.689697 -169.672338)
			(xy 43.705726 -169.589172) (xy 43.729587 -169.507905) (xy 43.761066 -169.429275) (xy 43.799877 -169.353994)
			(xy 43.845667 -169.282742) (xy 43.898023 -169.216166) (xy 43.956471 -169.154868) (xy 44.020481 -169.099403)
			(xy 44.089473 -169.050274) (xy 44.162823 -169.007925) (xy 44.239866 -168.972741) (xy 44.319905 -168.945039)
			(xy 44.402214 -168.925071) (xy 44.486049 -168.913018) (xy 44.57065 -168.908988) (xy 44.655251 -168.913018)
			(xy 44.739086 -168.925071) (xy 44.821395 -168.945039) (xy 44.901434 -168.972741) (xy 44.978477 -169.007925)
			(xy 45.051827 -169.050274) (xy 45.120819 -169.099403) (xy 45.184829 -169.154868) (xy 45.243277 -169.216166)
			(xy 45.295633 -169.282742) (xy 45.341423 -169.353994) (xy 45.380234 -169.429275) (xy 45.411713 -169.507905)
			(xy 45.435574 -169.589172) (xy 45.451603 -169.672338) (xy 45.459654 -169.756652) (xy 45.460158 -169.799)
			(xy 45.459701 -169.84086) (xy 45.451854 -169.924212) (xy 45.43621 -170.006458) (xy 45.412908 -170.08687)
			(xy 45.382154 -170.164737) (xy 45.344219 -170.23937) (xy 45.322236 -170.274996) (xy 45.317364 -170.283394)
			(xy 45.313787 -170.302463) (xy 45.31756 -170.321494) (xy 45.32249 -170.32986) (xy 45.345406 -170.365979)
			(xy 45.384986 -170.441816) (xy 45.417097 -170.521104) (xy 45.441441 -170.603112) (xy 45.457794 -170.687078)
			(xy 45.466003 -170.772228) (xy 45.466508 -170.815) (xy 45.466 -170.841924) (xy 45.465746 -170.85183)
			(xy 45.472096 -170.86961) (xy 45.53077 -170.936412) (xy 45.547534 -170.945302) (xy 45.557186 -170.946064)
			(xy 45.600437 -170.951095) (xy 45.685767 -170.968459) (xy 45.768991 -170.994075) (xy 45.849316 -171.0277)
			(xy 45.92597 -171.069012) (xy 45.998223 -171.117615) (xy 46.065381 -171.173044) (xy 46.126802 -171.234769)
			(xy 46.1819 -171.302199) (xy 46.230146 -171.37469) (xy 46.27108 -171.451547) (xy 46.304308 -171.532036)
			(xy 46.329515 -171.615386) (xy 46.346457 -171.7008) (xy 46.354974 -171.787461) (xy 46.355508 -171.831)
			(xy 46.355031 -171.872536) (xy 46.347277 -171.955244) (xy 46.331847 -172.03687) (xy 46.308874 -172.116701)
			(xy 46.278559 -172.194043) (xy 46.241165 -172.268223) (xy 46.197019 -172.338593) (xy 46.146505 -172.404541)
			(xy 46.090063 -172.465492) (xy 46.028184 -172.520917) (xy 45.995082 -172.54601) (xy 45.985866 -172.553717)
			(xy 45.975117 -172.575162) (xy 45.974508 -172.587158) (xy 45.974508 -172.593) (xy 45.973922 -172.637977)
			(xy 45.964827 -172.72747) (xy 45.946759 -172.81559) (xy 45.933868 -172.858684) (xy 45.930566 -172.869352)
			(xy 45.933106 -172.890434) (xy 45.983652 -172.974762) (xy 46.001178 -172.986954) (xy 46.0121 -172.988986)
			(xy 46.052337 -172.997108) (xy 46.131255 -173.019704) (xy 46.207755 -173.049477) (xy 46.281187 -173.086173)
			(xy 46.350924 -173.129479) (xy 46.416374 -173.179027) (xy 46.47698 -173.234396) (xy 46.532225 -173.295114)
			(xy 46.581641 -173.360664) (xy 46.624806 -173.430489) (xy 46.661352 -173.503994) (xy 46.69097 -173.580555)
			(xy 46.713407 -173.659519) (xy 46.728471 -173.740215) (xy 46.736036 -173.821955) (xy 46.736508 -173.863)
			(xy 46.734984 -173.913292) (xy 46.734836 -173.923082) (xy 46.741143 -173.941606) (xy 46.753921 -173.956424)
			(xy 46.762416 -173.961298) (xy 46.798276 -173.980322) (xy 46.866757 -174.023921) (xy 46.93098 -174.07358)
			(xy 46.99041 -174.128885) (xy 47.044553 -174.189376) (xy 47.092958 -174.254549) (xy 47.135222 -174.323862)
			(xy 47.170993 -174.396739) (xy 47.199974 -174.472572) (xy 47.221923 -174.550731) (xy 47.236658 -174.630564)
			(xy 47.244057 -174.711409) (xy 47.244508 -174.752) (xy 47.244033 -174.793102) (xy 47.236448 -174.874957)
			(xy 47.221343 -174.955762) (xy 47.198847 -175.034829) (xy 47.169151 -175.111483) (xy 47.132509 -175.18507)
			(xy 47.089234 -175.254962) (xy 47.039694 -175.320563) (xy 46.984313 -175.381313) (xy 46.923563 -175.436694)
			(xy 46.857962 -175.486234) (xy 46.78807 -175.529509) (xy 46.714483 -175.566151) (xy 46.637829 -175.595847)
			(xy 46.558762 -175.618343) (xy 46.477957 -175.633448) (xy 46.396102 -175.641033) (xy 46.355 -175.641508)
			(xy 46.306232 -175.640238) (xy 46.291754 -175.639476) (xy 46.266862 -175.652684) (xy 46.206664 -175.756062)
			(xy 46.207172 -175.784256) (xy 46.215046 -175.796448) (xy 46.235214 -175.828686) (xy 46.270636 -175.895982)
			(xy 46.300188 -175.966054) (xy 46.323654 -176.038392) (xy 46.332648 -176.07534) (xy 46.335828 -176.086307)
			(xy 46.350084 -176.104108) (xy 46.36008 -176.10963) (xy 46.397352 -176.128081) (xy 46.468583 -176.171025)
			(xy 46.535493 -176.22043) (xy 46.5975 -176.275865) (xy 46.654062 -176.336846) (xy 46.704685 -176.40284)
			(xy 46.748927 -176.473272) (xy 46.786402 -176.547525) (xy 46.816782 -176.624952) (xy 46.839802 -176.704877)
			(xy 46.855262 -176.786602) (xy 46.863025 -176.869413) (xy 46.863508 -176.911) (xy 46.863033 -176.952102)
			(xy 46.855448 -177.033957) (xy 46.840343 -177.114762) (xy 46.817847 -177.193829) (xy 46.788151 -177.270483)
			(xy 46.751509 -177.34407) (xy 46.708234 -177.413962) (xy 46.658694 -177.479563) (xy 46.603313 -177.540313)
			(xy 46.542563 -177.595694) (xy 46.476962 -177.645234) (xy 46.40707 -177.688509) (xy 46.333483 -177.725151)
			(xy 46.256829 -177.754847) (xy 46.177762 -177.777343) (xy 46.096957 -177.792448) (xy 46.015102 -177.800033)
			(xy 45.974 -177.800508) (xy 45.931315 -177.800055) (xy 45.846335 -177.791885) (xy 45.76253 -177.77561)
			(xy 45.68067 -177.75138) (xy 45.601508 -177.719419) (xy 45.525772 -177.680019) (xy 45.45416 -177.633544)
			(xy 45.387331 -177.580422) (xy 45.325899 -177.52114) (xy 45.270429 -177.456246) (xy 45.221433 -177.386335)
			(xy 45.17936 -177.312051) (xy 45.144599 -177.234078) (xy 45.117468 -177.153132) (xy 45.107352 -177.11166)
			(xy 45.104172 -177.100693) (xy 45.089916 -177.082892) (xy 45.07992 -177.07737) (xy 45.042648 -177.058919)
			(xy 44.971417 -177.015975) (xy 44.904507 -176.96657) (xy 44.8425 -176.911135) (xy 44.785938 -176.850154)
			(xy 44.735315 -176.78416) (xy 44.691073 -176.713728) (xy 44.653598 -176.639475) (xy 44.623218 -176.562048)
			(xy 44.600198 -176.482123) (xy 44.584738 -176.400398) (xy 44.576975 -176.317587) (xy 44.576492 -176.276)
			(xy 44.576967 -176.234898) (xy 44.584552 -176.153043) (xy 44.599657 -176.072238) (xy 44.622153 -175.993171)
			(xy 44.651849 -175.916517) (xy 44.688491 -175.84293) (xy 44.731766 -175.773038) (xy 44.781306 -175.707437)
			(xy 44.836687 -175.646687) (xy 44.897437 -175.591306) (xy 44.963038 -175.541766) (xy 45.03293 -175.498491)
			(xy 45.106517 -175.461849) (xy 45.183171 -175.432153) (xy 45.262238 -175.409657) (xy 45.343043 -175.394552)
			(xy 45.424898 -175.386967) (xy 45.466 -175.386492) (xy 45.514768 -175.387762) (xy 45.529246 -175.388524)
			(xy 45.554138 -175.375316) (xy 45.614336 -175.271938) (xy 45.613828 -175.243744) (xy 45.605954 -175.231552)
			(xy 45.583604 -175.195733) (xy 45.545015 -175.120632) (xy 45.513714 -175.042214) (xy 45.48998 -174.961184)
			(xy 45.474029 -174.878269) (xy 45.466003 -174.794217) (xy 45.465492 -174.752) (xy 45.467016 -174.701708)
			(xy 45.467164 -174.691918) (xy 45.460857 -174.673394) (xy 45.448079 -174.658576) (xy 45.439584 -174.653702)
			(xy 45.403724 -174.634678) (xy 45.335243 -174.591079) (xy 45.27102 -174.54142) (xy 45.21159 -174.486115)
			(xy 45.157447 -174.425624) (xy 45.109042 -174.360451) (xy 45.066778 -174.291138) (xy 45.031007 -174.218261)
			(xy 45.002026 -174.142428) (xy 44.980077 -174.064269) (xy 44.965342 -173.984436) (xy 44.957943 -173.903591)
			(xy 44.957492 -173.863) (xy 44.958078 -173.818023) (xy 44.967173 -173.72853) (xy 44.985241 -173.64041)
			(xy 44.998132 -173.597316) (xy 45.001434 -173.586648) (xy 44.998894 -173.565566) (xy 44.948348 -173.481238)
			(xy 44.930822 -173.469046) (xy 44.9199 -173.467014) (xy 44.879663 -173.458892) (xy 44.800745 -173.436296)
			(xy 44.724245 -173.406523) (xy 44.650813 -173.369827) (xy 44.581076 -173.326521) (xy 44.515626 -173.276973)
			(xy 44.45502 -173.221604) (xy 44.399775 -173.160886) (xy 44.350359 -173.095336) (xy 44.307194 -173.025511)
			(xy 44.270648 -172.952006) (xy 44.24103 -172.875445) (xy 44.218593 -172.796481) (xy 44.203529 -172.715785)
			(xy 44.195964 -172.634045) (xy 44.195492 -172.593) (xy 44.195969 -172.551464) (xy 44.203723 -172.468756)
			(xy 44.219153 -172.38713) (xy 44.242126 -172.307299) (xy 44.272441 -172.229957) (xy 44.309835 -172.155777)
			(xy 44.353981 -172.085407) (xy 44.404495 -172.019459) (xy 44.460937 -171.958508) (xy 44.522816 -171.903083)
			(xy 44.555918 -171.87799) (xy 44.565134 -171.870283) (xy 44.575883 -171.848838) (xy 44.576492 -171.836842)
			(xy 44.576492 -171.831) (xy 44.577 -171.804076) (xy 44.577254 -171.79417) (xy 44.570904 -171.77639)
			(xy 44.51223 -171.709588) (xy 44.495466 -171.700698) (xy 44.485814 -171.699936) (xy 44.442563 -171.694905)
			(xy 44.357233 -171.677541) (xy 44.274009 -171.651925) (xy 44.193684 -171.6183) (xy 44.11703 -171.576988)
			(xy 44.044777 -171.528385) (xy 43.977619 -171.472956) (xy 43.916198 -171.411231) (xy 43.8611 -171.343801)
			(xy 43.812854 -171.27131) (xy 43.77192 -171.194453) (xy 43.738692 -171.113964) (xy 43.713485 -171.030614)
			(xy 43.696543 -170.9452) (xy 43.688026 -170.858539) (xy 43.687492 -170.815) (xy 43.687957 -170.77314)
			(xy 43.695803 -170.689789) (xy 43.711446 -170.607543) (xy 43.734747 -170.527131) (xy 43.7655 -170.449264)
			(xy 43.803432 -170.374631) (xy 43.825414 -170.339004) (xy 43.83029 -170.330607) (xy 43.833871 -170.311537)
			(xy 43.830094 -170.292505) (xy 43.82516 -170.28414) (xy 43.802249 -170.248018) (xy 43.762668 -170.172182)
			(xy 43.730555 -170.092894) (xy 43.70621 -170.010888) (xy 43.689857 -169.926921) (xy 43.681647 -169.841772)
			(xy 43.681142 -169.799) (xy 40.780901 -169.799) (xy 40.806781 -169.810819) (xy 40.880131 -169.853168)
			(xy 40.949123 -169.902297) (xy 41.013133 -169.957762) (xy 41.071581 -170.01906) (xy 41.123937 -170.085636)
			(xy 41.169727 -170.156888) (xy 41.208538 -170.232169) (xy 41.240017 -170.310799) (xy 41.263878 -170.392066)
			(xy 41.279907 -170.475232) (xy 41.287958 -170.559546) (xy 41.288462 -170.601894) (xy 41.287958 -170.644242)
			(xy 41.279907 -170.728556) (xy 41.263878 -170.811722) (xy 41.240017 -170.892989) (xy 41.208538 -170.971619)
			(xy 41.169727 -171.0469) (xy 41.123937 -171.118152) (xy 41.071581 -171.184728) (xy 41.013133 -171.246026)
			(xy 40.949123 -171.301491) (xy 40.947195 -171.302864) (xy 41.701462 -171.302864) (xy 41.701462 -171.218168)
			(xy 41.709513 -171.133854) (xy 41.725542 -171.050688) (xy 41.749403 -170.969421) (xy 41.780882 -170.890791)
			(xy 41.819693 -170.81551) (xy 41.865483 -170.744258) (xy 41.917839 -170.677682) (xy 41.976287 -170.616384)
			(xy 42.040297 -170.560919) (xy 42.109289 -170.51179) (xy 42.182639 -170.469441) (xy 42.259682 -170.434257)
			(xy 42.339721 -170.406555) (xy 42.42203 -170.386587) (xy 42.505865 -170.374534) (xy 42.590466 -170.370504)
			(xy 42.675067 -170.374534) (xy 42.758902 -170.386587) (xy 42.841211 -170.406555) (xy 42.92125 -170.434257)
			(xy 42.998293 -170.469441) (xy 43.071643 -170.51179) (xy 43.140635 -170.560919) (xy 43.204645 -170.616384)
			(xy 43.263093 -170.677682) (xy 43.315449 -170.744258) (xy 43.361239 -170.81551) (xy 43.40005 -170.890791)
			(xy 43.431529 -170.969421) (xy 43.45539 -171.050688) (xy 43.471419 -171.133854) (xy 43.47947 -171.218168)
			(xy 43.479974 -171.260516) (xy 43.47947 -171.302864) (xy 43.471419 -171.387178) (xy 43.45539 -171.470344)
			(xy 43.431529 -171.551611) (xy 43.40005 -171.630241) (xy 43.361239 -171.705522) (xy 43.315449 -171.776774)
			(xy 43.263093 -171.84335) (xy 43.204645 -171.904648) (xy 43.140635 -171.960113) (xy 43.071643 -172.009242)
			(xy 42.998293 -172.051591) (xy 42.92125 -172.086775) (xy 42.841211 -172.114477) (xy 42.758902 -172.134445)
			(xy 42.675067 -172.146498) (xy 42.590466 -172.150529) (xy 42.505865 -172.146498) (xy 42.42203 -172.134445)
			(xy 42.339721 -172.114477) (xy 42.259682 -172.086775) (xy 42.182639 -172.051591) (xy 42.109289 -172.009242)
			(xy 42.040297 -171.960113) (xy 41.976287 -171.904648) (xy 41.917839 -171.84335) (xy 41.865483 -171.776774)
			(xy 41.819693 -171.705522) (xy 41.780882 -171.630241) (xy 41.749403 -171.551611) (xy 41.725542 -171.470344)
			(xy 41.709513 -171.387178) (xy 41.701462 -171.302864) (xy 40.947195 -171.302864) (xy 40.880131 -171.35062)
			(xy 40.806781 -171.392969) (xy 40.729738 -171.428153) (xy 40.649699 -171.455855) (xy 40.56739 -171.475823)
			(xy 40.483555 -171.487876) (xy 40.398954 -171.491907) (xy 40.314353 -171.487876) (xy 40.230518 -171.475823)
			(xy 40.148209 -171.455855) (xy 40.06817 -171.428153) (xy 39.991127 -171.392969) (xy 39.917777 -171.35062)
			(xy 39.848785 -171.301491) (xy 39.784775 -171.246026) (xy 39.726327 -171.184728) (xy 39.673971 -171.118152)
			(xy 39.628181 -171.0469) (xy 39.58937 -170.971619) (xy 39.557891 -170.892989) (xy 39.53403 -170.811722)
			(xy 39.518001 -170.728556) (xy 39.50995 -170.644242) (xy 31.902405 -170.644242) (xy 31.894023 -170.651505)
			(xy 31.825031 -170.700634) (xy 31.751681 -170.742983) (xy 31.674638 -170.778167) (xy 31.594599 -170.805869)
			(xy 31.51229 -170.825837) (xy 31.428455 -170.83789) (xy 31.343854 -170.841921) (xy 31.259253 -170.83789)
			(xy 31.175418 -170.825837) (xy 31.093109 -170.805869) (xy 31.01307 -170.778167) (xy 30.936027 -170.742983)
			(xy 30.862677 -170.700634) (xy 30.793685 -170.651505) (xy 30.729675 -170.59604) (xy 30.671227 -170.534742)
			(xy 30.618871 -170.468166) (xy 30.573081 -170.396914) (xy 30.53427 -170.321633) (xy 30.502791 -170.243003)
			(xy 30.47893 -170.161736) (xy 30.462901 -170.07857) (xy 30.45485 -169.994256) (xy 26.411416 -169.994256)
			(xy 26.451119 -170.044742) (xy 26.496909 -170.115994) (xy 26.53572 -170.191275) (xy 26.567199 -170.269905)
			(xy 26.59106 -170.351172) (xy 26.607089 -170.434338) (xy 26.61514 -170.518652) (xy 26.615644 -170.561)
			(xy 26.615189 -170.60286) (xy 26.607342 -170.686212) (xy 26.591698 -170.768458) (xy 26.568395 -170.84887)
			(xy 26.537641 -170.926737) (xy 26.499706 -171.00137) (xy 26.477722 -171.036996) (xy 26.472851 -171.045394)
			(xy 26.469275 -171.064463) (xy 26.473047 -171.083494) (xy 26.477976 -171.09186) (xy 26.500891 -171.12798)
			(xy 26.540471 -171.203816) (xy 26.572582 -171.283105) (xy 26.596927 -171.365112) (xy 26.61328 -171.449078)
			(xy 26.621489 -171.534228) (xy 26.621994 -171.577) (xy 26.62149 -171.619348) (xy 26.613439 -171.703662)
			(xy 26.59741 -171.786828) (xy 26.573549 -171.868095) (xy 26.54207 -171.946725) (xy 26.503259 -172.022006)
			(xy 26.457469 -172.093258) (xy 26.405113 -172.159834) (xy 26.346665 -172.221132) (xy 26.282655 -172.276597)
			(xy 26.213663 -172.325726) (xy 26.140313 -172.368075) (xy 26.06327 -172.403259) (xy 25.983231 -172.430961)
			(xy 25.900922 -172.450929) (xy 25.817087 -172.462982) (xy 25.732486 -172.467013) (xy 25.647885 -172.462982)
			(xy 25.56405 -172.450929) (xy 25.481741 -172.430961) (xy 25.401702 -172.403259) (xy 25.324659 -172.368075)
			(xy 25.251309 -172.325726) (xy 25.182317 -172.276597) (xy 25.118307 -172.221132) (xy 25.059859 -172.159834)
			(xy 25.007503 -172.093258) (xy 24.961713 -172.022006) (xy 24.922902 -171.946725) (xy 24.891423 -171.868095)
			(xy 24.867562 -171.786828) (xy 24.851533 -171.703662) (xy 24.843482 -171.619348) (xy 24.842978 -171.577)
			(xy 24.843445 -171.53514) (xy 24.851291 -171.451789) (xy 24.866934 -171.369544) (xy 24.890235 -171.289132)
			(xy 24.920987 -171.211265) (xy 24.958918 -171.136631) (xy 24.9809 -171.101004) (xy 24.985777 -171.092607)
			(xy 24.989359 -171.073537) (xy 24.985581 -171.054504) (xy 24.980646 -171.04614) (xy 24.957734 -171.010019)
			(xy 24.918152 -170.934183) (xy 24.886041 -170.854895) (xy 24.861696 -170.772888) (xy 24.845343 -170.688921)
			(xy 24.837133 -170.603772) (xy 24.836628 -170.561) (xy 18.295795 -170.561) (xy 18.257358 -170.622359)
			(xy 18.206948 -170.688278) (xy 18.150621 -170.749217) (xy 18.088865 -170.804649) (xy 18.022217 -170.85409)
			(xy 17.951256 -170.897112) (xy 17.876598 -170.933342) (xy 17.837912 -170.94835) (xy 17.824958 -170.953176)
			(xy 17.807686 -170.974512) (xy 17.790414 -171.090082) (xy 17.800828 -171.115736) (xy 17.812004 -171.124118)
			(xy 17.844212 -171.149259) (xy 17.904314 -171.20462) (xy 17.959087 -171.265259) (xy 18.008068 -171.330665)
			(xy 18.050846 -171.400287) (xy 18.087059 -171.473538) (xy 18.116402 -171.549802) (xy 18.138629 -171.628434)
			(xy 18.153552 -171.708774) (xy 18.161045 -171.790143) (xy 18.161508 -171.831) (xy 18.161056 -171.872024)
			(xy 18.153508 -171.953723) (xy 18.138468 -172.03438) (xy 18.116064 -172.113308) (xy 18.086485 -172.189838)
			(xy 18.049984 -172.263319) (xy 18.00687 -172.333125) (xy 17.957511 -172.398664) (xy 17.902325 -172.459378)
			(xy 17.841781 -172.514752) (xy 17.776395 -172.564314) (xy 17.706723 -172.607643) (xy 17.633356 -172.644372)
			(xy 17.556918 -172.674187) (xy 17.517618 -172.685964) (xy 17.50955 -172.688621) (xy 17.495678 -172.698408)
			(xy 17.485788 -172.712205) (xy 17.483074 -172.720254) (xy 17.47012 -172.761814) (xy 17.437187 -172.842402)
			(xy 17.396534 -172.919384) (xy 17.348551 -172.992024) (xy 17.293696 -173.059626) (xy 17.232497 -173.121542)
			(xy 17.199356 -173.149768) (xy 17.19072 -173.157134) (xy 17.181068 -173.177454) (xy 17.181068 -173.278546)
			(xy 17.19072 -173.298866) (xy 17.199356 -173.306232) (xy 17.232351 -173.334343) (xy 17.293292 -173.395995)
			(xy 17.347948 -173.463281) (xy 17.395801 -173.535564) (xy 17.436398 -173.612158) (xy 17.469353 -173.692337)
			(xy 17.494354 -173.775341) (xy 17.511164 -173.860383) (xy 17.519624 -173.946656) (xy 17.520158 -173.99)
			(xy 17.519633 -174.031101) (xy 17.512049 -174.112952) (xy 17.496945 -174.193755) (xy 17.47445 -174.272819)
			(xy 17.444756 -174.349471) (xy 17.408117 -174.423056) (xy 17.364845 -174.492946) (xy 17.315308 -174.558546)
			(xy 17.259931 -174.619295) (xy 17.199184 -174.674676) (xy 17.133587 -174.724216) (xy 17.088719 -174.752)
			(xy 20.954492 -174.752) (xy 20.954995 -174.709685) (xy 20.963026 -174.625437) (xy 20.979024 -174.542334)
			(xy 21.002845 -174.461125) (xy 21.034272 -174.382548) (xy 21.073023 -174.307311) (xy 21.095462 -174.271432)
			(xy 21.100345 -174.263043) (xy 21.104017 -174.244) (xy 21.100345 -174.224957) (xy 21.095462 -174.216568)
			(xy 21.073024 -174.180689) (xy 21.034273 -174.105451) (xy 21.002843 -174.026874) (xy 20.979019 -173.945666)
			(xy 20.963015 -173.862563) (xy 20.954977 -173.778315) (xy 20.954977 -173.693685) (xy 20.963015 -173.609437)
			(xy 20.979019 -173.526334) (xy 21.002843 -173.445126) (xy 21.034273 -173.366549) (xy 21.073024 -173.291311)
			(xy 21.095462 -173.255432) (xy 21.100345 -173.247043) (xy 21.104017 -173.228) (xy 21.100345 -173.208957)
			(xy 21.095462 -173.200568) (xy 21.073024 -173.164689) (xy 21.034273 -173.089451) (xy 21.002843 -173.010874)
			(xy 20.979019 -172.929666) (xy 20.963015 -172.846563) (xy 20.954977 -172.762315) (xy 20.954977 -172.677685)
			(xy 20.963015 -172.593437) (xy 20.979019 -172.510334) (xy 21.002843 -172.429126) (xy 21.034273 -172.350549)
			(xy 21.073024 -172.275311) (xy 21.095462 -172.239432) (xy 21.100345 -172.231043) (xy 21.104017 -172.212)
			(xy 21.100345 -172.192957) (xy 21.095462 -172.184568) (xy 21.073016 -172.148694) (xy 21.034273 -172.073453)
			(xy 21.002849 -171.994874) (xy 20.97903 -171.913665) (xy 20.96303 -171.830562) (xy 20.954994 -171.746315)
			(xy 20.954492 -171.704) (xy 20.954996 -171.661652) (xy 20.963047 -171.577338) (xy 20.979076 -171.494172)
			(xy 21.002937 -171.412905) (xy 21.034416 -171.334275) (xy 21.073227 -171.258994) (xy 21.119017 -171.187742)
			(xy 21.171373 -171.121166) (xy 21.229821 -171.059868) (xy 21.293831 -171.004403) (xy 21.362823 -170.955274)
			(xy 21.436173 -170.912925) (xy 21.513216 -170.877741) (xy 21.593255 -170.850039) (xy 21.675564 -170.830071)
			(xy 21.759399 -170.818018) (xy 21.844 -170.813988) (xy 21.928601 -170.818018) (xy 22.012436 -170.830071)
			(xy 22.094745 -170.850039) (xy 22.174784 -170.877741) (xy 22.251827 -170.912925) (xy 22.325177 -170.955274)
			(xy 22.394169 -171.004403) (xy 22.458179 -171.059868) (xy 22.516627 -171.121166) (xy 22.568983 -171.187742)
			(xy 22.614773 -171.258994) (xy 22.653584 -171.334275) (xy 22.685063 -171.412905) (xy 22.708924 -171.494172)
			(xy 22.724953 -171.577338) (xy 22.733004 -171.661652) (xy 22.733508 -171.704) (xy 22.733005 -171.746315)
			(xy 22.724974 -171.830563) (xy 22.708976 -171.913666) (xy 22.685155 -171.994875) (xy 22.653728 -172.073452)
			(xy 22.614977 -172.148689) (xy 22.592538 -172.184568) (xy 22.587655 -172.192957) (xy 22.583983 -172.212)
			(xy 22.587655 -172.231043) (xy 22.592538 -172.239432) (xy 22.614976 -172.275311) (xy 22.653727 -172.350549)
			(xy 22.685157 -172.429126) (xy 22.708981 -172.510334) (xy 22.724985 -172.593437) (xy 22.733023 -172.677685)
			(xy 22.733023 -172.762315) (xy 22.724985 -172.846563) (xy 22.708981 -172.929666) (xy 22.685157 -173.010874)
			(xy 22.653727 -173.089451) (xy 22.614976 -173.164689) (xy 22.592538 -173.200568) (xy 22.587655 -173.208957)
			(xy 22.583983 -173.228) (xy 22.587655 -173.247043) (xy 22.592538 -173.255432) (xy 22.614976 -173.291311)
			(xy 22.632567 -173.325466) (xy 41.692064 -173.325466) (xy 41.692064 -173.24077) (xy 41.700115 -173.156456)
			(xy 41.716144 -173.07329) (xy 41.740005 -172.992023) (xy 41.771484 -172.913393) (xy 41.810295 -172.838112)
			(xy 41.856085 -172.76686) (xy 41.908441 -172.700284) (xy 41.966889 -172.638986) (xy 42.030899 -172.583521)
			(xy 42.099891 -172.534392) (xy 42.173241 -172.492043) (xy 42.250284 -172.456859) (xy 42.330323 -172.429157)
			(xy 42.412632 -172.409189) (xy 42.496467 -172.397136) (xy 42.581068 -172.393106) (xy 42.665669 -172.397136)
			(xy 42.749504 -172.409189) (xy 42.831813 -172.429157) (xy 42.911852 -172.456859) (xy 42.988895 -172.492043)
			(xy 43.062245 -172.534392) (xy 43.131237 -172.583521) (xy 43.195247 -172.638986) (xy 43.253695 -172.700284)
			(xy 43.306051 -172.76686) (xy 43.351841 -172.838112) (xy 43.390652 -172.913393) (xy 43.422131 -172.992023)
			(xy 43.445992 -173.07329) (xy 43.462021 -173.156456) (xy 43.470072 -173.24077) (xy 43.470576 -173.283118)
			(xy 43.470072 -173.325466) (xy 43.462021 -173.40978) (xy 43.445992 -173.492946) (xy 43.422131 -173.574213)
			(xy 43.390652 -173.652843) (xy 43.351841 -173.728124) (xy 43.306051 -173.799376) (xy 43.253695 -173.865952)
			(xy 43.195247 -173.92725) (xy 43.131237 -173.982715) (xy 43.062245 -174.031844) (xy 42.988895 -174.074193)
			(xy 42.911852 -174.109377) (xy 42.831813 -174.137079) (xy 42.749504 -174.157047) (xy 42.665669 -174.1691)
			(xy 42.581068 -174.173131) (xy 42.496467 -174.1691) (xy 42.412632 -174.157047) (xy 42.330323 -174.137079)
			(xy 42.250284 -174.109377) (xy 42.173241 -174.074193) (xy 42.099891 -174.031844) (xy 42.030899 -173.982715)
			(xy 41.966889 -173.92725) (xy 41.908441 -173.865952) (xy 41.856085 -173.799376) (xy 41.810295 -173.728124)
			(xy 41.771484 -173.652843) (xy 41.740005 -173.574213) (xy 41.716144 -173.492946) (xy 41.700115 -173.40978)
			(xy 41.692064 -173.325466) (xy 22.632567 -173.325466) (xy 22.653727 -173.366549) (xy 22.685157 -173.445126)
			(xy 22.708981 -173.526334) (xy 22.724985 -173.609437) (xy 22.733023 -173.693685) (xy 22.733023 -173.778315)
			(xy 22.724985 -173.862563) (xy 22.708981 -173.945666) (xy 22.685157 -174.026874) (xy 22.653727 -174.105451)
			(xy 22.614976 -174.180689) (xy 22.592538 -174.216568) (xy 22.587655 -174.224957) (xy 22.583983 -174.244)
			(xy 22.587655 -174.263043) (xy 22.592538 -174.271432) (xy 22.614984 -174.307306) (xy 22.653727 -174.382547)
			(xy 22.685151 -174.461126) (xy 22.70897 -174.542335) (xy 22.72497 -174.625438) (xy 22.733006 -174.709685)
			(xy 22.733508 -174.752) (xy 22.733004 -174.794348) (xy 22.724953 -174.878662) (xy 22.708924 -174.961828)
			(xy 22.685063 -175.043095) (xy 22.653584 -175.121725) (xy 22.614773 -175.197006) (xy 22.590613 -175.2346)
			(xy 28.955492 -175.2346) (xy 28.955996 -175.192252) (xy 28.964047 -175.107938) (xy 28.980076 -175.024772)
			(xy 29.003937 -174.943505) (xy 29.035416 -174.864875) (xy 29.074227 -174.789594) (xy 29.120017 -174.718342)
			(xy 29.172373 -174.651766) (xy 29.230821 -174.590468) (xy 29.294831 -174.535003) (xy 29.363823 -174.485874)
			(xy 29.437173 -174.443525) (xy 29.514216 -174.408341) (xy 29.594255 -174.380639) (xy 29.676564 -174.360671)
			(xy 29.760399 -174.348618) (xy 29.845 -174.344588) (xy 29.929601 -174.348618) (xy 30.013436 -174.360671)
			(xy 30.095745 -174.380639) (xy 30.175784 -174.408341) (xy 30.252827 -174.443525) (xy 30.326177 -174.485874)
			(xy 30.395169 -174.535003) (xy 30.459179 -174.590468) (xy 30.517627 -174.651766) (xy 30.569983 -174.718342)
			(xy 30.615773 -174.789594) (xy 30.654584 -174.864875) (xy 30.686063 -174.943505) (xy 30.698073 -174.98441)
			(xy 31.161482 -174.98441) (xy 31.161986 -174.942062) (xy 31.170037 -174.857748) (xy 31.186066 -174.774582)
			(xy 31.209927 -174.693315) (xy 31.241406 -174.614685) (xy 31.280217 -174.539404) (xy 31.326007 -174.468152)
			(xy 31.378363 -174.401576) (xy 31.436811 -174.340278) (xy 31.500821 -174.284813) (xy 31.569813 -174.235684)
			(xy 31.643163 -174.193335) (xy 31.720206 -174.158151) (xy 31.800245 -174.130449) (xy 31.882554 -174.110481)
			(xy 31.966389 -174.098428) (xy 32.05099 -174.094398) (xy 32.135591 -174.098428) (xy 32.219426 -174.110481)
			(xy 32.301735 -174.130449) (xy 32.381774 -174.158151) (xy 32.458817 -174.193335) (xy 32.532167 -174.235684)
			(xy 32.601159 -174.284813) (xy 32.665169 -174.340278) (xy 32.723617 -174.401576) (xy 32.775973 -174.468152)
			(xy 32.821763 -174.539404) (xy 32.860574 -174.614685) (xy 32.892053 -174.693315) (xy 32.915914 -174.774582)
			(xy 32.931943 -174.857748) (xy 32.939994 -174.942062) (xy 32.940498 -174.98441) (xy 32.940048 -175.024261)
			(xy 32.932915 -175.103642) (xy 32.918706 -175.182067) (xy 32.897537 -175.258906) (xy 32.869576 -175.333542)
			(xy 32.835049 -175.405376) (xy 32.815022 -175.439832) (xy 32.809434 -175.449484) (xy 32.806894 -175.471074)
			(xy 32.837374 -175.5648) (xy 32.852106 -175.581056) (xy 32.862266 -175.585374) (xy 32.877151 -175.591827)
			(xy 32.906496 -175.605673) (xy 32.92094 -175.61306) (xy 32.931608 -175.618648) (xy 32.954468 -175.619156)
			(xy 33.048448 -175.576992) (xy 33.06318 -175.559466) (xy 33.066228 -175.548036) (xy 33.077044 -175.50748)
			(xy 33.105367 -175.428461) (xy 33.141009 -175.352462) (xy 33.183653 -175.280159) (xy 33.232919 -175.212196)
			(xy 33.28837 -175.149177) (xy 33.349513 -175.091663) (xy 33.415802 -175.040166) (xy 33.486648 -174.995143)
			(xy 33.561421 -174.956997) (xy 33.639456 -174.926065) (xy 33.720058 -174.902623) (xy 33.80251 -174.88688)
			(xy 33.886079 -174.878975) (xy 33.92805 -174.878492) (xy 33.970398 -174.878996) (xy 34.054712 -174.887047)
			(xy 34.137878 -174.903076) (xy 34.219145 -174.926937) (xy 34.297775 -174.958416) (xy 34.373056 -174.997227)
			(xy 34.444308 -175.043017) (xy 34.510884 -175.095373) (xy 34.572182 -175.153821) (xy 34.627647 -175.217831)
			(xy 34.676776 -175.286823) (xy 34.719125 -175.360173) (xy 34.754309 -175.437216) (xy 34.782011 -175.517255)
			(xy 34.801979 -175.599564) (xy 34.814032 -175.683399) (xy 34.818063 -175.768) (xy 34.815597 -175.819746)
			(xy 38.979344 -175.819746) (xy 38.979344 -175.73505) (xy 38.987395 -175.650736) (xy 39.003424 -175.56757)
			(xy 39.027285 -175.486303) (xy 39.058764 -175.407673) (xy 39.097575 -175.332392) (xy 39.143365 -175.26114)
			(xy 39.195721 -175.194564) (xy 39.254169 -175.133266) (xy 39.318179 -175.077801) (xy 39.387171 -175.028672)
			(xy 39.460521 -174.986323) (xy 39.537564 -174.951139) (xy 39.617603 -174.923437) (xy 39.699912 -174.903469)
			(xy 39.783747 -174.891416) (xy 39.868348 -174.887386) (xy 39.952949 -174.891416) (xy 40.036784 -174.903469)
			(xy 40.119093 -174.923437) (xy 40.199132 -174.951139) (xy 40.276175 -174.986323) (xy 40.349525 -175.028672)
			(xy 40.418517 -175.077801) (xy 40.482527 -175.133266) (xy 40.540975 -175.194564) (xy 40.593331 -175.26114)
			(xy 40.639121 -175.332392) (xy 40.677932 -175.407673) (xy 40.709411 -175.486303) (xy 40.733272 -175.56757)
			(xy 40.749301 -175.650736) (xy 40.757352 -175.73505) (xy 40.757856 -175.777398) (xy 40.757352 -175.819746)
			(xy 40.749301 -175.90406) (xy 40.742885 -175.937348) (xy 41.544236 -175.937348) (xy 41.544236 -175.852652)
			(xy 41.552287 -175.768338) (xy 41.568316 -175.685172) (xy 41.592177 -175.603905) (xy 41.623656 -175.525275)
			(xy 41.662467 -175.449994) (xy 41.708257 -175.378742) (xy 41.760613 -175.312166) (xy 41.819061 -175.250868)
			(xy 41.883071 -175.195403) (xy 41.952063 -175.146274) (xy 42.025413 -175.103925) (xy 42.102456 -175.068741)
			(xy 42.182495 -175.041039) (xy 42.264804 -175.021071) (xy 42.348639 -175.009018) (xy 42.43324 -175.004988)
			(xy 42.517841 -175.009018) (xy 42.601676 -175.021071) (xy 42.683985 -175.041039) (xy 42.764024 -175.068741)
			(xy 42.841067 -175.103925) (xy 42.914417 -175.146274) (xy 42.983409 -175.195403) (xy 43.047419 -175.250868)
			(xy 43.105867 -175.312166) (xy 43.158223 -175.378742) (xy 43.204013 -175.449994) (xy 43.242824 -175.525275)
			(xy 43.274303 -175.603905) (xy 43.298164 -175.685172) (xy 43.314193 -175.768338) (xy 43.322244 -175.852652)
			(xy 43.322748 -175.895) (xy 43.322244 -175.937348) (xy 43.314193 -176.021662) (xy 43.298164 -176.104828)
			(xy 43.274303 -176.186095) (xy 43.242824 -176.264725) (xy 43.204013 -176.340006) (xy 43.158223 -176.411258)
			(xy 43.105867 -176.477834) (xy 43.047419 -176.539132) (xy 42.983409 -176.594597) (xy 42.914417 -176.643726)
			(xy 42.841067 -176.686075) (xy 42.764024 -176.721259) (xy 42.683985 -176.748961) (xy 42.601676 -176.768929)
			(xy 42.517841 -176.780982) (xy 42.43324 -176.785013) (xy 42.348639 -176.780982) (xy 42.264804 -176.768929)
			(xy 42.182495 -176.748961) (xy 42.102456 -176.721259) (xy 42.025413 -176.686075) (xy 41.952063 -176.643726)
			(xy 41.883071 -176.594597) (xy 41.819061 -176.539132) (xy 41.760613 -176.477834) (xy 41.708257 -176.411258)
			(xy 41.662467 -176.340006) (xy 41.623656 -176.264725) (xy 41.592177 -176.186095) (xy 41.568316 -176.104828)
			(xy 41.552287 -176.021662) (xy 41.544236 -175.937348) (xy 40.742885 -175.937348) (xy 40.733272 -175.987226)
			(xy 40.709411 -176.068493) (xy 40.677932 -176.147123) (xy 40.639121 -176.222404) (xy 40.593331 -176.293656)
			(xy 40.540975 -176.360232) (xy 40.482527 -176.42153) (xy 40.418517 -176.476995) (xy 40.349525 -176.526124)
			(xy 40.276175 -176.568473) (xy 40.199132 -176.603657) (xy 40.119093 -176.631359) (xy 40.036784 -176.651327)
			(xy 39.952949 -176.66338) (xy 39.868348 -176.667411) (xy 39.783747 -176.66338) (xy 39.699912 -176.651327)
			(xy 39.617603 -176.631359) (xy 39.537564 -176.603657) (xy 39.460521 -176.568473) (xy 39.387171 -176.526124)
			(xy 39.318179 -176.476995) (xy 39.254169 -176.42153) (xy 39.195721 -176.360232) (xy 39.143365 -176.293656)
			(xy 39.097575 -176.222404) (xy 39.058764 -176.147123) (xy 39.027285 -176.068493) (xy 39.003424 -175.987226)
			(xy 38.987395 -175.90406) (xy 38.979344 -175.819746) (xy 34.815597 -175.819746) (xy 34.814032 -175.852601)
			(xy 34.801979 -175.936436) (xy 34.782011 -176.018745) (xy 34.754309 -176.098784) (xy 34.719125 -176.175827)
			(xy 34.676776 -176.249177) (xy 34.627647 -176.318169) (xy 34.572182 -176.382179) (xy 34.510884 -176.440627)
			(xy 34.444308 -176.492983) (xy 34.373056 -176.538773) (xy 34.297775 -176.577584) (xy 34.219145 -176.609063)
			(xy 34.137878 -176.632924) (xy 34.054712 -176.648953) (xy 33.970398 -176.657004) (xy 33.92805 -176.657508)
			(xy 33.88555 -176.65701) (xy 33.800937 -176.648906) (xy 33.717483 -176.632765) (xy 33.635949 -176.608737)
			(xy 33.55708 -176.577039) (xy 33.51911 -176.55794) (xy 33.508442 -176.552352) (xy 33.485582 -176.551844)
			(xy 33.391602 -176.594008) (xy 33.37687 -176.611534) (xy 33.373822 -176.622964) (xy 33.36296 -176.663507)
			(xy 33.334639 -176.742524) (xy 33.299 -176.818521) (xy 33.256359 -176.890823) (xy 33.207096 -176.958785)
			(xy 33.151648 -177.021804) (xy 33.09051 -177.079318) (xy 33.024225 -177.130816) (xy 32.953382 -177.175839)
			(xy 32.878613 -177.213988) (xy 32.800582 -177.244922) (xy 32.719984 -177.268367) (xy 32.637535 -177.284114)
			(xy 32.55397 -177.292022) (xy 32.512 -177.292508) (xy 32.470898 -177.292033) (xy 32.389043 -177.284448)
			(xy 32.308238 -177.269343) (xy 32.229171 -177.246847) (xy 32.152517 -177.217151) (xy 32.07893 -177.180509)
			(xy 32.009038 -177.137234) (xy 31.943437 -177.087694) (xy 31.882687 -177.032313) (xy 31.827306 -176.971563)
			(xy 31.777766 -176.905962) (xy 31.734491 -176.83607) (xy 31.697849 -176.762483) (xy 31.668153 -176.685829)
			(xy 31.645657 -176.606762) (xy 31.630552 -176.525957) (xy 31.622967 -176.444102) (xy 31.622492 -176.403)
			(xy 31.622948 -176.363149) (xy 31.630081 -176.283768) (xy 31.644288 -176.205343) (xy 31.665456 -176.128505)
			(xy 31.693416 -176.053869) (xy 31.727942 -175.982034) (xy 31.747968 -175.947578) (xy 31.753556 -175.937926)
			(xy 31.756096 -175.916336) (xy 31.725616 -175.82261) (xy 31.710884 -175.806354) (xy 31.700724 -175.802036)
			(xy 31.661211 -175.784501) (xy 31.58542 -175.742916) (xy 31.51402 -175.694174) (xy 31.447687 -175.638734)
			(xy 31.387046 -175.57712) (xy 31.332669 -175.509913) (xy 31.28507 -175.437747) (xy 31.244697 -175.361303)
			(xy 31.211932 -175.281302) (xy 31.187083 -175.1985) (xy 31.170385 -175.113678) (xy 31.161996 -175.027635)
			(xy 31.161482 -174.98441) (xy 30.698073 -174.98441) (xy 30.709924 -175.024772) (xy 30.725953 -175.107938)
			(xy 30.734004 -175.192252) (xy 30.734508 -175.2346) (xy 30.734082 -175.275117) (xy 30.726705 -175.355815)
			(xy 30.712021 -175.435508) (xy 30.690152 -175.513535) (xy 30.661279 -175.589251) (xy 30.625641 -175.662028)
			(xy 30.583534 -175.731263) (xy 30.535306 -175.796383) (xy 30.481357 -175.856848) (xy 30.45206 -175.88484)
			(xy 30.443424 -175.892968) (xy 30.435042 -175.914304) (xy 30.443424 -176.017428) (xy 30.455108 -176.036986)
			(xy 30.465014 -176.04359) (xy 30.501145 -176.068257) (xy 30.568851 -176.123669) (xy 30.63079 -176.185459)
			(xy 30.686365 -176.253031) (xy 30.735037 -176.325733) (xy 30.776338 -176.402861) (xy 30.809868 -176.483672)
			(xy 30.835303 -176.567383) (xy 30.852397 -176.653187) (xy 30.860986 -176.740255) (xy 30.861508 -176.784)
			(xy 30.861004 -176.826348) (xy 30.852953 -176.910662) (xy 30.836924 -176.993828) (xy 30.813063 -177.075095)
			(xy 30.781584 -177.153725) (xy 30.742773 -177.229006) (xy 30.696983 -177.300258) (xy 30.644627 -177.366834)
			(xy 30.586179 -177.428132) (xy 30.522169 -177.483597) (xy 30.453177 -177.532726) (xy 30.379827 -177.575075)
			(xy 30.302784 -177.610259) (xy 30.222745 -177.637961) (xy 30.140436 -177.657929) (xy 30.056601 -177.669982)
			(xy 29.972 -177.674013) (xy 29.887399 -177.669982) (xy 29.803564 -177.657929) (xy 29.721255 -177.637961)
			(xy 29.641216 -177.610259) (xy 29.564173 -177.575075) (xy 29.490823 -177.532726) (xy 29.421831 -177.483597)
			(xy 29.357821 -177.428132) (xy 29.299373 -177.366834) (xy 29.247017 -177.300258) (xy 29.201227 -177.229006)
			(xy 29.162416 -177.153725) (xy 29.130937 -177.075095) (xy 29.107076 -176.993828) (xy 29.091047 -176.910662)
			(xy 29.082996 -176.826348) (xy 29.082492 -176.784) (xy 29.082918 -176.743483) (xy 29.090295 -176.662785)
			(xy 29.104979 -176.583092) (xy 29.126848 -176.505065) (xy 29.155721 -176.429349) (xy 29.191359 -176.356572)
			(xy 29.233466 -176.287337) (xy 29.281694 -176.222217) (xy 29.335643 -176.161752) (xy 29.36494 -176.13376)
			(xy 29.373576 -176.125632) (xy 29.381958 -176.104296) (xy 29.373576 -176.001172) (xy 29.361892 -175.981614)
			(xy 29.351986 -175.97501) (xy 29.315855 -175.950343) (xy 29.248149 -175.894931) (xy 29.18621 -175.833141)
			(xy 29.130635 -175.765569) (xy 29.081963 -175.692867) (xy 29.040662 -175.615739) (xy 29.007132 -175.534928)
			(xy 28.981697 -175.451217) (xy 28.964603 -175.365413) (xy 28.956014 -175.278345) (xy 28.955492 -175.2346)
			(xy 22.590613 -175.2346) (xy 22.568983 -175.268258) (xy 22.516627 -175.334834) (xy 22.458179 -175.396132)
			(xy 22.394169 -175.451597) (xy 22.325177 -175.500726) (xy 22.251827 -175.543075) (xy 22.174784 -175.578259)
			(xy 22.094745 -175.605961) (xy 22.012436 -175.625929) (xy 21.928601 -175.637982) (xy 21.844 -175.642013)
			(xy 21.759399 -175.637982) (xy 21.675564 -175.625929) (xy 21.593255 -175.605961) (xy 21.513216 -175.578259)
			(xy 21.436173 -175.543075) (xy 21.362823 -175.500726) (xy 21.293831 -175.451597) (xy 21.229821 -175.396132)
			(xy 21.171373 -175.334834) (xy 21.119017 -175.268258) (xy 21.073227 -175.197006) (xy 21.034416 -175.121725)
			(xy 21.002937 -175.043095) (xy 20.979076 -174.961828) (xy 20.963047 -174.878662) (xy 20.954996 -174.794348)
			(xy 20.954492 -174.752) (xy 17.088719 -174.752) (xy 17.063699 -174.767493) (xy 16.990116 -174.804136)
			(xy 16.913467 -174.833834) (xy 16.834404 -174.856334) (xy 16.753602 -174.871442) (xy 16.671751 -174.879031)
			(xy 16.63065 -174.879508) (xy 16.586991 -174.878987) (xy 16.500094 -174.870424) (xy 16.414454 -174.853386)
			(xy 16.330897 -174.828037) (xy 16.250226 -174.794621) (xy 16.173219 -174.753459) (xy 16.13662 -174.729648)
			(xy 16.123666 -174.721012) (xy 16.09344 -174.721012) (xy 15.9893 -174.789846) (xy 15.977616 -174.81804)
			(xy 15.98041 -174.83328) (xy 15.987777 -174.874478) (xy 15.995665 -174.957802) (xy 15.996158 -174.99965)
			(xy 15.995654 -175.041998) (xy 15.987603 -175.126312) (xy 15.971574 -175.209478) (xy 15.947713 -175.290745)
			(xy 15.916234 -175.369375) (xy 15.877423 -175.444656) (xy 15.831633 -175.515908) (xy 15.779277 -175.582484)
			(xy 15.720829 -175.643782) (xy 15.656819 -175.699247) (xy 15.587827 -175.748376) (xy 15.514477 -175.790725)
			(xy 15.437434 -175.825909) (xy 15.357395 -175.853611) (xy 15.275086 -175.873579) (xy 15.191251 -175.885632)
			(xy 15.10665 -175.889663) (xy 15.022049 -175.885632) (xy 14.938214 -175.873579) (xy 14.855905 -175.853611)
			(xy 14.775866 -175.825909) (xy 14.698823 -175.790725) (xy 14.625473 -175.748376) (xy 14.556481 -175.699247)
			(xy 14.492471 -175.643782) (xy 14.434023 -175.582484) (xy 14.381667 -175.515908) (xy 14.335877 -175.444656)
			(xy 14.297066 -175.369375) (xy 14.265587 -175.290745) (xy 14.241726 -175.209478) (xy 14.225697 -175.126312)
			(xy 14.217646 -175.041998) (xy 14.217142 -174.99965) (xy 14.217282 -174.979363) (xy 14.219189 -174.938834)
			(xy 14.220952 -174.918624) (xy 14.221479 -174.909185) (xy 14.216297 -174.891015) (xy 14.204878 -174.875963)
			(xy 14.188777 -174.866077) (xy 14.17955 -174.864014) (xy 14.139345 -174.855958) (xy 14.060502 -174.833409)
			(xy 13.984071 -174.803697) (xy 13.9107 -174.767074) (xy 13.841012 -174.723852) (xy 13.775599 -174.674397)
			(xy 13.715018 -174.61913) (xy 13.659782 -174.55852) (xy 13.61036 -174.493082) (xy 13.567174 -174.423372)
			(xy 13.530589 -174.349982) (xy 13.500916 -174.273535) (xy 13.478408 -174.194681) (xy 13.463255 -174.11409)
			(xy 13.458952 -174.073312) (xy 13.457788 -174.064285) (xy 13.449873 -174.047906) (xy 13.436728 -174.035331)
			(xy 13.420013 -174.028152) (xy 13.410946 -174.027338) (xy 13.36877 -174.024678) (xy 13.28515 -174.012416)
			(xy 13.203072 -173.992277) (xy 13.123274 -173.964441) (xy 13.046477 -173.929159) (xy 12.973374 -173.88675)
			(xy 12.904625 -173.837597) (xy 12.840849 -173.782142) (xy 12.782623 -173.720887) (xy 12.730471 -173.654384)
			(xy 12.684863 -173.583232) (xy 12.646213 -173.508075) (xy 12.614867 -173.429589) (xy 12.59111 -173.348484)
			(xy 12.575154 -173.26549) (xy 12.567145 -173.181357) (xy 12.56665 -173.1391) (xy 12.567213 -173.095814)
			(xy 12.575605 -173.009649) (xy 12.59233 -172.924708) (xy 12.617229 -172.841793) (xy 12.650067 -172.76169)
			(xy 12.690532 -172.685157) (xy 12.738242 -172.612918) (xy 12.792746 -172.545656) (xy 12.853527 -172.484009)
			(xy 12.920011 -172.428559) (xy 12.991567 -172.379831) (xy 13.06752 -172.338286) (xy 13.14715 -172.304318)
			(xy 13.229704 -172.278248) (xy 13.3144 -172.260323) (xy 13.400437 -172.250712) (xy 13.443712 -172.249592)
			(xy 13.454504 -172.248967) (xy 13.474083 -172.239848) (xy 13.488181 -172.223486) (xy 13.491718 -172.21327)
			(xy 13.504851 -172.171008) (xy 13.53831 -172.089074) (xy 13.579737 -172.010866) (xy 13.628722 -171.937156)
			(xy 13.684782 -171.868672) (xy 13.747362 -171.806091) (xy 13.815846 -171.75003) (xy 13.852398 -171.725082)
			(xy 13.863066 -171.71797) (xy 13.875004 -171.695618) (xy 13.875004 -171.585382) (xy 13.863066 -171.56303)
			(xy 13.852398 -171.555918) (xy 13.816194 -171.531277) (xy 13.748368 -171.475867) (xy 13.686314 -171.41406)
			(xy 13.630634 -171.346455) (xy 13.581867 -171.273705) (xy 13.540485 -171.196516) (xy 13.506888 -171.115633)
			(xy 13.481402 -171.031841) (xy 13.464273 -170.94595) (xy 13.455666 -170.858791) (xy 13.455142 -170.815)
			(xy 13.455646 -170.771653) (xy 13.464077 -170.68537) (xy 13.480868 -170.600318) (xy 13.505859 -170.517305)
			(xy 13.538814 -170.437119) (xy 13.579419 -170.360522) (xy 13.627289 -170.288243) (xy 13.681968 -170.220967)
			(xy 13.742937 -170.159335) (xy 13.775944 -170.131232) (xy 13.78458 -170.123866) (xy 13.794232 -170.103546)
			(xy 13.794232 -170.002454) (xy 13.78458 -169.982134) (xy 13.775944 -169.974768) (xy 13.742941 -169.946663)
			(xy 13.681983 -169.885023) (xy 13.627314 -169.817743) (xy 13.579451 -169.745462) (xy 13.53885 -169.668866)
			(xy 13.505896 -169.588683) (xy 13.480902 -169.505673) (xy 13.464105 -169.420625) (xy 13.455664 -169.334346)
			(xy 13.455142 -169.291) (xy 13.455396 -169.273982) (xy 13.455161 -169.264345) (xy 13.448376 -169.246321)
			(xy 13.442188 -169.23893) (xy 13.421614 -169.216578) (xy 13.414851 -169.209747) (xy 13.397625 -169.201253)
			(xy 13.388086 -169.200068) (xy 13.342541 -169.195953) (xy 13.252557 -169.179623) (xy 13.164722 -169.154152)
			(xy 13.079962 -169.119809) (xy 12.999169 -169.076957) (xy 12.960858 -169.051986) (xy 12.948158 -169.04335)
			(xy 12.917932 -169.043096) (xy 12.813792 -169.109644) (xy 12.8016 -169.137076) (xy 12.803886 -169.152062)
			(xy 12.808998 -169.186569) (xy 12.814467 -169.256118) (xy 12.814808 -169.291) (xy 12.814322 -169.334348)
			(xy 12.805891 -169.420631) (xy 12.789099 -169.505685) (xy 12.764106 -169.588699) (xy 12.731149 -169.668885)
			(xy 12.690541 -169.745482) (xy 12.642669 -169.817761) (xy 12.587987 -169.885035) (xy 12.527015 -169.946666)
			(xy 12.494006 -169.974768) (xy 12.48537 -169.982134) (xy 12.475718 -170.002454) (xy 12.475718 -170.103546)
			(xy 12.48537 -170.123866) (xy 12.494006 -170.131232) (xy 12.527009 -170.159337) (xy 12.587967 -170.220977)
			(xy 12.642636 -170.288257) (xy 12.690499 -170.360538) (xy 12.7311 -170.437134) (xy 12.764054 -170.517317)
			(xy 12.789048 -170.600327) (xy 12.805845 -170.685375) (xy 12.814286 -170.771654) (xy 12.814808 -170.815)
			(xy 12.814333 -170.856102) (xy 12.806748 -170.937957) (xy 12.791643 -171.018762) (xy 12.769147 -171.097829)
			(xy 12.739451 -171.174483) (xy 12.702809 -171.24807) (xy 12.659534 -171.317962) (xy 12.609994 -171.383563)
			(xy 12.554613 -171.444313) (xy 12.493863 -171.499694) (xy 12.428262 -171.549234) (xy 12.35837 -171.592509)
			(xy 12.284783 -171.629151) (xy 12.208129 -171.658847) (xy 12.129062 -171.681343) (xy 12.048257 -171.696448)
			(xy 11.966402 -171.704033) (xy 11.9253 -171.704508) (xy 11.882542 -171.704) (xy 11.797421 -171.695789)
			(xy 11.713481 -171.679446) (xy 11.631497 -171.655123) (xy 11.552225 -171.623044) (xy 11.476398 -171.583506)
			(xy 11.404716 -171.536873) (xy 11.337839 -171.483576) (xy 11.276386 -171.424107) (xy 11.220924 -171.359015)
			(xy 11.171965 -171.288901) (xy 11.129961 -171.214412) (xy 11.095299 -171.136235) (xy 11.0683 -171.055093)
			(xy 11.049212 -170.971734) (xy 11.038212 -170.886928) (xy 11.0363 -170.84421) (xy 11.035122 -170.831882)
			(xy 11.02292 -170.810381) (xy 11.012932 -170.803062) (xy 10.977344 -170.779805) (xy 10.910322 -170.727494)
			(xy 10.848598 -170.669024) (xy 10.792737 -170.604931) (xy 10.743247 -170.535799) (xy 10.700581 -170.462259)
			(xy 10.665129 -170.384983) (xy 10.637213 -170.304676) (xy 10.61709 -170.222071) (xy 10.604941 -170.137923)
			(xy 10.60088 -170.053) (xy 9.210548 -170.053) (xy 9.210044 -170.095348) (xy 9.201993 -170.179662)
			(xy 9.185964 -170.262828) (xy 9.162103 -170.344095) (xy 9.130624 -170.422725) (xy 9.091813 -170.498006)
			(xy 9.046023 -170.569258) (xy 8.993667 -170.635834) (xy 8.935219 -170.697132) (xy 8.871209 -170.752597)
			(xy 8.802217 -170.801726) (xy 8.728867 -170.844075) (xy 8.651824 -170.879259) (xy 8.571785 -170.906961)
			(xy 8.489476 -170.926929) (xy 8.405641 -170.938982) (xy 8.32104 -170.943013) (xy 8.236439 -170.938982)
			(xy 8.152604 -170.926929) (xy 8.070295 -170.906961) (xy 7.990256 -170.879259) (xy 7.913213 -170.844075)
			(xy 7.839863 -170.801726) (xy 7.770871 -170.752597) (xy 7.706861 -170.697132) (xy 7.648413 -170.635834)
			(xy 7.596057 -170.569258) (xy 7.550267 -170.498006) (xy 7.511456 -170.422725) (xy 7.479977 -170.344095)
			(xy 7.456116 -170.262828) (xy 7.440087 -170.179662) (xy 7.432036 -170.095348) (xy 7.244514 -170.095348)
			(xy 7.244828 -170.098555) (xy 7.24535 -170.1419) (xy 7.244787 -170.185186) (xy 7.236395 -170.271351)
			(xy 7.21967 -170.356292) (xy 7.194771 -170.439207) (xy 7.161933 -170.51931) (xy 7.121468 -170.595843)
			(xy 7.073758 -170.668082) (xy 7.019254 -170.735344) (xy 6.958473 -170.796991) (xy 6.891989 -170.852441)
			(xy 6.820433 -170.901169) (xy 6.74448 -170.942714) (xy 6.66485 -170.976682) (xy 6.582296 -171.002752)
			(xy 6.4976 -171.020677) (xy 6.411563 -171.030288) (xy 6.368288 -171.031408) (xy 6.357496 -171.032033)
			(xy 6.337917 -171.041152) (xy 6.323819 -171.057514) (xy 6.320282 -171.06773) (xy 6.30827 -171.106681)
			(xy 6.278044 -171.182387) (xy 6.241019 -171.25501) (xy 6.197505 -171.323942) (xy 6.147869 -171.388605)
			(xy 6.092525 -171.448455) (xy 6.031939 -171.502992) (xy 5.966617 -171.551759) (xy 5.897109 -171.594345)
			(xy 5.823996 -171.630394) (xy 5.747892 -171.659604) (xy 5.669435 -171.68173) (xy 5.589283 -171.696586)
			(xy 5.508108 -171.704047) (xy 5.46735 -171.704508) (xy 5.426248 -171.704033) (xy 5.344393 -171.696448)
			(xy 5.263588 -171.681343) (xy 5.184521 -171.658847) (xy 5.107867 -171.629151) (xy 5.03428 -171.592509)
			(xy 4.964388 -171.549234) (xy 4.898787 -171.499694) (xy 4.838037 -171.444313) (xy 4.782656 -171.383563)
			(xy 4.733116 -171.317962) (xy 4.689841 -171.24807) (xy 4.653199 -171.174483) (xy 4.623503 -171.097829)
			(xy 4.601007 -171.018762) (xy 4.585902 -170.937957) (xy 4.578317 -170.856102) (xy 4.577842 -170.815)
			(xy 4.578346 -170.771653) (xy 4.586777 -170.68537) (xy 4.603568 -170.600318) (xy 4.628559 -170.517305)
			(xy 4.661514 -170.437119) (xy 4.702119 -170.360522) (xy 4.749989 -170.288243) (xy 4.804668 -170.220967)
			(xy 4.865637 -170.159335) (xy 4.898644 -170.131232) (xy 4.90728 -170.123866) (xy 4.916932 -170.103546)
			(xy 4.916932 -170.002454) (xy 4.90728 -169.982134) (xy 4.898644 -169.974768) (xy 4.886035 -169.964183)
			(xy 4.861518 -169.942207) (xy 4.849622 -169.930826) (xy 4.8387 -169.920666) (xy 4.810252 -169.914824)
			(xy 4.69646 -169.95775) (xy 4.678934 -169.981118) (xy 4.677664 -169.996104) (xy 4.673922 -170.037416)
			(xy 4.659716 -170.119147) (xy 4.637962 -170.1992) (xy 4.608849 -170.276879) (xy 4.572628 -170.351511)
			(xy 4.529616 -170.422445) (xy 4.480186 -170.489067) (xy 4.424767 -170.550796) (xy 4.363842 -170.607097)
			(xy 4.297938 -170.65748) (xy 4.22763 -170.701508) (xy 4.153527 -170.738798) (xy 4.076274 -170.769026)
			(xy 3.996542 -170.791929) (xy 3.915024 -170.807309) (xy 3.832428 -170.815031) (xy 3.79095 -170.815508)
			(xy 3.749848 -170.815033) (xy 3.667993 -170.807448) (xy 3.587188 -170.792343) (xy 3.508121 -170.769847)
			(xy 3.431467 -170.740151) (xy 3.35788 -170.703509) (xy 3.287988 -170.660234) (xy 3.222387 -170.610694)
			(xy 3.161637 -170.555313) (xy 3.106256 -170.494563) (xy 3.056716 -170.428962) (xy 3.013441 -170.35907)
			(xy 2.976799 -170.285483) (xy 2.947103 -170.208829) (xy 2.924607 -170.129762) (xy 2.909502 -170.048957)
			(xy 2.901917 -169.967102) (xy 2.901442 -169.926) (xy 1.651254 -169.926) (xy 1.651254 -170.300904)
			(xy 1.652778 -170.35145) (xy 1.651254 -170.401996) (xy 1.651254 -172.508348) (xy 2.285996 -172.508348)
			(xy 2.285996 -172.423652) (xy 2.294047 -172.339338) (xy 2.310076 -172.256172) (xy 2.333937 -172.174905)
			(xy 2.365416 -172.096275) (xy 2.404227 -172.020994) (xy 2.450017 -171.949742) (xy 2.502373 -171.883166)
			(xy 2.560821 -171.821868) (xy 2.624831 -171.766403) (xy 2.693823 -171.717274) (xy 2.767173 -171.674925)
			(xy 2.844216 -171.639741) (xy 2.924255 -171.612039) (xy 3.006564 -171.592071) (xy 3.090399 -171.580018)
			(xy 3.175 -171.575988) (xy 3.259601 -171.580018) (xy 3.343436 -171.592071) (xy 3.425745 -171.612039)
			(xy 3.505784 -171.639741) (xy 3.582827 -171.674925) (xy 3.656177 -171.717274) (xy 3.725169 -171.766403)
			(xy 3.789179 -171.821868) (xy 3.847627 -171.883166) (xy 3.899983 -171.949742) (xy 3.945773 -172.020994)
			(xy 3.984584 -172.096275) (xy 4.016063 -172.174905) (xy 4.039924 -172.256172) (xy 4.055953 -172.339338)
			(xy 4.064004 -172.423652) (xy 4.064508 -172.466) (xy 7.423404 -172.466) (xy 7.423908 -172.423652)
			(xy 7.431959 -172.339338) (xy 7.447988 -172.256172) (xy 7.471849 -172.174905) (xy 7.503328 -172.096275)
			(xy 7.542139 -172.020994) (xy 7.587929 -171.949742) (xy 7.640285 -171.883166) (xy 7.698733 -171.821868)
			(xy 7.762743 -171.766403) (xy 7.831735 -171.717274) (xy 7.905085 -171.674925) (xy 7.982128 -171.639741)
			(xy 8.062167 -171.612039) (xy 8.144476 -171.592071) (xy 8.228311 -171.580018) (xy 8.312912 -171.575988)
			(xy 8.397513 -171.580018) (xy 8.481348 -171.592071) (xy 8.563657 -171.612039) (xy 8.643696 -171.639741)
			(xy 8.720739 -171.674925) (xy 8.794089 -171.717274) (xy 8.863081 -171.766403) (xy 8.927091 -171.821868)
			(xy 8.985539 -171.883166) (xy 9.037895 -171.949742) (xy 9.083685 -172.020994) (xy 9.122496 -172.096275)
			(xy 9.153975 -172.174905) (xy 9.177836 -172.256172) (xy 9.193865 -172.339338) (xy 9.201916 -172.423652)
			(xy 9.20242 -172.466) (xy 9.201882 -172.511217) (xy 9.192741 -172.601187) (xy 9.174514 -172.689765)
			(xy 9.147388 -172.776034) (xy 9.13003 -172.81779) (xy 9.126302 -172.82776) (xy 9.126425 -172.849019)
			(xy 9.130284 -172.858938) (xy 9.145719 -172.893735) (xy 9.17128 -172.965444) (xy 9.190623 -173.039074)
			(xy 9.203606 -173.114088) (xy 9.210134 -173.189936) (xy 9.210548 -173.228) (xy 9.210044 -173.270348)
			(xy 10.601956 -173.270348) (xy 10.601956 -173.185652) (xy 10.610007 -173.101338) (xy 10.626036 -173.018172)
			(xy 10.649897 -172.936905) (xy 10.681376 -172.858275) (xy 10.720187 -172.782994) (xy 10.765977 -172.711742)
			(xy 10.818333 -172.645166) (xy 10.876781 -172.583868) (xy 10.940791 -172.528403) (xy 11.009783 -172.479274)
			(xy 11.083133 -172.436925) (xy 11.160176 -172.401741) (xy 11.240215 -172.374039) (xy 11.322524 -172.354071)
			(xy 11.406359 -172.342018) (xy 11.49096 -172.337988) (xy 11.575561 -172.342018) (xy 11.659396 -172.354071)
			(xy 11.741705 -172.374039) (xy 11.821744 -172.401741) (xy 11.898787 -172.436925) (xy 11.972137 -172.479274)
			(xy 12.041129 -172.528403) (xy 12.105139 -172.583868) (xy 12.163587 -172.645166) (xy 12.215943 -172.711742)
			(xy 12.261733 -172.782994) (xy 12.300544 -172.858275) (xy 12.332023 -172.936905) (xy 12.355884 -173.018172)
			(xy 12.371913 -173.101338) (xy 12.379964 -173.185652) (xy 12.380468 -173.228) (xy 12.379964 -173.270348)
			(xy 12.371913 -173.354662) (xy 12.355884 -173.437828) (xy 12.332023 -173.519095) (xy 12.300544 -173.597725)
			(xy 12.261733 -173.673006) (xy 12.215943 -173.744258) (xy 12.163587 -173.810834) (xy 12.105139 -173.872132)
			(xy 12.041129 -173.927597) (xy 11.972137 -173.976726) (xy 11.898787 -174.019075) (xy 11.821744 -174.054259)
			(xy 11.741705 -174.081961) (xy 11.659396 -174.101929) (xy 11.575561 -174.113982) (xy 11.49096 -174.118013)
			(xy 11.406359 -174.113982) (xy 11.322524 -174.101929) (xy 11.240215 -174.081961) (xy 11.160176 -174.054259)
			(xy 11.083133 -174.019075) (xy 11.009783 -173.976726) (xy 10.940791 -173.927597) (xy 10.876781 -173.872132)
			(xy 10.818333 -173.810834) (xy 10.765977 -173.744258) (xy 10.720187 -173.673006) (xy 10.681376 -173.597725)
			(xy 10.649897 -173.519095) (xy 10.626036 -173.437828) (xy 10.610007 -173.354662) (xy 10.601956 -173.270348)
			(xy 9.210044 -173.270348) (xy 9.201993 -173.354662) (xy 9.185964 -173.437828) (xy 9.162103 -173.519095)
			(xy 9.130624 -173.597725) (xy 9.091813 -173.673006) (xy 9.046023 -173.744258) (xy 8.993667 -173.810834)
			(xy 8.935219 -173.872132) (xy 8.871209 -173.927597) (xy 8.802217 -173.976726) (xy 8.728867 -174.019075)
			(xy 8.651824 -174.054259) (xy 8.571785 -174.081961) (xy 8.489476 -174.101929) (xy 8.405641 -174.113982)
			(xy 8.32104 -174.118013) (xy 8.236439 -174.113982) (xy 8.152604 -174.101929) (xy 8.070295 -174.081961)
			(xy 7.990256 -174.054259) (xy 7.913213 -174.019075) (xy 7.839863 -173.976726) (xy 7.770871 -173.927597)
			(xy 7.706861 -173.872132) (xy 7.648413 -173.810834) (xy 7.596057 -173.744258) (xy 7.550267 -173.673006)
			(xy 7.511456 -173.597725) (xy 7.479977 -173.519095) (xy 7.456116 -173.437828) (xy 7.440087 -173.354662)
			(xy 7.432036 -173.270348) (xy 7.431532 -173.228) (xy 7.432074 -173.182783) (xy 7.441214 -173.092813)
			(xy 7.45944 -173.004236) (xy 7.486565 -172.917966) (xy 7.503922 -172.87621) (xy 7.507652 -172.86624)
			(xy 7.50753 -172.844981) (xy 7.503668 -172.835062) (xy 7.48823 -172.800267) (xy 7.46267 -172.728557)
			(xy 7.443328 -172.654926) (xy 7.430346 -172.579913) (xy 7.423818 -172.504064) (xy 7.423404 -172.466)
			(xy 4.064508 -172.466) (xy 4.064004 -172.508348) (xy 4.055953 -172.592662) (xy 4.039924 -172.675828)
			(xy 4.016063 -172.757095) (xy 3.984584 -172.835725) (xy 3.945773 -172.911006) (xy 3.899983 -172.982258)
			(xy 3.847627 -173.048834) (xy 3.789179 -173.110132) (xy 3.725169 -173.165597) (xy 3.656177 -173.214726)
			(xy 3.582827 -173.257075) (xy 3.505784 -173.292259) (xy 3.425745 -173.319961) (xy 3.343436 -173.339929)
			(xy 3.259601 -173.351982) (xy 3.175 -173.356013) (xy 3.090399 -173.351982) (xy 3.006564 -173.339929)
			(xy 2.924255 -173.319961) (xy 2.844216 -173.292259) (xy 2.767173 -173.257075) (xy 2.693823 -173.214726)
			(xy 2.624831 -173.165597) (xy 2.560821 -173.110132) (xy 2.502373 -173.048834) (xy 2.450017 -172.982258)
			(xy 2.404227 -172.911006) (xy 2.365416 -172.835725) (xy 2.333937 -172.757095) (xy 2.310076 -172.675828)
			(xy 2.294047 -172.592662) (xy 2.285996 -172.508348) (xy 1.651254 -172.508348) (xy 1.651254 -175.302348)
			(xy 2.901946 -175.302348) (xy 2.901946 -175.217652) (xy 2.909997 -175.133338) (xy 2.926026 -175.050172)
			(xy 2.949887 -174.968905) (xy 2.981366 -174.890275) (xy 3.020177 -174.814994) (xy 3.065967 -174.743742)
			(xy 3.118323 -174.677166) (xy 3.176771 -174.615868) (xy 3.240781 -174.560403) (xy 3.309773 -174.511274)
			(xy 3.383123 -174.468925) (xy 3.460166 -174.433741) (xy 3.540205 -174.406039) (xy 3.622514 -174.386071)
			(xy 3.706349 -174.374018) (xy 3.79095 -174.369988) (xy 3.875551 -174.374018) (xy 3.959386 -174.386071)
			(xy 4.041695 -174.406039) (xy 4.121734 -174.433741) (xy 4.198777 -174.468925) (xy 4.272127 -174.511274)
			(xy 4.341119 -174.560403) (xy 4.405129 -174.615868) (xy 4.463577 -174.677166) (xy 4.515933 -174.743742)
			(xy 4.561723 -174.814994) (xy 4.600534 -174.890275) (xy 4.632013 -174.968905) (xy 4.655874 -175.050172)
			(xy 4.671903 -175.133338) (xy 4.679954 -175.217652) (xy 4.680458 -175.26) (xy 4.679954 -175.302348)
			(xy 4.671903 -175.386662) (xy 4.655874 -175.469828) (xy 4.632013 -175.551095) (xy 4.600534 -175.629725)
			(xy 4.561723 -175.705006) (xy 4.515933 -175.776258) (xy 4.463577 -175.842834) (xy 4.405129 -175.904132)
			(xy 4.341119 -175.959597) (xy 4.272127 -176.008726) (xy 4.198777 -176.051075) (xy 4.121734 -176.086259)
			(xy 4.041695 -176.113961) (xy 3.959386 -176.133929) (xy 3.875551 -176.145982) (xy 3.79095 -176.150013)
			(xy 3.706349 -176.145982) (xy 3.622514 -176.133929) (xy 3.540205 -176.113961) (xy 3.460166 -176.086259)
			(xy 3.383123 -176.051075) (xy 3.309773 -176.008726) (xy 3.240781 -175.959597) (xy 3.176771 -175.904132)
			(xy 3.118323 -175.842834) (xy 3.065967 -175.776258) (xy 3.020177 -175.705006) (xy 2.981366 -175.629725)
			(xy 2.949887 -175.551095) (xy 2.926026 -175.469828) (xy 2.909997 -175.386662) (xy 2.901946 -175.302348)
			(xy 1.651254 -175.302348) (xy 1.651254 -175.380904) (xy 1.652778 -175.43145) (xy 1.651254 -175.481996)
			(xy 1.651254 -176.426298) (xy 7.619996 -176.426298) (xy 7.619996 -176.341602) (xy 7.628047 -176.257288)
			(xy 7.644076 -176.174122) (xy 7.667937 -176.092855) (xy 7.699416 -176.014225) (xy 7.738227 -175.938944)
			(xy 7.784017 -175.867692) (xy 7.836373 -175.801116) (xy 7.894821 -175.739818) (xy 7.958831 -175.684353)
			(xy 8.027823 -175.635224) (xy 8.101173 -175.592875) (xy 8.178216 -175.557691) (xy 8.258255 -175.529989)
			(xy 8.340564 -175.510021) (xy 8.424399 -175.497968) (xy 8.509 -175.493938) (xy 8.593601 -175.497968)
			(xy 8.677436 -175.510021) (xy 8.759745 -175.529989) (xy 8.839784 -175.557691) (xy 8.916827 -175.592875)
			(xy 8.990177 -175.635224) (xy 9.059169 -175.684353) (xy 9.123179 -175.739818) (xy 9.181627 -175.801116)
			(xy 9.233983 -175.867692) (xy 9.279773 -175.938944) (xy 9.318584 -176.014225) (xy 9.350063 -176.092855)
			(xy 9.373924 -176.174122) (xy 9.389953 -176.257288) (xy 9.398004 -176.341602) (xy 9.398508 -176.38395)
			(xy 9.398004 -176.426298) (xy 9.389953 -176.510612) (xy 9.373924 -176.593778) (xy 9.350063 -176.675045)
			(xy 9.318584 -176.753675) (xy 9.279773 -176.828956) (xy 9.233983 -176.900208) (xy 9.181627 -176.966784)
			(xy 9.123179 -177.028082) (xy 9.067551 -177.076284) (xy 14.350996 -177.076284) (xy 14.350996 -176.991588)
			(xy 14.359047 -176.907274) (xy 14.375076 -176.824108) (xy 14.398937 -176.742841) (xy 14.430416 -176.664211)
			(xy 14.469227 -176.58893) (xy 14.515017 -176.517678) (xy 14.567373 -176.451102) (xy 14.625821 -176.389804)
			(xy 14.689831 -176.334339) (xy 14.758823 -176.28521) (xy 14.832173 -176.242861) (xy 14.909216 -176.207677)
			(xy 14.989255 -176.179975) (xy 15.071564 -176.160007) (xy 15.155399 -176.147954) (xy 15.24 -176.143924)
			(xy 15.324601 -176.147954) (xy 15.408436 -176.160007) (xy 15.490745 -176.179975) (xy 15.570784 -176.207677)
			(xy 15.647827 -176.242861) (xy 15.721177 -176.28521) (xy 15.790169 -176.334339) (xy 15.854179 -176.389804)
			(xy 15.912627 -176.451102) (xy 15.964983 -176.517678) (xy 16.010773 -176.58893) (xy 16.049584 -176.664211)
			(xy 16.081063 -176.742841) (xy 16.104924 -176.824108) (xy 16.120953 -176.907274) (xy 16.129004 -176.991588)
			(xy 16.129508 -177.033936) (xy 16.129004 -177.076284) (xy 16.120953 -177.160598) (xy 16.104924 -177.243764)
			(xy 16.081063 -177.325031) (xy 16.049584 -177.403661) (xy 16.010773 -177.478942) (xy 15.964983 -177.550194)
			(xy 15.912627 -177.61677) (xy 15.854179 -177.678068) (xy 15.790169 -177.733533) (xy 15.721177 -177.782662)
			(xy 15.691147 -177.8) (xy 20.954492 -177.8) (xy 20.954995 -177.757685) (xy 20.963026 -177.673437)
			(xy 20.979024 -177.590334) (xy 21.002845 -177.509125) (xy 21.034272 -177.430548) (xy 21.073023 -177.355311)
			(xy 21.095462 -177.319432) (xy 21.100345 -177.311043) (xy 21.104017 -177.292) (xy 21.100345 -177.272957)
			(xy 21.095462 -177.264568) (xy 21.073016 -177.228694) (xy 21.034273 -177.153453) (xy 21.002849 -177.074874)
			(xy 20.97903 -176.993665) (xy 20.96303 -176.910562) (xy 20.954994 -176.826315) (xy 20.954492 -176.784)
			(xy 20.954996 -176.741652) (xy 20.963047 -176.657338) (xy 20.979076 -176.574172) (xy 21.002937 -176.492905)
			(xy 21.034416 -176.414275) (xy 21.073227 -176.338994) (xy 21.119017 -176.267742) (xy 21.171373 -176.201166)
			(xy 21.229821 -176.139868) (xy 21.293831 -176.084403) (xy 21.362823 -176.035274) (xy 21.436173 -175.992925)
			(xy 21.513216 -175.957741) (xy 21.593255 -175.930039) (xy 21.675564 -175.910071) (xy 21.759399 -175.898018)
			(xy 21.844 -175.893988) (xy 21.928601 -175.898018) (xy 22.012436 -175.910071) (xy 22.094745 -175.930039)
			(xy 22.174784 -175.957741) (xy 22.251827 -175.992925) (xy 22.325177 -176.035274) (xy 22.394169 -176.084403)
			(xy 22.458179 -176.139868) (xy 22.516627 -176.201166) (xy 22.568983 -176.267742) (xy 22.614773 -176.338994)
			(xy 22.653584 -176.414275) (xy 22.685063 -176.492905) (xy 22.708924 -176.574172) (xy 22.724953 -176.657338)
			(xy 22.733004 -176.741652) (xy 22.733508 -176.784) (xy 22.733005 -176.826315) (xy 22.724974 -176.910563)
			(xy 22.708976 -176.993666) (xy 22.685155 -177.074875) (xy 22.653728 -177.153452) (xy 22.614977 -177.228689)
			(xy 22.592538 -177.264568) (xy 22.587655 -177.272957) (xy 22.583983 -177.292) (xy 22.587655 -177.311043)
			(xy 22.592538 -177.319432) (xy 22.614984 -177.355306) (xy 22.653727 -177.430547) (xy 22.685151 -177.509126)
			(xy 22.70897 -177.590335) (xy 22.72497 -177.673438) (xy 22.733006 -177.757685) (xy 22.733508 -177.8)
			(xy 22.733004 -177.842348) (xy 22.724953 -177.926662) (xy 22.708924 -178.009828) (xy 22.685063 -178.091095)
			(xy 22.68296 -178.096348) (xy 46.843946 -178.096348) (xy 46.843946 -178.011652) (xy 46.851997 -177.927338)
			(xy 46.868026 -177.844172) (xy 46.891887 -177.762905) (xy 46.923366 -177.684275) (xy 46.962177 -177.608994)
			(xy 47.007967 -177.537742) (xy 47.060323 -177.471166) (xy 47.118771 -177.409868) (xy 47.182781 -177.354403)
			(xy 47.251773 -177.305274) (xy 47.325123 -177.262925) (xy 47.402166 -177.227741) (xy 47.482205 -177.200039)
			(xy 47.564514 -177.180071) (xy 47.648349 -177.168018) (xy 47.73295 -177.163988) (xy 47.817551 -177.168018)
			(xy 47.901386 -177.180071) (xy 47.983695 -177.200039) (xy 48.063734 -177.227741) (xy 48.140777 -177.262925)
			(xy 48.214127 -177.305274) (xy 48.283119 -177.354403) (xy 48.347129 -177.409868) (xy 48.405577 -177.471166)
			(xy 48.457933 -177.537742) (xy 48.503723 -177.608994) (xy 48.542534 -177.684275) (xy 48.574013 -177.762905)
			(xy 48.597874 -177.844172) (xy 48.613903 -177.927338) (xy 48.621954 -178.011652) (xy 48.622458 -178.054)
			(xy 48.621954 -178.096348) (xy 48.613903 -178.180662) (xy 48.597874 -178.263828) (xy 48.574013 -178.345095)
			(xy 48.542534 -178.423725) (xy 48.503723 -178.499006) (xy 48.457933 -178.570258) (xy 48.405577 -178.636834)
			(xy 48.347129 -178.698132) (xy 48.283119 -178.753597) (xy 48.214127 -178.802726) (xy 48.140777 -178.845075)
			(xy 48.063734 -178.880259) (xy 47.983695 -178.907961) (xy 47.901386 -178.927929) (xy 47.817551 -178.939982)
			(xy 47.73295 -178.944013) (xy 47.648349 -178.939982) (xy 47.564514 -178.927929) (xy 47.482205 -178.907961)
			(xy 47.402166 -178.880259) (xy 47.325123 -178.845075) (xy 47.251773 -178.802726) (xy 47.182781 -178.753597)
			(xy 47.118771 -178.698132) (xy 47.060323 -178.636834) (xy 47.007967 -178.570258) (xy 46.962177 -178.499006)
			(xy 46.923366 -178.423725) (xy 46.891887 -178.345095) (xy 46.868026 -178.263828) (xy 46.851997 -178.180662)
			(xy 46.843946 -178.096348) (xy 22.68296 -178.096348) (xy 22.653584 -178.169725) (xy 22.614773 -178.245006)
			(xy 22.568983 -178.316258) (xy 22.516627 -178.382834) (xy 22.458179 -178.444132) (xy 22.394169 -178.499597)
			(xy 22.325177 -178.548726) (xy 22.251827 -178.591075) (xy 22.174784 -178.626259) (xy 22.094745 -178.653961)
			(xy 22.012436 -178.673929) (xy 21.928601 -178.685982) (xy 21.844 -178.690013) (xy 21.759399 -178.685982)
			(xy 21.675564 -178.673929) (xy 21.593255 -178.653961) (xy 21.513216 -178.626259) (xy 21.436173 -178.591075)
			(xy 21.362823 -178.548726) (xy 21.293831 -178.499597) (xy 21.229821 -178.444132) (xy 21.171373 -178.382834)
			(xy 21.119017 -178.316258) (xy 21.073227 -178.245006) (xy 21.034416 -178.169725) (xy 21.002937 -178.091095)
			(xy 20.979076 -178.009828) (xy 20.963047 -177.926662) (xy 20.954996 -177.842348) (xy 20.954492 -177.8)
			(xy 15.691147 -177.8) (xy 15.647827 -177.825011) (xy 15.570784 -177.860195) (xy 15.490745 -177.887897)
			(xy 15.408436 -177.907865) (xy 15.324601 -177.919918) (xy 15.24 -177.923949) (xy 15.155399 -177.919918)
			(xy 15.071564 -177.907865) (xy 14.989255 -177.887897) (xy 14.909216 -177.860195) (xy 14.832173 -177.825011)
			(xy 14.758823 -177.782662) (xy 14.689831 -177.733533) (xy 14.625821 -177.678068) (xy 14.567373 -177.61677)
			(xy 14.515017 -177.550194) (xy 14.469227 -177.478942) (xy 14.430416 -177.403661) (xy 14.398937 -177.325031)
			(xy 14.375076 -177.243764) (xy 14.359047 -177.160598) (xy 14.350996 -177.076284) (xy 9.067551 -177.076284)
			(xy 9.059169 -177.083547) (xy 8.990177 -177.132676) (xy 8.916827 -177.175025) (xy 8.839784 -177.210209)
			(xy 8.759745 -177.237911) (xy 8.677436 -177.257879) (xy 8.593601 -177.269932) (xy 8.509 -177.273963)
			(xy 8.424399 -177.269932) (xy 8.340564 -177.257879) (xy 8.258255 -177.237911) (xy 8.178216 -177.210209)
			(xy 8.101173 -177.175025) (xy 8.027823 -177.132676) (xy 7.958831 -177.083547) (xy 7.894821 -177.028082)
			(xy 7.836373 -176.966784) (xy 7.784017 -176.900208) (xy 7.738227 -176.828956) (xy 7.699416 -176.753675)
			(xy 7.667937 -176.675045) (xy 7.644076 -176.593778) (xy 7.628047 -176.510612) (xy 7.619996 -176.426298)
			(xy 1.651254 -176.426298) (xy 1.651254 -180.086) (xy 2.412492 -180.086) (xy 2.412967 -180.044898)
			(xy 2.420552 -179.963043) (xy 2.435657 -179.882238) (xy 2.458153 -179.803171) (xy 2.487849 -179.726517)
			(xy 2.524491 -179.65293) (xy 2.567766 -179.583038) (xy 2.617306 -179.517437) (xy 2.672687 -179.456687)
			(xy 2.733437 -179.401306) (xy 2.799038 -179.351766) (xy 2.86893 -179.308491) (xy 2.942517 -179.271849)
			(xy 3.019171 -179.242153) (xy 3.098238 -179.219657) (xy 3.179043 -179.204552) (xy 3.260898 -179.196967)
			(xy 3.302 -179.196492) (xy 3.344134 -179.196986) (xy 3.428025 -179.204958) (xy 3.510787 -179.220825)
			(xy 3.591678 -179.244445) (xy 3.669973 -179.275607) (xy 3.744972 -179.314032) (xy 3.816002 -179.359375)
			(xy 3.882427 -179.411231) (xy 3.913378 -179.439824) (xy 3.921091 -179.446549) (xy 3.940228 -179.45375)
			(xy 3.950462 -179.453794) (xy 3.991102 -179.452778) (xy 4.030134 -179.453215) (xy 4.107895 -179.4601)
			(xy 4.184755 -179.473763) (xy 4.260124 -179.4941) (xy 4.296918 -179.507134) (xy 4.305943 -179.509966)
			(xy 4.324841 -179.509561) (xy 4.333748 -179.506372) (xy 4.361688 -179.494688) (xy 4.370304 -179.49076)
			(xy 4.383997 -179.477695) (xy 4.388358 -179.469288) (xy 4.406514 -179.431288) (xy 4.449046 -179.358591)
			(xy 4.498259 -179.290241) (xy 4.553714 -179.226849) (xy 4.614914 -179.168984) (xy 4.681311 -179.117165)
			(xy 4.752309 -179.071854) (xy 4.827273 -179.033459) (xy 4.905531 -179.002323) (xy 4.986382 -178.978725)
			(xy 5.069102 -178.962877) (xy 5.15295 -178.95492) (xy 5.195062 -178.95443) (xy 5.236164 -178.954905)
			(xy 5.318019 -178.96249) (xy 5.398824 -178.977595) (xy 5.477891 -179.000092) (xy 5.554544 -179.029788)
			(xy 5.628131 -179.06643) (xy 5.698023 -179.109705) (xy 5.763624 -179.159244) (xy 5.824374 -179.214626)
			(xy 5.879756 -179.275376) (xy 5.929295 -179.340977) (xy 5.97257 -179.410869) (xy 6.009212 -179.484456)
			(xy 6.038908 -179.561109) (xy 6.061405 -179.640176) (xy 6.07651 -179.720981) (xy 6.084095 -179.802836)
			(xy 6.08457 -179.843938) (xy 6.084103 -179.88635) (xy 6.076045 -179.97079) (xy 6.059987 -180.05408)
			(xy 6.036074 -180.135464) (xy 6.004524 -180.214202) (xy 5.98551 -180.252116) (xy 5.980895 -180.262275)
			(xy 5.979964 -180.28454) (xy 5.983732 -180.295042) (xy 6.000222 -180.335887) (xy 6.025998 -180.420122)
			(xy 6.043324 -180.506492) (xy 6.052029 -180.594151) (xy 6.052566 -180.638196) (xy 6.052104 -180.679299)
			(xy 6.044519 -180.761155) (xy 6.029414 -180.841961) (xy 6.019983 -180.875108) (xy 16.725896 -180.875108)
			(xy 16.725896 -180.790412) (xy 16.733947 -180.706098) (xy 16.749976 -180.622932) (xy 16.773837 -180.541665)
			(xy 16.805316 -180.463035) (xy 16.844127 -180.387754) (xy 16.889917 -180.316502) (xy 16.942273 -180.249926)
			(xy 17.000721 -180.188628) (xy 17.064731 -180.133163) (xy 17.133723 -180.084034) (xy 17.207073 -180.041685)
			(xy 17.284116 -180.006501) (xy 17.364155 -179.978799) (xy 17.446464 -179.958831) (xy 17.530299 -179.946778)
			(xy 17.6149 -179.942748) (xy 17.699501 -179.946778) (xy 17.783336 -179.958831) (xy 17.865645 -179.978799)
			(xy 17.945684 -180.006501) (xy 18.022727 -180.041685) (xy 18.096077 -180.084034) (xy 18.165069 -180.133163)
			(xy 18.229079 -180.188628) (xy 18.287527 -180.249926) (xy 18.339883 -180.316502) (xy 18.385673 -180.387754)
			(xy 18.424484 -180.463035) (xy 18.455963 -180.541665) (xy 18.479824 -180.622932) (xy 18.495853 -180.706098)
			(xy 18.503904 -180.790412) (xy 18.504408 -180.83276) (xy 18.503904 -180.875108) (xy 18.495853 -180.959422)
			(xy 18.479824 -181.042588) (xy 18.455963 -181.123855) (xy 18.424484 -181.202485) (xy 18.385673 -181.277766)
			(xy 18.339883 -181.349018) (xy 18.287527 -181.415594) (xy 18.229079 -181.476892) (xy 18.165069 -181.532357)
			(xy 18.096077 -181.581486) (xy 18.022727 -181.623835) (xy 17.945684 -181.659019) (xy 17.865645 -181.686721)
			(xy 17.783336 -181.706689) (xy 17.699501 -181.718742) (xy 17.6149 -181.722773) (xy 17.530299 -181.718742)
			(xy 17.446464 -181.706689) (xy 17.364155 -181.686721) (xy 17.284116 -181.659019) (xy 17.207073 -181.623835)
			(xy 17.133723 -181.581486) (xy 17.064731 -181.532357) (xy 17.000721 -181.476892) (xy 16.942273 -181.415594)
			(xy 16.889917 -181.349018) (xy 16.844127 -181.277766) (xy 16.805316 -181.202485) (xy 16.773837 -181.123855)
			(xy 16.749976 -181.042588) (xy 16.733947 -180.959422) (xy 16.725896 -180.875108) (xy 6.019983 -180.875108)
			(xy 6.006918 -180.92103) (xy 5.977222 -180.997685) (xy 5.940579 -181.071273) (xy 5.897303 -181.141166)
			(xy 5.847763 -181.206768) (xy 5.792381 -181.26752) (xy 5.73163 -181.322902) (xy 5.666028 -181.372442)
			(xy 5.596135 -181.415718) (xy 5.522547 -181.452361) (xy 5.445892 -181.482057) (xy 5.366823 -181.504554)
			(xy 5.286017 -181.519659) (xy 5.204161 -181.527244) (xy 5.163058 -181.527704) (xy 5.121003 -181.527203)
			(xy 5.037268 -181.519274) (xy 4.954655 -181.503473) (xy 4.873905 -181.479939) (xy 4.795737 -181.448885)
			(xy 4.720852 -181.410587) (xy 4.649919 -181.365388) (xy 4.583572 -181.313692) (xy 4.522403 -181.255961)
			(xy 4.466961 -181.192711) (xy 4.441952 -181.158896) (xy 4.436453 -181.151913) (xy 4.42176 -181.141933)
			(xy 4.40454 -181.137579) (xy 4.386869 -181.139376) (xy 4.378706 -181.142894) (xy 4.359138 -181.152247)
			(xy 4.319242 -181.169274) (xy 4.29895 -181.17693) (xy 4.287815 -181.181728) (xy 4.271367 -181.199491)
			(xy 4.267454 -181.210966) (xy 4.256033 -181.250737) (xy 4.226771 -181.328142) (xy 4.190445 -181.402495)
			(xy 4.14737 -181.473152) (xy 4.097918 -181.539502) (xy 4.042516 -181.600971) (xy 3.981644 -181.657028)
			(xy 3.915828 -181.707189) (xy 3.845637 -181.751019) (xy 3.771678 -181.78814) (xy 3.694591 -181.81823)
			(xy 3.615042 -181.84103) (xy 3.533719 -181.856341) (xy 3.451326 -181.864033) (xy 3.40995 -181.864508)
			(xy 3.368848 -181.864033) (xy 3.286993 -181.856448) (xy 3.206188 -181.841343) (xy 3.127121 -181.818847)
			(xy 3.050467 -181.789151) (xy 2.97688 -181.752509) (xy 2.906988 -181.709234) (xy 2.841387 -181.659694)
			(xy 2.780637 -181.604313) (xy 2.725256 -181.543563) (xy 2.675716 -181.477962) (xy 2.632441 -181.40807)
			(xy 2.595799 -181.334483) (xy 2.566103 -181.257829) (xy 2.543607 -181.178762) (xy 2.528502 -181.097957)
			(xy 2.520917 -181.016102) (xy 2.520442 -180.975) (xy 2.520954 -180.933252) (xy 2.52879 -180.850124)
			(xy 2.544375 -180.768095) (xy 2.567571 -180.687886) (xy 2.582418 -180.648864) (xy 2.585213 -180.640906)
			(xy 2.585981 -180.624069) (xy 2.581213 -180.607902) (xy 2.576576 -180.600858) (xy 2.554228 -180.568621)
			(xy 2.514646 -180.500891) (xy 2.481179 -180.42994) (xy 2.454089 -180.356319) (xy 2.433585 -180.280598)
			(xy 2.419827 -180.203367) (xy 2.412921 -180.125224) (xy 2.412492 -180.086) (xy 1.651254 -180.086)
			(xy 1.651254 -180.460904) (xy 1.652778 -180.51145) (xy 1.651254 -180.561996) (xy 1.651254 -183.752998)
			(xy 1.674368 -183.781192) (xy 1.692402 -183.784494) (xy 1.732512 -183.792699) (xy 1.811145 -183.815517)
			(xy 1.887347 -183.845464) (xy 1.960475 -183.882289) (xy 2.029908 -183.92568) (xy 2.09506 -183.975268)
			(xy 2.155378 -184.030634) (xy 2.210352 -184.09131) (xy 2.259517 -184.156782) (xy 2.302455 -184.226496)
			(xy 2.338805 -184.299861) (xy 2.368258 -184.376256) (xy 2.390564 -184.455035) (xy 2.405536 -184.535531)
			(xy 2.413046 -184.617062) (xy 2.413508 -184.658) (xy 2.413045 -184.699128) (xy 2.40545 -184.781031)
			(xy 2.390326 -184.861884) (xy 2.367803 -184.940996) (xy 2.338073 -185.01769) (xy 2.301391 -185.091313)
			(xy 2.258069 -185.161236) (xy 2.208477 -185.22686) (xy 2.153039 -185.287627) (xy 2.092229 -185.343016)
			(xy 2.026565 -185.392556) (xy 1.956609 -185.435823) (xy 1.919986 -185.454544) (xy 1.907032 -185.460894)
			(xy 1.891792 -185.485532) (xy 1.8923 -185.605928) (xy 1.90754 -185.630312) (xy 1.920748 -185.636662)
			(xy 1.957723 -185.655262) (xy 2.028392 -185.698361) (xy 2.094753 -185.747836) (xy 2.156233 -185.803259)
			(xy 2.2123 -185.864152) (xy 2.262471 -185.929989) (xy 2.306311 -186.0002) (xy 2.343442 -186.074179)
			(xy 2.373543 -186.151286) (xy 2.396354 -186.230855) (xy 2.411677 -186.312198) (xy 2.41938 -186.394613)
			(xy 2.419858 -186.436) (xy 2.419393 -186.477254) (xy 2.411756 -186.559409) (xy 2.396541 -186.640503)
			(xy 2.373881 -186.719839) (xy 2.343968 -186.796734) (xy 2.307062 -186.870529) (xy 2.263479 -186.940587)
			(xy 2.213593 -187.006307) (xy 2.157835 -187.067124) (xy 2.096682 -187.122515) (xy 2.030662 -187.172002)
			(xy 1.960342 -187.215162) (xy 1.923542 -187.233814) (xy 1.915239 -187.238377) (xy 1.902507 -187.25239)
			(xy 1.895723 -187.270066) (xy 1.895348 -187.279534) (xy 1.895348 -187.370466) (xy 1.89569 -187.379937)
			(xy 1.902486 -187.397614) (xy 1.915239 -187.411616) (xy 1.923542 -187.416186) (xy 1.960337 -187.434844)
			(xy 2.030645 -187.478016) (xy 2.096654 -187.527513) (xy 2.157796 -187.582909) (xy 2.213547 -187.643728)
			(xy 2.263427 -187.709447) (xy 2.307009 -187.779502) (xy 2.343916 -187.853292) (xy 2.373834 -187.930181)
			(xy 2.396504 -188.009511) (xy 2.411731 -188.090598) (xy 2.419386 -188.172748) (xy 2.419858 -188.214)
			(xy 2.419393 -188.255254) (xy 2.411756 -188.337409) (xy 2.396541 -188.418503) (xy 2.373881 -188.497839)
			(xy 2.343968 -188.574734) (xy 2.307062 -188.648529) (xy 2.263479 -188.718587) (xy 2.213593 -188.784307)
			(xy 2.157835 -188.845124) (xy 2.096682 -188.900515) (xy 2.030662 -188.950002) (xy 1.960342 -188.993162)
			(xy 1.923542 -189.011814) (xy 1.915239 -189.016377) (xy 1.902507 -189.03039) (xy 1.895723 -189.048066)
			(xy 1.895348 -189.057534) (xy 1.895348 -189.148466) (xy 1.89569 -189.157937) (xy 1.902486 -189.175614)
			(xy 1.915239 -189.189616) (xy 1.923542 -189.194186) (xy 1.960337 -189.212844) (xy 2.030645 -189.256016)
			(xy 2.096654 -189.305513) (xy 2.157796 -189.360909) (xy 2.213547 -189.421728) (xy 2.263427 -189.487447)
			(xy 2.307009 -189.557502) (xy 2.343916 -189.631292) (xy 2.373834 -189.708181) (xy 2.396504 -189.787511)
			(xy 2.411731 -189.868598) (xy 2.419386 -189.950748) (xy 2.419858 -189.992) (xy 2.419398 -190.033141)
			(xy 2.411802 -190.115072) (xy 2.39667 -190.195951) (xy 2.374133 -190.275087) (xy 2.344383 -190.351802)
			(xy 2.307674 -190.425442) (xy 2.264321 -190.495377) (xy 2.214693 -190.561008) (xy 2.159216 -190.621775)
			(xy 2.098363 -190.677158) (xy 2.032654 -190.726683) (xy 1.962653 -190.769928) (xy 1.888956 -190.806522)
			(xy 1.812194 -190.836152) (xy 1.733023 -190.858566) (xy 1.692656 -190.866522) (xy 1.674368 -190.869824)
			(xy 1.665122 -190.881) (xy 2.366518 -190.881) (xy 2.366989 -190.839706) (xy 2.374647 -190.757472)
			(xy 2.389894 -190.676303) (xy 2.412599 -190.596896) (xy 2.442568 -190.519937) (xy 2.479541 -190.446086)
			(xy 2.523201 -190.375981) (xy 2.573171 -190.310224) (xy 2.629021 -190.249383) (xy 2.690271 -190.19398)
			(xy 2.756392 -190.144494) (xy 2.826816 -190.10135) (xy 2.900936 -190.06492) (xy 2.978114 -190.035517)
			(xy 3.017774 -190.024004) (xy 3.029712 -190.020702) (xy 3.047746 -190.004192) (xy 3.084576 -189.903862)
			(xy 3.081782 -189.879478) (xy 3.074924 -189.869318) (xy 3.050861 -189.832611) (xy 3.009289 -189.755302)
			(xy 2.975535 -189.674274) (xy 2.949928 -189.590315) (xy 2.932717 -189.504241) (xy 2.92407 -189.416891)
			(xy 2.92354 -189.373002) (xy 2.92405 -189.330058) (xy 2.932314 -189.244568) (xy 2.948781 -189.160273)
			(xy 2.973298 -189.077957) (xy 3.005635 -188.998389) (xy 3.045493 -188.922309) (xy 3.092499 -188.850425)
			(xy 3.146216 -188.783408) (xy 3.206143 -188.721881) (xy 3.271722 -188.666418) (xy 3.342343 -188.617535)
			(xy 3.417347 -188.575687) (xy 3.496036 -188.541265) (xy 3.536696 -188.527436) (xy 3.545746 -188.52407)
			(xy 3.560638 -188.51181) (xy 3.565652 -188.50356) (xy 3.58013 -188.47689) (xy 3.584341 -188.468254)
			(xy 3.586699 -188.449203) (xy 3.584702 -188.439806) (xy 3.575409 -188.402897) (xy 3.562427 -188.327895)
			(xy 3.555903 -188.252058) (xy 3.555492 -188.214) (xy 3.55592 -188.17467) (xy 3.562861 -188.096317)
			(xy 3.576689 -188.018882) (xy 3.597296 -187.942969) (xy 3.624521 -187.86917) (xy 3.658152 -187.798062)
			(xy 3.677666 -187.763912) (xy 3.682041 -187.75581) (xy 3.685182 -187.737679) (xy 3.68167 -187.719616)
			(xy 3.677158 -187.711588) (xy 3.656058 -187.676474) (xy 3.619659 -187.603076) (xy 3.590163 -187.526643)
			(xy 3.567821 -187.447822) (xy 3.552821 -187.36728) (xy 3.545291 -187.285699) (xy 3.544824 -187.244736)
			(xy 3.545278 -187.203999) (xy 3.552732 -187.122866) (xy 3.567582 -187.042756) (xy 3.589702 -186.964341)
			(xy 3.618907 -186.888281) (xy 3.636518 -186.851544) (xy 3.640984 -186.841099) (xy 3.641235 -186.818409)
			(xy 3.637026 -186.807856) (xy 3.619425 -186.768464) (xy 3.591066 -186.686974) (xy 3.570741 -186.603118)
			(xy 3.558644 -186.517687) (xy 3.556254 -186.474608) (xy 3.556 -186.464194) (xy 3.547364 -186.44616)
			(xy 3.478276 -186.383676) (xy 3.459226 -186.377072) (xy 3.448812 -186.37758) (xy 3.39725 -186.379104)
			(xy 3.354902 -186.3786) (xy 3.270588 -186.370549) (xy 3.187422 -186.35452) (xy 3.106155 -186.330659)
			(xy 3.027525 -186.29918) (xy 2.952244 -186.260369) (xy 2.880992 -186.214579) (xy 2.814416 -186.162223)
			(xy 2.753118 -186.103775) (xy 2.697653 -186.039765) (xy 2.648524 -185.970773) (xy 2.606175 -185.897423)
			(xy 2.570991 -185.82038) (xy 2.543289 -185.740341) (xy 2.523321 -185.658032) (xy 2.511268 -185.574197)
			(xy 2.507238 -185.489596) (xy 2.511268 -185.404995) (xy 2.523321 -185.32116) (xy 2.543289 -185.238851)
			(xy 2.570991 -185.158812) (xy 2.606175 -185.081769) (xy 2.648524 -185.008419) (xy 2.697653 -184.939427)
			(xy 2.753118 -184.875417) (xy 2.814416 -184.816969) (xy 2.880992 -184.764613) (xy 2.952244 -184.718823)
			(xy 3.027525 -184.680012) (xy 3.106155 -184.648533) (xy 3.187422 -184.624672) (xy 3.270588 -184.608643)
			(xy 3.354902 -184.600592) (xy 3.39725 -184.600088) (xy 3.439719 -184.600576) (xy 3.52427 -184.60866)
			(xy 3.607666 -184.624767) (xy 3.689147 -184.648751) (xy 3.76797 -184.680394) (xy 3.843418 -184.719406)
			(xy 3.914803 -184.765434) (xy 3.981475 -184.818057) (xy 4.042826 -184.876796) (xy 4.098299 -184.941116)
			(xy 4.147387 -185.010432) (xy 4.171789 -185.05298) (xy 14.731097 -185.05298) (xy 14.733731 -184.96917)
			(xy 14.74424 -184.885981) (xy 14.762532 -184.80415) (xy 14.788443 -184.724403) (xy 14.821744 -184.647449)
			(xy 14.86214 -184.57397) (xy 14.909271 -184.504618) (xy 14.962719 -184.44001) (xy 15.02201 -184.380719)
			(xy 15.086618 -184.327271) (xy 15.15597 -184.28014) (xy 15.229449 -184.239744) (xy 15.306403 -184.206443)
			(xy 15.38615 -184.180532) (xy 15.467981 -184.16224) (xy 15.55117 -184.151731) (xy 15.63498 -184.149097)
			(xy 15.718665 -184.154362) (xy 15.801483 -184.167479) (xy 15.8827 -184.188332) (xy 15.961593 -184.216736)
			(xy 16.037463 -184.252438) (xy 16.109637 -184.295121) (xy 16.177474 -184.344407) (xy 16.240371 -184.399859)
			(xy 16.297771 -184.460983) (xy 16.349163 -184.527238) (xy 16.394093 -184.598036) (xy 16.43216 -184.672747)
			(xy 16.463028 -184.750709) (xy 16.486421 -184.831231) (xy 16.502133 -184.913596) (xy 16.510024 -184.997075)
			(xy 16.510508 -185.039) (xy 16.509982 -185.083166) (xy 16.501229 -185.171064) (xy 16.483808 -185.257662)
			(xy 16.457892 -185.342107) (xy 16.423734 -185.423568) (xy 16.381673 -185.501243) (xy 16.357346 -185.53811)
			(xy 16.348456 -185.551064) (xy 16.348456 -185.582306) (xy 16.419068 -185.686192) (xy 16.448024 -185.697622)
			(xy 16.463264 -185.69432) (xy 16.510537 -185.684544) (xy 16.60651 -185.674109) (xy 16.65478 -185.673492)
			(xy 16.70177 -185.6741) (xy 16.795226 -185.684015) (xy 16.887116 -185.703725) (xy 16.976416 -185.733012)
			(xy 17.019524 -185.751724) (xy 17.029684 -185.756296) (xy 17.051528 -185.756042) (xy 17.141698 -185.714132)
			(xy 17.155668 -185.697368) (xy 17.158716 -185.686446) (xy 17.170254 -185.647275) (xy 17.199544 -185.571043)
			(xy 17.235697 -185.497816) (xy 17.278408 -185.42821) (xy 17.327318 -185.362811) (xy 17.382016 -185.302169)
			(xy 17.44204 -185.246796) (xy 17.506887 -185.197156) (xy 17.57601 -185.153667) (xy 17.648827 -185.116696)
			(xy 17.724727 -185.086554) (xy 17.803068 -185.063494) (xy 17.883194 -185.047711) (xy 17.923764 -185.043064)
			(xy 17.935956 -185.042048) (xy 17.95653 -185.028586) (xy 18.009616 -184.935622) (xy 18.010886 -184.911238)
			(xy 18.005806 -184.900062) (xy 17.990371 -184.865266) (xy 17.96481 -184.793556) (xy 17.945467 -184.719926)
			(xy 17.932484 -184.644912) (xy 17.925956 -184.569064) (xy 17.925542 -184.531) (xy 17.925975 -184.490947)
			(xy 17.933186 -184.411166) (xy 17.94754 -184.332356) (xy 17.968921 -184.255155) (xy 17.997157 -184.18019)
			(xy 18.032017 -184.108067) (xy 18.07322 -184.039369) (xy 18.120433 -183.974654) (xy 18.146522 -183.94426)
			(xy 18.152201 -183.937135) (xy 18.15859 -183.920088) (xy 18.158968 -183.910986) (xy 18.158968 -183.881014)
			(xy 18.158573 -183.871913) (xy 18.1522 -183.854863) (xy 18.146522 -183.84774) (xy 18.130628 -183.829356)
			(xy 18.100639 -183.791108) (xy 18.086578 -183.771286) (xy 18.079974 -183.762142) (xy 18.060416 -183.750966)
			(xy 17.960086 -183.74233) (xy 17.939004 -183.750204) (xy 17.930876 -183.758332) (xy 17.899554 -183.789347)
			(xy 17.831781 -183.845716) (xy 17.758763 -183.895102) (xy 17.681216 -183.937021) (xy 17.599903 -183.97106)
			(xy 17.515619 -183.996887) (xy 17.429194 -184.014246) (xy 17.341476 -184.022969) (xy 17.2974 -184.023508)
			(xy 17.255052 -184.023004) (xy 17.170738 -184.014953) (xy 17.087572 -183.998924) (xy 17.006305 -183.975063)
			(xy 16.927675 -183.943584) (xy 16.852394 -183.904773) (xy 16.781142 -183.858983) (xy 16.714566 -183.806627)
			(xy 16.653268 -183.748179) (xy 16.597803 -183.684169) (xy 16.548674 -183.615177) (xy 16.506325 -183.541827)
			(xy 16.471141 -183.464784) (xy 16.443439 -183.384745) (xy 16.423471 -183.302436) (xy 16.411418 -183.218601)
			(xy 16.407388 -183.134) (xy 16.411418 -183.049399) (xy 16.423471 -182.965564) (xy 16.443439 -182.883255)
			(xy 16.471141 -182.803216) (xy 16.506325 -182.726173) (xy 16.548674 -182.652823) (xy 16.597803 -182.583831)
			(xy 16.653268 -182.519821) (xy 16.714566 -182.461373) (xy 16.781142 -182.409017) (xy 16.852394 -182.363227)
			(xy 16.927675 -182.324416) (xy 17.006305 -182.292937) (xy 17.087572 -182.269076) (xy 17.170738 -182.253047)
			(xy 17.255052 -182.244996) (xy 17.2974 -182.244492) (xy 17.340091 -182.245037) (xy 17.425082 -182.253212)
			(xy 17.508897 -182.269497) (xy 17.590766 -182.293741) (xy 17.669933 -182.325721) (xy 17.74567 -182.365143)
			(xy 17.81728 -182.411644) (xy 17.884102 -182.464794) (xy 17.945521 -182.524106) (xy 18.000972 -182.589032)
			(xy 18.025872 -182.623714) (xy 18.032476 -182.632858) (xy 18.052034 -182.644034) (xy 18.152364 -182.65267)
			(xy 18.173446 -182.644796) (xy 18.181574 -182.636668) (xy 18.211717 -182.606735) (xy 18.276832 -182.552171)
			(xy 18.346857 -182.504068) (xy 18.421153 -182.462868) (xy 18.499041 -182.428944) (xy 18.57981 -182.402608)
			(xy 18.662724 -182.384098) (xy 18.704814 -182.37835) (xy 18.719038 -182.376572) (xy 18.741136 -182.359046)
			(xy 18.782284 -182.24754) (xy 18.77695 -182.219854) (xy 18.767298 -182.209186) (xy 18.73994 -182.178512)
			(xy 18.690401 -182.112919) (xy 18.647126 -182.043034) (xy 18.610484 -181.969454) (xy 18.580789 -181.892807)
			(xy 18.558292 -181.813746) (xy 18.543187 -181.732947) (xy 18.535602 -181.651099) (xy 18.535142 -181.61)
			(xy 18.535657 -181.566261) (xy 18.544255 -181.479208) (xy 18.561358 -181.393419) (xy 18.586802 -181.309724)
			(xy 18.620339 -181.228931) (xy 18.661647 -181.151821) (xy 18.710326 -181.079139) (xy 18.765905 -181.011588)
			(xy 18.796508 -180.980334) (xy 18.80362 -180.972968) (xy 18.81124 -180.95468) (xy 18.811748 -180.862732)
			(xy 18.804382 -180.844444) (xy 18.797016 -180.837078) (xy 18.767046 -180.80591) (xy 18.712677 -180.738668)
			(xy 18.665084 -180.66647) (xy 18.624716 -180.589998) (xy 18.591953 -180.509972) (xy 18.567105 -180.427146)
			(xy 18.550404 -180.342301) (xy 18.54201 -180.256236) (xy 18.541492 -180.213) (xy 18.542023 -180.169509)
			(xy 18.550524 -180.082945) (xy 18.567435 -179.997623) (xy 18.592594 -179.91436) (xy 18.625761 -179.833951)
			(xy 18.66662 -179.757163) (xy 18.714779 -179.684731) (xy 18.76978 -179.617346) (xy 18.800064 -179.586128)
			(xy 18.807176 -179.578762) (xy 18.814796 -179.560474) (xy 18.814796 -179.468526) (xy 18.807176 -179.450238)
			(xy 18.800064 -179.442872) (xy 18.769788 -179.411645) (xy 18.714779 -179.344267) (xy 18.666612 -179.271839)
			(xy 18.625749 -179.195053) (xy 18.59258 -179.114644) (xy 18.567421 -179.03138) (xy 18.550514 -178.946057)
			(xy 18.54202 -178.859491) (xy 18.541492 -178.816) (xy 18.541996 -178.773652) (xy 18.550047 -178.689338)
			(xy 18.566076 -178.606172) (xy 18.589937 -178.524905) (xy 18.621416 -178.446275) (xy 18.660227 -178.370994)
			(xy 18.706017 -178.299742) (xy 18.758373 -178.233166) (xy 18.816821 -178.171868) (xy 18.880831 -178.116403)
			(xy 18.949823 -178.067274) (xy 19.023173 -178.024925) (xy 19.100216 -177.989741) (xy 19.180255 -177.962039)
			(xy 19.262564 -177.942071) (xy 19.346399 -177.930018) (xy 19.431 -177.925988) (xy 19.515601 -177.930018)
			(xy 19.599436 -177.942071) (xy 19.681745 -177.962039) (xy 19.761784 -177.989741) (xy 19.838827 -178.024925)
			(xy 19.912177 -178.067274) (xy 19.981169 -178.116403) (xy 20.045179 -178.171868) (xy 20.103627 -178.233166)
			(xy 20.155983 -178.299742) (xy 20.201773 -178.370994) (xy 20.240584 -178.446275) (xy 20.272063 -178.524905)
			(xy 20.295924 -178.606172) (xy 20.311953 -178.689338) (xy 20.320004 -178.773652) (xy 20.320508 -178.816)
			(xy 20.319977 -178.859491) (xy 20.311476 -178.946055) (xy 20.294565 -179.031377) (xy 20.269406 -179.11464)
			(xy 20.236239 -179.195049) (xy 20.19538 -179.271837) (xy 20.147221 -179.344269) (xy 20.09222 -179.411654)
			(xy 20.061936 -179.442872) (xy 20.054824 -179.450238) (xy 20.047204 -179.468526) (xy 20.047204 -179.560474)
			(xy 20.054824 -179.578762) (xy 20.061936 -179.586128) (xy 20.092212 -179.617355) (xy 20.147221 -179.684733)
			(xy 20.160699 -179.705) (xy 29.462988 -179.705) (xy 29.467018 -179.620399) (xy 29.479071 -179.536564)
			(xy 29.499039 -179.454255) (xy 29.526741 -179.374216) (xy 29.561925 -179.297173) (xy 29.604274 -179.223823)
			(xy 29.653403 -179.154831) (xy 29.708868 -179.090821) (xy 29.770166 -179.032373) (xy 29.836742 -178.980017)
			(xy 29.907994 -178.934227) (xy 29.983275 -178.895416) (xy 30.061905 -178.863937) (xy 30.143172 -178.840076)
			(xy 30.226338 -178.824047) (xy 30.310652 -178.815996) (xy 30.353 -178.815492) (xy 30.39713 -178.816069)
			(xy 30.484957 -178.824799) (xy 30.571487 -178.842182) (xy 30.655872 -178.868049) (xy 30.73728 -178.902144)
			(xy 30.814911 -178.944133) (xy 30.888004 -178.993603) (xy 30.955839 -179.050067) (xy 31.017749 -179.112971)
			(xy 31.073125 -179.181697) (xy 31.097728 -179.218336) (xy 31.106041 -179.230105) (xy 31.127931 -179.24882)
			(xy 31.154175 -179.260681) (xy 31.182686 -179.264745) (xy 31.211199 -179.260688) (xy 31.237446 -179.248834)
			(xy 31.259341 -179.230125) (xy 31.275144 -179.206048) (xy 31.279846 -179.192428) (xy 31.293038 -179.150806)
			(xy 31.326492 -179.070149) (xy 31.367687 -178.993158) (xy 31.416228 -178.920573) (xy 31.471647 -178.853094)
			(xy 31.533411 -178.791369) (xy 31.600925 -178.735993) (xy 31.67354 -178.687498) (xy 31.750557 -178.646351)
			(xy 31.831235 -178.612948) (xy 31.914798 -178.587611) (xy 32.000441 -178.570582) (xy 32.08734 -178.562027)
			(xy 32.131 -178.561492) (xy 32.173348 -178.561996) (xy 32.257662 -178.570047) (xy 32.340828 -178.586076)
			(xy 32.422095 -178.609937) (xy 32.500725 -178.641416) (xy 32.576006 -178.680227) (xy 32.647258 -178.726017)
			(xy 32.713834 -178.778373) (xy 32.775132 -178.836821) (xy 32.830597 -178.900831) (xy 32.879726 -178.969823)
			(xy 32.922075 -179.043173) (xy 32.957259 -179.120216) (xy 32.984961 -179.200255) (xy 33.004929 -179.282564)
			(xy 33.016982 -179.366399) (xy 33.021013 -179.451) (xy 33.016982 -179.535601) (xy 33.004929 -179.619436)
			(xy 32.984961 -179.701745) (xy 32.957259 -179.781784) (xy 32.922075 -179.858827) (xy 32.879726 -179.932177)
			(xy 32.830597 -180.001169) (xy 32.775132 -180.065179) (xy 32.713834 -180.123627) (xy 32.647258 -180.175983)
			(xy 32.576006 -180.221773) (xy 32.500725 -180.260584) (xy 32.422095 -180.292063) (xy 32.340828 -180.315924)
			(xy 32.257662 -180.331953) (xy 32.173348 -180.340004) (xy 32.131 -180.340508) (xy 32.08687 -180.339931)
			(xy 31.999043 -180.331201) (xy 31.912513 -180.313818) (xy 31.828128 -180.287951) (xy 31.74672 -180.253856)
			(xy 31.669089 -180.211867) (xy 31.595996 -180.162397) (xy 31.528161 -180.105933) (xy 31.466251 -180.043029)
			(xy 31.410875 -179.974303) (xy 31.386272 -179.937664) (xy 31.377959 -179.925895) (xy 31.356069 -179.90718)
			(xy 31.329825 -179.895319) (xy 31.301314 -179.891255) (xy 31.272801 -179.895312) (xy 31.246554 -179.907166)
			(xy 31.224659 -179.925875) (xy 31.208856 -179.949952) (xy 31.204154 -179.963572) (xy 31.190962 -180.005194)
			(xy 31.157508 -180.085851) (xy 31.116313 -180.162842) (xy 31.067772 -180.235427) (xy 31.012353 -180.302906)
			(xy 30.950589 -180.364631) (xy 30.883075 -180.420007) (xy 30.81046 -180.468502) (xy 30.733443 -180.509649)
			(xy 30.652765 -180.543052) (xy 30.569202 -180.568389) (xy 30.483559 -180.585418) (xy 30.39666 -180.593973)
			(xy 30.353 -180.594508) (xy 30.310652 -180.594004) (xy 30.226338 -180.585953) (xy 30.143172 -180.569924)
			(xy 30.061905 -180.546063) (xy 29.983275 -180.514584) (xy 29.907994 -180.475773) (xy 29.836742 -180.429983)
			(xy 29.770166 -180.377627) (xy 29.708868 -180.319179) (xy 29.653403 -180.255169) (xy 29.604274 -180.186177)
			(xy 29.561925 -180.112827) (xy 29.526741 -180.035784) (xy 29.499039 -179.955745) (xy 29.479071 -179.873436)
			(xy 29.467018 -179.789601) (xy 29.462988 -179.705) (xy 20.160699 -179.705) (xy 20.195388 -179.757161)
			(xy 20.236251 -179.833947) (xy 20.26942 -179.914356) (xy 20.294579 -179.99762) (xy 20.311486 -180.082943)
			(xy 20.31998 -180.169509) (xy 20.320508 -180.213) (xy 20.319979 -180.256738) (xy 20.311381 -180.343791)
			(xy 20.294279 -180.429579) (xy 20.268837 -180.513274) (xy 20.235301 -180.594066) (xy 20.193996 -180.671176)
			(xy 20.14532 -180.743859) (xy 20.089743 -180.811411) (xy 20.059142 -180.842666) (xy 20.05203 -180.850032)
			(xy 20.04441 -180.86832) (xy 20.043902 -180.960268) (xy 20.051268 -180.978556) (xy 20.058634 -180.985922)
			(xy 20.088595 -181.017098) (xy 20.142966 -181.084339) (xy 20.190561 -181.156534) (xy 20.230931 -181.233005)
			(xy 20.263695 -181.31303) (xy 20.288544 -181.395855) (xy 20.305245 -181.4807) (xy 20.31364 -181.566764)
			(xy 20.314158 -181.61) (xy 20.313686 -181.6529) (xy 20.305551 -181.737) (xy 29.462988 -181.737) (xy 29.467018 -181.652399)
			(xy 29.479071 -181.568564) (xy 29.499039 -181.486255) (xy 29.526741 -181.406216) (xy 29.561925 -181.329173)
			(xy 29.604274 -181.255823) (xy 29.653403 -181.186831) (xy 29.708868 -181.122821) (xy 29.770166 -181.064373)
			(xy 29.836742 -181.012017) (xy 29.907994 -180.966227) (xy 29.983275 -180.927416) (xy 30.061905 -180.895937)
			(xy 30.143172 -180.872076) (xy 30.226338 -180.856047) (xy 30.310652 -180.847996) (xy 30.353 -180.847492)
			(xy 30.398149 -180.848059) (xy 30.487982 -180.857204) (xy 30.576427 -180.875402) (xy 30.662574 -180.902463)
			(xy 30.745538 -180.938111) (xy 30.824464 -180.981979) (xy 30.898541 -181.033614) (xy 30.933136 -181.06263)
			(xy 30.94101 -181.069488) (xy 30.960568 -181.075584) (xy 31.053532 -181.067202) (xy 31.07182 -181.05755)
			(xy 31.07817 -181.049676) (xy 31.106275 -181.01587) (xy 31.168129 -180.95339) (xy 31.235845 -180.897315)
			(xy 31.308762 -180.848193) (xy 31.386168 -180.806503) (xy 31.467309 -180.772651) (xy 31.551393 -180.746968)
			(xy 31.6376 -180.729704) (xy 31.72509 -180.721027) (xy 31.76905 -180.720492) (xy 31.811398 -180.720996)
			(xy 31.895712 -180.729047) (xy 31.978878 -180.745076) (xy 32.060145 -180.768937) (xy 32.138775 -180.800416)
			(xy 32.214056 -180.839227) (xy 32.285308 -180.885017) (xy 32.351884 -180.937373) (xy 32.413182 -180.995821)
			(xy 32.431835 -181.017348) (xy 34.455096 -181.017348) (xy 34.455096 -180.932652) (xy 34.463147 -180.848338)
			(xy 34.479176 -180.765172) (xy 34.503037 -180.683905) (xy 34.534516 -180.605275) (xy 34.573327 -180.529994)
			(xy 34.619117 -180.458742) (xy 34.671473 -180.392166) (xy 34.729921 -180.330868) (xy 34.793931 -180.275403)
			(xy 34.862923 -180.226274) (xy 34.936273 -180.183925) (xy 35.013316 -180.148741) (xy 35.093355 -180.121039)
			(xy 35.175664 -180.101071) (xy 35.259499 -180.089018) (xy 35.3441 -180.084988) (xy 35.428701 -180.089018)
			(xy 35.512536 -180.101071) (xy 35.594845 -180.121039) (xy 35.674884 -180.148741) (xy 35.751927 -180.183925)
			(xy 35.825277 -180.226274) (xy 35.894269 -180.275403) (xy 35.958279 -180.330868) (xy 36.016727 -180.392166)
			(xy 36.069083 -180.458742) (xy 36.114873 -180.529994) (xy 36.153684 -180.605275) (xy 36.185163 -180.683905)
			(xy 36.209024 -180.765172) (xy 36.225053 -180.848338) (xy 36.233104 -180.932652) (xy 36.233608 -180.975)
			(xy 36.233104 -181.017348) (xy 36.225053 -181.101662) (xy 36.209024 -181.184828) (xy 36.185163 -181.266095)
			(xy 36.153684 -181.344725) (xy 36.114873 -181.420006) (xy 36.069083 -181.491258) (xy 36.016727 -181.557834)
			(xy 35.958279 -181.619132) (xy 35.894269 -181.674597) (xy 35.825277 -181.723726) (xy 35.751927 -181.766075)
			(xy 35.674884 -181.801259) (xy 35.594845 -181.828961) (xy 35.512536 -181.848929) (xy 35.428701 -181.860982)
			(xy 35.3441 -181.865013) (xy 35.259499 -181.860982) (xy 35.175664 -181.848929) (xy 35.093355 -181.828961)
			(xy 35.013316 -181.801259) (xy 34.936273 -181.766075) (xy 34.862923 -181.723726) (xy 34.793931 -181.674597)
			(xy 34.729921 -181.619132) (xy 34.671473 -181.557834) (xy 34.619117 -181.491258) (xy 34.573327 -181.420006)
			(xy 34.534516 -181.344725) (xy 34.503037 -181.266095) (xy 34.479176 -181.184828) (xy 34.463147 -181.101662)
			(xy 34.455096 -181.017348) (xy 32.431835 -181.017348) (xy 32.468647 -181.059831) (xy 32.517776 -181.128823)
			(xy 32.560125 -181.202173) (xy 32.595309 -181.279216) (xy 32.623011 -181.359255) (xy 32.642979 -181.441564)
			(xy 32.655032 -181.525399) (xy 32.659063 -181.61) (xy 32.655032 -181.694601) (xy 32.642979 -181.778436)
			(xy 32.623011 -181.860745) (xy 32.595309 -181.940784) (xy 32.560125 -182.017827) (xy 32.517776 -182.091177)
			(xy 32.468647 -182.160169) (xy 32.413182 -182.224179) (xy 32.351884 -182.282627) (xy 32.285308 -182.334983)
			(xy 32.214056 -182.380773) (xy 32.138775 -182.419584) (xy 32.060145 -182.451063) (xy 31.978878 -182.474924)
			(xy 31.895712 -182.490953) (xy 31.811398 -182.499004) (xy 31.76905 -182.499508) (xy 31.7239 -182.498971)
			(xy 31.634066 -182.489821) (xy 31.54562 -182.471618) (xy 31.459473 -182.444552) (xy 31.37651 -182.408899)
			(xy 31.297585 -182.365028) (xy 31.223508 -182.313388) (xy 31.188914 -182.28437) (xy 31.18104 -182.277512)
			(xy 31.161482 -182.271416) (xy 31.068518 -182.279798) (xy 31.05023 -182.28945) (xy 31.04388 -182.297324)
			(xy 31.015804 -182.331154) (xy 30.953945 -182.393634) (xy 30.886225 -182.449707) (xy 30.813305 -182.498827)
			(xy 30.735895 -182.540514) (xy 30.654751 -182.574363) (xy 30.570663 -182.600043) (xy 30.484453 -182.617303)
			(xy 30.396961 -182.625975) (xy 30.353 -182.626508) (xy 30.310652 -182.626004) (xy 30.226338 -182.617953)
			(xy 30.143172 -182.601924) (xy 30.061905 -182.578063) (xy 29.983275 -182.546584) (xy 29.907994 -182.507773)
			(xy 29.836742 -182.461983) (xy 29.770166 -182.409627) (xy 29.708868 -182.351179) (xy 29.653403 -182.287169)
			(xy 29.604274 -182.218177) (xy 29.561925 -182.144827) (xy 29.526741 -182.067784) (xy 29.499039 -181.987745)
			(xy 29.479071 -181.905436) (xy 29.467018 -181.821601) (xy 29.462988 -181.737) (xy 20.305551 -181.737)
			(xy 20.305425 -181.738302) (xy 20.288978 -181.822512) (xy 20.264499 -181.904746) (xy 20.232215 -181.984241)
			(xy 20.192427 -182.060259) (xy 20.145504 -182.132091) (xy 20.091882 -182.199072) (xy 20.032059 -182.260578)
			(xy 19.966592 -182.316038) (xy 19.896089 -182.364937) (xy 19.821205 -182.406819) (xy 19.742636 -182.441296)
			(xy 19.661113 -182.468048) (xy 19.577392 -182.486825) (xy 19.534886 -182.49265) (xy 19.520662 -182.494428)
			(xy 19.498564 -182.511954) (xy 19.457416 -182.62346) (xy 19.46275 -182.651146) (xy 19.472402 -182.661814)
			(xy 19.49976 -182.692488) (xy 19.549299 -182.758081) (xy 19.592574 -182.827966) (xy 19.618486 -182.88)
			(xy 42.157142 -182.88) (xy 42.157631 -182.838269) (xy 42.165432 -182.755172) (xy 42.180984 -182.673172)
			(xy 42.20415 -182.59299) (xy 42.234727 -182.515331) (xy 42.272445 -182.440878) (xy 42.316973 -182.370287)
			(xy 42.367919 -182.304178) (xy 42.424835 -182.243133) (xy 42.487219 -182.187689) (xy 42.554524 -182.138333)
			(xy 42.626157 -182.095501) (xy 42.663618 -182.077106) (xy 42.672376 -182.072409) (xy 42.685714 -182.057699)
			(xy 42.692497 -182.039039) (xy 42.692574 -182.0291) (xy 42.691812 -181.991) (xy 42.692574 -181.9529)
			(xy 42.692501 -181.942956) (xy 42.685745 -181.924279) (xy 42.672388 -181.909579) (xy 42.663618 -181.904894)
			(xy 42.626172 -181.886473) (xy 42.554552 -181.843628) (xy 42.487259 -181.794265) (xy 42.424884 -181.738817)
			(xy 42.367975 -181.677772) (xy 42.317033 -181.611666) (xy 42.272505 -181.54108) (xy 42.234782 -181.466634)
			(xy 42.204196 -181.388984) (xy 42.181016 -181.30881) (xy 42.165445 -181.226818) (xy 42.157621 -181.143729)
			(xy 42.157142 -181.102) (xy 42.157625 -181.060613) (xy 42.16533 -180.978199) (xy 42.180654 -180.896857)
			(xy 42.203465 -180.817288) (xy 42.233566 -180.740182) (xy 42.270697 -180.666204) (xy 42.314536 -180.595993)
			(xy 42.364706 -180.530157) (xy 42.420773 -180.469263) (xy 42.482251 -180.413839) (xy 42.548611 -180.364363)
			(xy 42.619278 -180.321263) (xy 42.656252 -180.302662) (xy 42.666525 -180.297114) (xy 42.680925 -180.278764)
			(xy 42.685744 -180.255942) (xy 42.68343 -180.244496) (xy 42.677794 -180.221605) (xy 42.668645 -180.175353)
			(xy 42.665142 -180.15204) (xy 42.662733 -180.140134) (xy 42.648677 -180.12037) (xy 42.638218 -180.114194)
			(xy 42.602418 -180.095157) (xy 42.534069 -180.051525) (xy 42.469975 -180.001853) (xy 42.410668 -179.946553)
			(xy 42.356642 -179.886084) (xy 42.308343 -179.820949) (xy 42.266174 -179.751687) (xy 42.230485 -179.678875)
			(xy 42.201571 -179.603117) (xy 42.179673 -179.525041) (xy 42.164972 -179.445296) (xy 42.157591 -179.364544)
			(xy 42.157142 -179.324) (xy 42.157667 -179.282899) (xy 42.165251 -179.201048) (xy 42.180355 -179.120245)
			(xy 42.20285 -179.041181) (xy 42.232544 -178.964529) (xy 42.269183 -178.890944) (xy 42.312455 -178.821054)
			(xy 42.361992 -178.755454) (xy 42.417369 -178.694705) (xy 42.478116 -178.639324) (xy 42.543713 -178.589784)
			(xy 42.613601 -178.546507) (xy 42.687184 -178.509864) (xy 42.763833 -178.480166) (xy 42.842896 -178.457666)
			(xy 42.923698 -178.442558) (xy 43.005549 -178.434969) (xy 43.04665 -178.434492) (xy 43.089045 -178.434967)
			(xy 43.173448 -178.443039) (xy 43.256701 -178.459107) (xy 43.338047 -178.483024) (xy 43.416748 -178.514573)
			(xy 43.49209 -178.553467) (xy 43.563389 -178.599355) (xy 43.629999 -178.651818) (xy 43.691313 -178.710382)
			(xy 43.746777 -178.774514) (xy 43.795886 -178.843634) (xy 43.838196 -178.917112) (xy 43.873322 -178.994283)
			(xy 43.900945 -179.074447) (xy 43.920815 -179.156875) (xy 43.927268 -179.198778) (xy 43.929663 -179.210688)
			(xy 43.943729 -179.230451) (xy 43.954192 -179.236624) (xy 43.990002 -179.255643) (xy 44.058351 -179.299277)
			(xy 44.122445 -179.348951) (xy 44.181751 -179.404253) (xy 44.235777 -179.464723) (xy 44.284075 -179.52986)
			(xy 44.326243 -179.599123) (xy 44.361932 -179.671937) (xy 44.390844 -179.747697) (xy 44.412741 -179.825774)
			(xy 44.42744 -179.90552) (xy 44.43482 -179.986273) (xy 44.435268 -180.026818) (xy 44.434794 -180.068205)
			(xy 44.427088 -180.150619) (xy 44.411763 -180.231962) (xy 44.38895 -180.31153) (xy 44.358848 -180.388636)
			(xy 44.321717 -180.462614) (xy 44.277876 -180.532825) (xy 44.227706 -180.598661) (xy 44.171639 -180.659554)
			(xy 44.110159 -180.714979) (xy 44.0438 -180.764455) (xy 43.973132 -180.807555) (xy 43.936158 -180.826156)
			(xy 43.925915 -180.831746) (xy 43.911525 -180.850081) (xy 43.906687 -180.872881) (xy 43.90898 -180.884322)
			(xy 43.917608 -180.919954) (xy 43.929683 -180.992273) (xy 43.935762 -181.06534) (xy 43.936158 -181.102)
			(xy 43.935396 -181.1401) (xy 43.935486 -181.150042) (xy 43.942237 -181.168717) (xy 43.955587 -181.183418)
			(xy 43.964352 -181.188106) (xy 44.001813 -181.206504) (xy 44.073445 -181.24934) (xy 44.140749 -181.298698)
			(xy 44.203135 -181.354143) (xy 44.260053 -181.415188) (xy 44.311003 -181.481296) (xy 44.355538 -181.551885)
			(xy 44.393264 -181.626336) (xy 44.423851 -181.703992) (xy 44.44703 -181.784173) (xy 44.462596 -181.866172)
			(xy 44.470414 -181.949268) (xy 44.470414 -182.032732) (xy 44.462596 -182.115828) (xy 44.44703 -182.197827)
			(xy 44.423851 -182.278008) (xy 44.393264 -182.355664) (xy 44.355538 -182.430115) (xy 44.311003 -182.500704)
			(xy 44.260053 -182.566812) (xy 44.203135 -182.627857) (xy 44.140749 -182.683302) (xy 44.073445 -182.73266)
			(xy 44.001813 -182.775496) (xy 43.964352 -182.793894) (xy 43.955588 -182.798581) (xy 43.942253 -182.813296)
			(xy 43.935472 -182.83196) (xy 43.935396 -182.8419) (xy 43.936158 -182.88) (xy 45.205142 -182.88)
			(xy 45.205588 -182.838747) (xy 45.213246 -182.756597) (xy 45.228476 -182.675509) (xy 45.251149 -182.596179)
			(xy 45.281069 -182.519289) (xy 45.317979 -182.4455) (xy 45.361562 -182.375444) (xy 45.411445 -182.309725)
			(xy 45.467198 -182.248907) (xy 45.528342 -182.193512) (xy 45.594353 -182.144015) (xy 45.664662 -182.100843)
			(xy 45.701458 -182.082186) (xy 45.709761 -182.077616) (xy 45.722514 -182.063614) (xy 45.72931 -182.045937)
			(xy 45.729652 -182.036466) (xy 45.729652 -181.945534) (xy 45.729277 -181.936066) (xy 45.722493 -181.91839)
			(xy 45.709761 -181.904377) (xy 45.701458 -181.899814) (xy 45.664649 -181.881179) (xy 45.594327 -181.838019)
			(xy 45.528306 -181.788531) (xy 45.467153 -181.733139) (xy 45.411394 -181.672321) (xy 45.361508 -181.606599)
			(xy 45.317926 -181.536539) (xy 45.28102 -181.462743) (xy 45.25111 -181.385845) (xy 45.228451 -181.306507)
			(xy 45.213239 -181.225411) (xy 45.205605 -181.143255) (xy 45.205142 -181.102) (xy 45.205646 -181.059652)
			(xy 45.213697 -180.975338) (xy 45.229726 -180.892172) (xy 45.253587 -180.810905) (xy 45.285066 -180.732275)
			(xy 45.323877 -180.656994) (xy 45.369667 -180.585742) (xy 45.422023 -180.519166) (xy 45.480471 -180.457868)
			(xy 45.544481 -180.402403) (xy 45.613473 -180.353274) (xy 45.686823 -180.310925) (xy 45.763866 -180.275741)
			(xy 45.843905 -180.248039) (xy 45.926214 -180.228071) (xy 46.010049 -180.216018) (xy 46.09465 -180.211988)
			(xy 46.179251 -180.216018) (xy 46.263086 -180.228071) (xy 46.345395 -180.248039) (xy 46.425434 -180.275741)
			(xy 46.502477 -180.310925) (xy 46.575827 -180.353274) (xy 46.644819 -180.402403) (xy 46.708829 -180.457868)
			(xy 46.767277 -180.519166) (xy 46.819633 -180.585742) (xy 46.865423 -180.656994) (xy 46.904234 -180.732275)
			(xy 46.935713 -180.810905) (xy 46.959574 -180.892172) (xy 46.975603 -180.975338) (xy 46.983654 -181.059652)
			(xy 46.984158 -181.102) (xy 46.983712 -181.143253) (xy 46.976054 -181.225403) (xy 46.960824 -181.306491)
			(xy 46.938151 -181.385821) (xy 46.908231 -181.462711) (xy 46.871321 -181.5365) (xy 46.827738 -181.606556)
			(xy 46.777855 -181.672275) (xy 46.722102 -181.733093) (xy 46.660958 -181.788488) (xy 46.594947 -181.837985)
			(xy 46.524638 -181.881157) (xy 46.487842 -181.899814) (xy 46.479539 -181.904384) (xy 46.466786 -181.918386)
			(xy 46.45999 -181.936063) (xy 46.459648 -181.945534) (xy 46.459648 -182.036466) (xy 46.460023 -182.045934)
			(xy 46.466807 -182.06361) (xy 46.479539 -182.077623) (xy 46.487842 -182.082186) (xy 46.524651 -182.100821)
			(xy 46.594973 -182.143981) (xy 46.660994 -182.193469) (xy 46.722147 -182.248861) (xy 46.777906 -182.309679)
			(xy 46.827792 -182.375401) (xy 46.871374 -182.445461) (xy 46.90828 -182.519257) (xy 46.93819 -182.596155)
			(xy 46.960849 -182.675493) (xy 46.976061 -182.756589) (xy 46.983695 -182.838745) (xy 46.984158 -182.88)
			(xy 46.983654 -182.922348) (xy 46.975603 -183.006662) (xy 46.959574 -183.089828) (xy 46.935713 -183.171095)
			(xy 46.904234 -183.249725) (xy 46.865423 -183.325006) (xy 46.819633 -183.396258) (xy 46.767277 -183.462834)
			(xy 46.708829 -183.524132) (xy 46.644819 -183.579597) (xy 46.575827 -183.628726) (xy 46.502477 -183.671075)
			(xy 46.425434 -183.706259) (xy 46.345395 -183.733961) (xy 46.263086 -183.753929) (xy 46.179251 -183.765982)
			(xy 46.09465 -183.770013) (xy 46.010049 -183.765982) (xy 45.926214 -183.753929) (xy 45.843905 -183.733961)
			(xy 45.763866 -183.706259) (xy 45.686823 -183.671075) (xy 45.613473 -183.628726) (xy 45.544481 -183.579597)
			(xy 45.480471 -183.524132) (xy 45.422023 -183.462834) (xy 45.369667 -183.396258) (xy 45.323877 -183.325006)
			(xy 45.285066 -183.249725) (xy 45.253587 -183.171095) (xy 45.229726 -183.089828) (xy 45.213697 -183.006662)
			(xy 45.205646 -182.922348) (xy 45.205142 -182.88) (xy 43.936158 -182.88) (xy 43.935654 -182.922348)
			(xy 43.927603 -183.006662) (xy 43.911574 -183.089828) (xy 43.887713 -183.171095) (xy 43.856234 -183.249725)
			(xy 43.817423 -183.325006) (xy 43.771633 -183.396258) (xy 43.719277 -183.462834) (xy 43.660829 -183.524132)
			(xy 43.596819 -183.579597) (xy 43.527827 -183.628726) (xy 43.454477 -183.671075) (xy 43.377434 -183.706259)
			(xy 43.297395 -183.733961) (xy 43.215086 -183.753929) (xy 43.131251 -183.765982) (xy 43.04665 -183.770013)
			(xy 42.962049 -183.765982) (xy 42.878214 -183.753929) (xy 42.795905 -183.733961) (xy 42.715866 -183.706259)
			(xy 42.638823 -183.671075) (xy 42.565473 -183.628726) (xy 42.496481 -183.579597) (xy 42.432471 -183.524132)
			(xy 42.374023 -183.462834) (xy 42.321667 -183.396258) (xy 42.275877 -183.325006) (xy 42.237066 -183.249725)
			(xy 42.205587 -183.171095) (xy 42.181726 -183.089828) (xy 42.165697 -183.006662) (xy 42.157646 -182.922348)
			(xy 42.157142 -182.88) (xy 19.618486 -182.88) (xy 19.629216 -182.901546) (xy 19.658911 -182.978193)
			(xy 19.681408 -183.057254) (xy 19.696513 -183.138053) (xy 19.704098 -183.219901) (xy 19.704558 -183.261)
			(xy 19.704125 -183.301053) (xy 19.696914 -183.380834) (xy 19.68256 -183.459644) (xy 19.661179 -183.536845)
			(xy 19.632943 -183.61181) (xy 19.598083 -183.683933) (xy 19.55688 -183.752631) (xy 19.509667 -183.817346)
			(xy 19.483578 -183.84774) (xy 19.477899 -183.854865) (xy 19.47151 -183.871912) (xy 19.471132 -183.881014)
			(xy 19.471132 -183.910986) (xy 19.471527 -183.920087) (xy 19.4779 -183.937137) (xy 19.483578 -183.94426)
			(xy 19.509656 -183.974664) (xy 19.556875 -184.039374) (xy 19.598084 -184.108068) (xy 19.632947 -184.180189)
			(xy 19.661183 -184.255154) (xy 19.682563 -184.332355) (xy 19.683247 -184.336112) (xy 31.639506 -184.336112)
			(xy 31.639506 -184.251416) (xy 31.647557 -184.167102) (xy 31.663586 -184.083936) (xy 31.687447 -184.002669)
			(xy 31.718926 -183.924039) (xy 31.757737 -183.848758) (xy 31.803527 -183.777506) (xy 31.855883 -183.71093)
			(xy 31.914331 -183.649632) (xy 31.978341 -183.594167) (xy 32.047333 -183.545038) (xy 32.120683 -183.502689)
			(xy 32.197726 -183.467505) (xy 32.277765 -183.439803) (xy 32.360074 -183.419835) (xy 32.443909 -183.407782)
			(xy 32.52851 -183.403752) (xy 32.613111 -183.407782) (xy 32.696946 -183.419835) (xy 32.779255 -183.439803)
			(xy 32.859294 -183.467505) (xy 32.936337 -183.502689) (xy 33.009687 -183.545038) (xy 33.078679 -183.594167)
			(xy 33.142689 -183.649632) (xy 33.201137 -183.71093) (xy 33.253493 -183.777506) (xy 33.299283 -183.848758)
			(xy 33.338094 -183.924039) (xy 33.369573 -184.002669) (xy 33.393434 -184.083936) (xy 33.409463 -184.167102)
			(xy 33.417514 -184.251416) (xy 33.418018 -184.293764) (xy 33.417514 -184.336112) (xy 33.409463 -184.420426)
			(xy 33.393434 -184.503592) (xy 33.369573 -184.584859) (xy 33.338094 -184.663489) (xy 33.299283 -184.73877)
			(xy 33.253493 -184.810022) (xy 33.201137 -184.876598) (xy 33.142689 -184.937896) (xy 33.078679 -184.993361)
			(xy 33.009687 -185.04249) (xy 32.942384 -185.081348) (xy 33.781996 -185.081348) (xy 33.781996 -184.996652)
			(xy 33.790047 -184.912338) (xy 33.806076 -184.829172) (xy 33.829937 -184.747905) (xy 33.861416 -184.669275)
			(xy 33.900227 -184.593994) (xy 33.946017 -184.522742) (xy 33.998373 -184.456166) (xy 34.056821 -184.394868)
			(xy 34.120831 -184.339403) (xy 34.189823 -184.290274) (xy 34.263173 -184.247925) (xy 34.340216 -184.212741)
			(xy 34.420255 -184.185039) (xy 34.502564 -184.165071) (xy 34.586399 -184.153018) (xy 34.671 -184.148988)
			(xy 34.755601 -184.153018) (xy 34.839436 -184.165071) (xy 34.921745 -184.185039) (xy 35.001784 -184.212741)
			(xy 35.078827 -184.247925) (xy 35.152177 -184.290274) (xy 35.221169 -184.339403) (xy 35.285179 -184.394868)
			(xy 35.343627 -184.456166) (xy 35.395983 -184.522742) (xy 35.441773 -184.593994) (xy 35.480584 -184.669275)
			(xy 35.512063 -184.747905) (xy 35.535924 -184.829172) (xy 35.551953 -184.912338) (xy 35.560004 -184.996652)
			(xy 35.560508 -185.039) (xy 35.560004 -185.081348) (xy 35.551953 -185.165662) (xy 35.543726 -185.208348)
			(xy 36.194996 -185.208348) (xy 36.194996 -185.123652) (xy 36.203047 -185.039338) (xy 36.219076 -184.956172)
			(xy 36.242937 -184.874905) (xy 36.274416 -184.796275) (xy 36.313227 -184.720994) (xy 36.359017 -184.649742)
			(xy 36.411373 -184.583166) (xy 36.469821 -184.521868) (xy 36.533831 -184.466403) (xy 36.602823 -184.417274)
			(xy 36.676173 -184.374925) (xy 36.753216 -184.339741) (xy 36.833255 -184.312039) (xy 36.915564 -184.292071)
			(xy 36.999399 -184.280018) (xy 37.084 -184.275988) (xy 37.168601 -184.280018) (xy 37.252436 -184.292071)
			(xy 37.334745 -184.312039) (xy 37.414784 -184.339741) (xy 37.491827 -184.374925) (xy 37.565177 -184.417274)
			(xy 37.634169 -184.466403) (xy 37.698179 -184.521868) (xy 37.756627 -184.583166) (xy 37.808983 -184.649742)
			(xy 37.854773 -184.720994) (xy 37.893584 -184.796275) (xy 37.925063 -184.874905) (xy 37.948924 -184.956172)
			(xy 37.964953 -185.039338) (xy 37.973004 -185.123652) (xy 37.973508 -185.166) (xy 37.973004 -185.208348)
			(xy 37.964953 -185.292662) (xy 37.948924 -185.375828) (xy 37.925063 -185.457095) (xy 37.893584 -185.535725)
			(xy 37.854773 -185.611006) (xy 37.808983 -185.682258) (xy 37.756627 -185.748834) (xy 37.698179 -185.810132)
			(xy 37.634169 -185.865597) (xy 37.565177 -185.914726) (xy 37.491827 -185.957075) (xy 37.414784 -185.992259)
			(xy 37.334745 -186.019961) (xy 37.252436 -186.039929) (xy 37.168601 -186.051982) (xy 37.084 -186.056013)
			(xy 36.999399 -186.051982) (xy 36.915564 -186.039929) (xy 36.833255 -186.019961) (xy 36.753216 -185.992259)
			(xy 36.676173 -185.957075) (xy 36.602823 -185.914726) (xy 36.533831 -185.865597) (xy 36.469821 -185.810132)
			(xy 36.411373 -185.748834) (xy 36.359017 -185.682258) (xy 36.313227 -185.611006) (xy 36.274416 -185.535725)
			(xy 36.242937 -185.457095) (xy 36.219076 -185.375828) (xy 36.203047 -185.292662) (xy 36.194996 -185.208348)
			(xy 35.543726 -185.208348) (xy 35.535924 -185.248828) (xy 35.512063 -185.330095) (xy 35.480584 -185.408725)
			(xy 35.441773 -185.484006) (xy 35.395983 -185.555258) (xy 35.343627 -185.621834) (xy 35.285179 -185.683132)
			(xy 35.221169 -185.738597) (xy 35.152177 -185.787726) (xy 35.078827 -185.830075) (xy 35.001784 -185.865259)
			(xy 34.921745 -185.892961) (xy 34.839436 -185.912929) (xy 34.755601 -185.924982) (xy 34.671 -185.929013)
			(xy 34.586399 -185.924982) (xy 34.502564 -185.912929) (xy 34.420255 -185.892961) (xy 34.340216 -185.865259)
			(xy 34.263173 -185.830075) (xy 34.189823 -185.787726) (xy 34.120831 -185.738597) (xy 34.056821 -185.683132)
			(xy 33.998373 -185.621834) (xy 33.946017 -185.555258) (xy 33.900227 -185.484006) (xy 33.861416 -185.408725)
			(xy 33.829937 -185.330095) (xy 33.806076 -185.248828) (xy 33.790047 -185.165662) (xy 33.781996 -185.081348)
			(xy 32.942384 -185.081348) (xy 32.936337 -185.084839) (xy 32.859294 -185.120023) (xy 32.779255 -185.147725)
			(xy 32.696946 -185.167693) (xy 32.613111 -185.179746) (xy 32.52851 -185.183777) (xy 32.443909 -185.179746)
			(xy 32.360074 -185.167693) (xy 32.277765 -185.147725) (xy 32.197726 -185.120023) (xy 32.120683 -185.084839)
			(xy 32.047333 -185.04249) (xy 31.978341 -184.993361) (xy 31.914331 -184.937896) (xy 31.855883 -184.876598)
			(xy 31.803527 -184.810022) (xy 31.757737 -184.73877) (xy 31.718926 -184.663489) (xy 31.687447 -184.584859)
			(xy 31.663586 -184.503592) (xy 31.647557 -184.420426) (xy 31.639506 -184.336112) (xy 19.683247 -184.336112)
			(xy 19.696913 -184.411165) (xy 19.704118 -184.490947) (xy 19.704558 -184.531) (xy 19.704042 -184.574491)
			(xy 19.69554 -184.661057) (xy 19.678628 -184.746379) (xy 19.653467 -184.829643) (xy 19.620298 -184.910052)
			(xy 19.579437 -184.98684) (xy 19.531275 -185.059271) (xy 19.476272 -185.126655) (xy 19.445986 -185.157872)
			(xy 19.438874 -185.165238) (xy 19.431254 -185.183526) (xy 19.431254 -185.275474) (xy 19.438874 -185.293762)
			(xy 19.445986 -185.301128) (xy 19.476253 -185.332364) (xy 19.531264 -185.39974) (xy 19.579432 -185.472166)
			(xy 19.620297 -185.54895) (xy 19.653468 -185.629358) (xy 19.678628 -185.712621) (xy 19.695536 -185.797944)
			(xy 19.70403 -185.884509) (xy 19.704558 -185.928) (xy 19.704033 -185.969101) (xy 19.696449 -186.050952)
			(xy 19.681345 -186.131755) (xy 19.65885 -186.210819) (xy 19.629156 -186.287471) (xy 19.592517 -186.361056)
			(xy 19.549245 -186.430946) (xy 19.499708 -186.496546) (xy 19.444331 -186.557295) (xy 19.383584 -186.612676)
			(xy 19.317987 -186.662216) (xy 19.248099 -186.705493) (xy 19.174516 -186.742136) (xy 19.097867 -186.771834)
			(xy 19.018804 -186.794334) (xy 18.938002 -186.809442) (xy 18.856151 -186.817031) (xy 18.81505 -186.817508)
			(xy 18.775951 -186.817075) (xy 18.698056 -186.810188) (xy 18.621065 -186.796497) (xy 18.545571 -186.776107)
			(xy 18.472155 -186.749176) (xy 18.43659 -186.732926) (xy 18.426203 -186.728691) (xy 18.403797 -186.728691)
			(xy 18.39341 -186.732926) (xy 18.357857 -186.749206) (xy 18.284445 -186.776156) (xy 18.208949 -186.79655)
			(xy 18.131952 -186.81023) (xy 18.054051 -186.81709) (xy 18.01495 -186.817508) (xy 17.96796 -186.816889)
			(xy 17.874505 -186.806978) (xy 17.782615 -186.78727) (xy 17.693314 -186.757987) (xy 17.650206 -186.739276)
			(xy 17.640046 -186.734704) (xy 17.618202 -186.734958) (xy 17.528032 -186.776868) (xy 17.514062 -186.793632)
			(xy 17.511014 -186.804554) (xy 17.499397 -186.844061) (xy 17.469791 -186.920909) (xy 17.433209 -186.994692)
			(xy 17.389966 -187.064779) (xy 17.34043 -187.13057) (xy 17.285027 -187.191501) (xy 17.22423 -187.247052)
			(xy 17.15856 -187.296747) (xy 17.088578 -187.34016) (xy 17.014883 -187.37692) (xy 16.938107 -187.406713)
			(xy 16.858906 -187.429283) (xy 16.777959 -187.444437) (xy 16.695957 -187.452046) (xy 16.65478 -187.452508)
			(xy 16.613677 -187.452052) (xy 16.531822 -187.444466) (xy 16.451017 -187.429359) (xy 16.37195 -187.406861)
			(xy 16.295296 -187.377163) (xy 16.221709 -187.34052) (xy 16.151817 -187.297243) (xy 16.086216 -187.247702)
			(xy 16.025466 -187.19232) (xy 15.970085 -187.131569) (xy 15.920545 -187.065967) (xy 15.87727 -186.996074)
			(xy 15.840629 -186.922486) (xy 15.810933 -186.845831) (xy 15.788437 -186.766764) (xy 15.773332 -186.685958)
			(xy 15.765747 -186.604103) (xy 15.765272 -186.563) (xy 15.765801 -186.518834) (xy 15.774554 -186.430936)
			(xy 15.791975 -186.344339) (xy 15.817891 -186.259894) (xy 15.852047 -186.178433) (xy 15.894108 -186.100757)
			(xy 15.918434 -186.06389) (xy 15.927324 -186.050936) (xy 15.927324 -186.019694) (xy 15.856712 -185.915808)
			(xy 15.827756 -185.904378) (xy 15.812516 -185.90768) (xy 15.765243 -185.917459) (xy 15.66927 -185.927892)
			(xy 15.621 -185.928508) (xy 15.579075 -185.928024) (xy 15.495596 -185.920133) (xy 15.413231 -185.904421)
			(xy 15.332709 -185.881028) (xy 15.254747 -185.85016) (xy 15.180036 -185.812093) (xy 15.109238 -185.767163)
			(xy 15.042983 -185.715771) (xy 14.981859 -185.658371) (xy 14.926407 -185.595474) (xy 14.877121 -185.527637)
			(xy 14.834438 -185.455463) (xy 14.798736 -185.379593) (xy 14.770332 -185.3007) (xy 14.749479 -185.219483)
			(xy 14.736362 -185.136665) (xy 14.731097 -185.05298) (xy 4.171789 -185.05298) (xy 4.189644 -185.084111)
			(xy 4.224685 -185.161484) (xy 4.25219 -185.241844) (xy 4.271909 -185.324461) (xy 4.283662 -185.408581)
			(xy 4.285996 -185.450988) (xy 4.28625 -185.461402) (xy 4.294886 -185.479436) (xy 4.363974 -185.54192)
			(xy 4.383024 -185.548524) (xy 4.393438 -185.548016) (xy 4.445 -185.546492) (xy 4.486102 -185.546967)
			(xy 4.567957 -185.554552) (xy 4.648762 -185.569657) (xy 4.727829 -185.592153) (xy 4.804483 -185.621849)
			(xy 4.87807 -185.658491) (xy 4.947962 -185.701766) (xy 5.013563 -185.751306) (xy 5.074313 -185.806687)
			(xy 5.129694 -185.867437) (xy 5.179234 -185.933038) (xy 5.222509 -186.00293) (xy 5.259151 -186.076517)
			(xy 5.267221 -186.097348) (xy 5.841996 -186.097348) (xy 5.841996 -186.012652) (xy 5.850047 -185.928338)
			(xy 5.866076 -185.845172) (xy 5.889937 -185.763905) (xy 5.921416 -185.685275) (xy 5.960227 -185.609994)
			(xy 6.006017 -185.538742) (xy 6.058373 -185.472166) (xy 6.116821 -185.410868) (xy 6.180831 -185.355403)
			(xy 6.249823 -185.306274) (xy 6.323173 -185.263925) (xy 6.400216 -185.228741) (xy 6.480255 -185.201039)
			(xy 6.562564 -185.181071) (xy 6.646399 -185.169018) (xy 6.731 -185.164988) (xy 6.815601 -185.169018)
			(xy 6.899436 -185.181071) (xy 6.981745 -185.201039) (xy 7.061784 -185.228741) (xy 7.138827 -185.263925)
			(xy 7.212177 -185.306274) (xy 7.281169 -185.355403) (xy 7.345179 -185.410868) (xy 7.403627 -185.472166)
			(xy 7.455983 -185.538742) (xy 7.501773 -185.609994) (xy 7.540584 -185.685275) (xy 7.572063 -185.763905)
			(xy 7.595924 -185.845172) (xy 7.611953 -185.928338) (xy 7.620004 -186.012652) (xy 7.620508 -186.055)
			(xy 7.620004 -186.097348) (xy 7.611953 -186.181662) (xy 7.595924 -186.264828) (xy 7.572063 -186.346095)
			(xy 7.540584 -186.424725) (xy 7.501773 -186.500006) (xy 7.455983 -186.571258) (xy 7.403627 -186.637834)
			(xy 7.345179 -186.699132) (xy 7.281169 -186.754597) (xy 7.212177 -186.803726) (xy 7.138827 -186.846075)
			(xy 7.061784 -186.881259) (xy 6.981745 -186.908961) (xy 6.899436 -186.928929) (xy 6.815601 -186.940982)
			(xy 6.731 -186.945013) (xy 6.646399 -186.940982) (xy 6.562564 -186.928929) (xy 6.480255 -186.908961)
			(xy 6.400216 -186.881259) (xy 6.323173 -186.846075) (xy 6.249823 -186.803726) (xy 6.180831 -186.754597)
			(xy 6.116821 -186.699132) (xy 6.058373 -186.637834) (xy 6.006017 -186.571258) (xy 5.960227 -186.500006)
			(xy 5.921416 -186.424725) (xy 5.889937 -186.346095) (xy 5.866076 -186.264828) (xy 5.850047 -186.181662)
			(xy 5.841996 -186.097348) (xy 5.267221 -186.097348) (xy 5.288847 -186.153171) (xy 5.311343 -186.232238)
			(xy 5.326448 -186.313043) (xy 5.334033 -186.394898) (xy 5.334508 -186.436) (xy 5.334065 -186.476738)
			(xy 5.326608 -186.557871) (xy 5.311755 -186.637981) (xy 5.289633 -186.716395) (xy 5.260425 -186.792455)
			(xy 5.242814 -186.829192) (xy 5.238386 -186.839651) (xy 5.238109 -186.862328) (xy 5.242306 -186.87288)
			(xy 5.25797 -186.907911) (xy 5.283936 -186.980127) (xy 5.30359 -187.05431) (xy 5.316784 -187.12991)
			(xy 5.323421 -187.206365) (xy 5.32384 -187.244736) (xy 5.323392 -187.284066) (xy 5.316456 -187.362418)
			(xy 5.302633 -187.439854) (xy 5.282029 -187.515767) (xy 5.254807 -187.589565) (xy 5.221179 -187.660673)
			(xy 5.201666 -187.694824) (xy 5.19734 -187.702949) (xy 5.194179 -187.721066) (xy 5.197671 -187.739121)
			(xy 5.202174 -187.747148) (xy 5.223272 -187.782263) (xy 5.259672 -187.85566) (xy 5.289168 -187.932093)
			(xy 5.31151 -188.010915) (xy 5.326511 -188.091457) (xy 5.330008 -188.129348) (xy 13.998444 -188.129348)
			(xy 13.998444 -188.044652) (xy 14.006495 -187.960338) (xy 14.022524 -187.877172) (xy 14.046385 -187.795905)
			(xy 14.077864 -187.717275) (xy 14.116675 -187.641994) (xy 14.162465 -187.570742) (xy 14.214821 -187.504166)
			(xy 14.273269 -187.442868) (xy 14.337279 -187.387403) (xy 14.406271 -187.338274) (xy 14.479621 -187.295925)
			(xy 14.556664 -187.260741) (xy 14.636703 -187.233039) (xy 14.719012 -187.213071) (xy 14.802847 -187.201018)
			(xy 14.887448 -187.196988) (xy 14.972049 -187.201018) (xy 15.055884 -187.213071) (xy 15.138193 -187.233039)
			(xy 15.218232 -187.260741) (xy 15.295275 -187.295925) (xy 15.368625 -187.338274) (xy 15.437617 -187.387403)
			(xy 15.501627 -187.442868) (xy 15.560075 -187.504166) (xy 15.612431 -187.570742) (xy 15.658221 -187.641994)
			(xy 15.697032 -187.717275) (xy 15.728511 -187.795905) (xy 15.752372 -187.877172) (xy 15.768401 -187.960338)
			(xy 15.776452 -188.044652) (xy 15.776956 -188.087) (xy 15.776452 -188.129348) (xy 15.768401 -188.213662)
			(xy 15.752372 -188.296828) (xy 15.728511 -188.378095) (xy 15.697032 -188.456725) (xy 15.658221 -188.532006)
			(xy 15.612431 -188.603258) (xy 15.560075 -188.669834) (xy 15.501627 -188.731132) (xy 15.437617 -188.786597)
			(xy 15.368625 -188.835726) (xy 15.295275 -188.878075) (xy 15.218232 -188.913259) (xy 15.138193 -188.940961)
			(xy 15.055884 -188.960929) (xy 14.972049 -188.972982) (xy 14.887448 -188.977013) (xy 14.802847 -188.972982)
			(xy 14.719012 -188.960929) (xy 14.636703 -188.940961) (xy 14.556664 -188.913259) (xy 14.479621 -188.878075)
			(xy 14.406271 -188.835726) (xy 14.337279 -188.786597) (xy 14.273269 -188.731132) (xy 14.214821 -188.669834)
			(xy 14.162465 -188.603258) (xy 14.116675 -188.532006) (xy 14.077864 -188.456725) (xy 14.046385 -188.378095)
			(xy 14.022524 -188.296828) (xy 14.006495 -188.213662) (xy 13.998444 -188.129348) (xy 5.330008 -188.129348)
			(xy 5.334041 -188.173037) (xy 5.334508 -188.214) (xy 5.334036 -188.255252) (xy 5.326381 -188.337402)
			(xy 5.311154 -188.418489) (xy 5.288484 -188.497819) (xy 5.258566 -188.574708) (xy 5.221659 -188.648498)
			(xy 5.178077 -188.718553) (xy 5.128197 -188.784272) (xy 5.072446 -188.845091) (xy 5.011304 -188.900487)
			(xy 4.945295 -188.949984) (xy 4.874987 -188.993156) (xy 4.838192 -189.011814) (xy 4.829899 -189.016402)
			(xy 4.817141 -189.030393) (xy 4.810341 -189.048065) (xy 4.809998 -189.057534) (xy 4.809998 -189.148466)
			(xy 4.8104 -189.157931) (xy 4.817176 -189.175603) (xy 4.829896 -189.189618) (xy 4.838192 -189.194186)
			(xy 4.874992 -189.212838) (xy 4.945312 -189.255998) (xy 5.011332 -189.305485) (xy 5.072485 -189.360876)
			(xy 5.128243 -189.421693) (xy 5.178129 -189.487413) (xy 5.221712 -189.557471) (xy 5.258618 -189.631266)
			(xy 5.288531 -189.708161) (xy 5.311191 -189.787497) (xy 5.326406 -189.868591) (xy 5.334043 -189.950746)
			(xy 5.334508 -189.992) (xy 5.334033 -190.033102) (xy 5.326448 -190.114957) (xy 5.311343 -190.195762)
			(xy 5.297049 -190.246) (xy 17.124938 -190.246) (xy 17.128968 -190.161399) (xy 17.141021 -190.077564)
			(xy 17.160989 -189.995255) (xy 17.188691 -189.915216) (xy 17.223875 -189.838173) (xy 17.266224 -189.764823)
			(xy 17.315353 -189.695831) (xy 17.370818 -189.631821) (xy 17.432116 -189.573373) (xy 17.498692 -189.521017)
			(xy 17.569944 -189.475227) (xy 17.645225 -189.436416) (xy 17.723855 -189.404937) (xy 17.805122 -189.381076)
			(xy 17.888288 -189.365047) (xy 17.972602 -189.356996) (xy 18.01495 -189.356492) (xy 18.05745 -189.35699)
			(xy 18.142063 -189.365094) (xy 18.225517 -189.381235) (xy 18.307051 -189.405263) (xy 18.38592 -189.436961)
			(xy 18.42389 -189.45606) (xy 18.434558 -189.461648) (xy 18.457418 -189.462156) (xy 18.551398 -189.419992)
			(xy 18.56613 -189.402466) (xy 18.569178 -189.391036) (xy 18.581273 -189.345964) (xy 18.613629 -189.258427)
			(xy 18.654975 -189.17476) (xy 18.679414 -189.135004) (xy 18.68429 -189.126607) (xy 18.687871 -189.107537)
			(xy 18.684094 -189.088505) (xy 18.67916 -189.08014) (xy 18.656249 -189.044018) (xy 18.616668 -188.968182)
			(xy 18.584555 -188.888894) (xy 18.56021 -188.806888) (xy 18.543857 -188.722921) (xy 18.535647 -188.637772)
			(xy 18.535142 -188.595) (xy 18.535561 -188.553963) (xy 18.543122 -188.472238) (xy 18.558179 -188.391558)
			(xy 18.580604 -188.312607) (xy 18.610207 -188.236058) (xy 18.646737 -188.162561) (xy 18.689881 -188.092743)
			(xy 18.739274 -188.027195) (xy 18.794495 -187.966476) (xy 18.855074 -187.911103) (xy 18.920497 -187.861546)
			(xy 18.990207 -187.818226) (xy 19.063612 -187.781512) (xy 19.140086 -187.751717) (xy 19.21898 -187.729093)
			(xy 19.299623 -187.713833) (xy 19.381328 -187.706067) (xy 19.422364 -187.705492) (xy 19.432932 -187.704952)
			(xy 19.45227 -187.69642) (xy 19.466506 -187.680799) (xy 19.47037 -187.670948) (xy 19.484391 -187.630634)
			(xy 19.519146 -187.552669) (xy 19.561211 -187.478393) (xy 19.610198 -187.408489) (xy 19.665657 -187.343599)
			(xy 19.727077 -187.284321) (xy 19.793894 -187.231199) (xy 19.865493 -187.184723) (xy 19.941215 -187.145321)
			(xy 20.020363 -187.113353) (xy 20.10221 -187.089116) (xy 20.186003 -187.072831) (xy 20.27097 -187.064648)
			(xy 20.31365 -187.064142) (xy 20.354752 -187.064617) (xy 20.436607 -187.072202) (xy 20.517412 -187.087307)
			(xy 20.596479 -187.109803) (xy 20.673133 -187.139499) (xy 20.74672 -187.176141) (xy 20.816612 -187.219416)
			(xy 20.882213 -187.268956) (xy 20.942963 -187.324337) (xy 20.998344 -187.385087) (xy 21.047884 -187.450688)
			(xy 21.091159 -187.52058) (xy 21.127801 -187.594167) (xy 21.157497 -187.670821) (xy 21.179993 -187.749888)
			(xy 21.195098 -187.830693) (xy 21.202683 -187.912548) (xy 21.203158 -187.95365) (xy 21.202692 -187.994686)
			(xy 21.195135 -188.07641) (xy 21.180082 -188.157089) (xy 21.157661 -188.23604) (xy 21.128062 -188.312588)
			(xy 21.091536 -188.386085) (xy 21.048395 -188.455904) (xy 20.999006 -188.521451) (xy 20.943788 -188.58217)
			(xy 20.883211 -188.637544) (xy 20.81779 -188.687102) (xy 20.748082 -188.730422) (xy 20.67468 -188.767137)
			(xy 20.598208 -188.796933) (xy 20.519315 -188.819557) (xy 20.438675 -188.834817) (xy 20.356971 -188.842583)
			(xy 20.315936 -188.843158) (xy 20.305372 -188.843731) (xy 20.286041 -188.852253) (xy 20.2718 -188.867858)
			(xy 20.26793 -188.877702) (xy 20.256273 -188.911498) (xy 20.22825 -188.977274) (xy 20.195032 -189.040586)
			(xy 20.176236 -189.070996) (xy 20.171364 -189.079394) (xy 20.167787 -189.098463) (xy 20.17156 -189.117494)
			(xy 20.17649 -189.12586) (xy 20.199406 -189.161979) (xy 20.234907 -189.23) (xy 22.732492 -189.23)
			(xy 22.732947 -189.188612) (xy 22.740652 -189.106197) (xy 22.755977 -189.024852) (xy 22.77879 -188.945283)
			(xy 22.808893 -188.868175) (xy 22.846026 -188.794197) (xy 22.889868 -188.723986) (xy 22.940041 -188.658149)
			(xy 22.996111 -188.597257) (xy 23.057593 -188.541834) (xy 23.123956 -188.492359) (xy 23.194626 -188.449261)
			(xy 23.231602 -188.430662) (xy 23.24481 -188.424312) (xy 23.26005 -188.399928) (xy 23.260558 -188.279532)
			(xy 23.245318 -188.254894) (xy 23.232364 -188.248544) (xy 23.195722 -188.22986) (xy 23.125766 -188.186589)
			(xy 23.060103 -188.137045) (xy 22.999293 -188.081652) (xy 22.943857 -188.020881) (xy 22.894267 -187.955253)
			(xy 22.850946 -187.885328) (xy 22.814266 -187.811702) (xy 22.784538 -187.735004) (xy 22.762018 -187.65589)
			(xy 22.746896 -187.575035) (xy 22.739303 -187.493129) (xy 22.738842 -187.452) (xy 22.739325 -187.410872)
			(xy 22.746911 -187.328967) (xy 22.762027 -187.248112) (xy 22.784543 -187.168998) (xy 22.814268 -187.092301)
			(xy 22.850948 -187.018676) (xy 22.894269 -186.948753) (xy 22.943861 -186.883128) (xy 22.9993 -186.822362)
			(xy 23.060113 -186.766974) (xy 23.125781 -186.717439) (xy 23.195741 -186.674177) (xy 23.232364 -186.655456)
			(xy 23.245318 -186.649106) (xy 23.260558 -186.624468) (xy 23.26005 -186.504072) (xy 23.24481 -186.479688)
			(xy 23.231602 -186.473338) (xy 23.194612 -186.454763) (xy 23.123929 -186.411677) (xy 23.057555 -186.362211)
			(xy 22.996064 -186.306792) (xy 22.939987 -186.245899) (xy 22.889811 -186.18006) (xy 22.84597 -186.109844)
			(xy 22.808841 -186.035858) (xy 22.778748 -185.958742) (xy 22.755949 -185.879164) (xy 22.740643 -185.797812)
			(xy 22.732961 -185.71539) (xy 22.732492 -185.674) (xy 22.732996 -185.631652) (xy 22.741047 -185.547338)
			(xy 22.757076 -185.464172) (xy 22.780937 -185.382905) (xy 22.812416 -185.304275) (xy 22.851227 -185.228994)
			(xy 22.897017 -185.157742) (xy 22.949373 -185.091166) (xy 23.007821 -185.029868) (xy 23.071831 -184.974403)
			(xy 23.140823 -184.925274) (xy 23.214173 -184.882925) (xy 23.291216 -184.847741) (xy 23.371255 -184.820039)
			(xy 23.453564 -184.800071) (xy 23.537399 -184.788018) (xy 23.622 -184.783988) (xy 23.706601 -184.788018)
			(xy 23.790436 -184.800071) (xy 23.872745 -184.820039) (xy 23.952784 -184.847741) (xy 24.029827 -184.882925)
			(xy 24.103177 -184.925274) (xy 24.172169 -184.974403) (xy 24.236179 -185.029868) (xy 24.294627 -185.091166)
			(xy 24.346983 -185.157742) (xy 24.392773 -185.228994) (xy 24.431584 -185.304275) (xy 24.463063 -185.382905)
			(xy 24.486924 -185.464172) (xy 24.502953 -185.547338) (xy 24.511004 -185.631652) (xy 24.511508 -185.674)
			(xy 24.511052 -185.715129) (xy 24.503466 -185.797036) (xy 24.48835 -185.877892) (xy 24.465832 -185.957007)
			(xy 24.436105 -186.033705) (xy 24.399423 -186.107331) (xy 24.356099 -186.177255) (xy 24.306504 -186.24288)
			(xy 24.251062 -186.303645) (xy 24.190245 -186.359031) (xy 24.124574 -186.408565) (xy 24.05461 -186.451824)
			(xy 24.017986 -186.470544) (xy 24.005032 -186.476894) (xy 23.989792 -186.501532) (xy 23.9903 -186.621928)
			(xy 24.00554 -186.646312) (xy 24.018748 -186.652662) (xy 24.055724 -186.671259) (xy 24.126394 -186.714354)
			(xy 24.192755 -186.763826) (xy 24.254234 -186.819249) (xy 24.3103 -186.880142) (xy 24.360467 -186.94598)
			(xy 24.404302 -187.016193) (xy 24.441426 -187.090173) (xy 24.471518 -187.167283) (xy 24.494318 -187.246854)
			(xy 24.509628 -187.328198) (xy 24.517316 -187.410614) (xy 24.517316 -187.493386) (xy 24.509628 -187.575802)
			(xy 24.494318 -187.657146) (xy 24.471518 -187.736717) (xy 24.441426 -187.813827) (xy 24.404302 -187.887807)
			(xy 24.360467 -187.95802) (xy 24.3103 -188.023858) (xy 24.254234 -188.084751) (xy 24.192755 -188.140174)
			(xy 24.126394 -188.189646) (xy 24.055724 -188.232741) (xy 24.018748 -188.251338) (xy 24.00554 -188.257688)
			(xy 23.9903 -188.282072) (xy 23.990051 -188.341) (xy 28.283705 -188.341) (xy 28.287478 -188.259151)
			(xy 28.298765 -188.177996) (xy 28.31747 -188.098224) (xy 28.343434 -188.020511) (xy 28.376438 -187.945516)
			(xy 28.416201 -187.873875) (xy 28.462386 -187.806196) (xy 28.488132 -187.774326) (xy 28.493358 -187.767577)
			(xy 28.499302 -187.751585) (xy 28.499627 -187.734527) (xy 28.497276 -187.72632) (xy 28.483511 -187.68191)
			(xy 28.464191 -187.59096) (xy 28.454462 -187.49849) (xy 28.453842 -187.452) (xy 28.454288 -187.410747)
			(xy 28.461946 -187.328597) (xy 28.477176 -187.247509) (xy 28.499849 -187.168179) (xy 28.529769 -187.091289)
			(xy 28.566679 -187.0175) (xy 28.610262 -186.947444) (xy 28.660145 -186.881725) (xy 28.715898 -186.820907)
			(xy 28.777042 -186.765512) (xy 28.843053 -186.716015) (xy 28.913362 -186.672843) (xy 28.950158 -186.654186)
			(xy 28.958461 -186.649616) (xy 28.971214 -186.635614) (xy 28.97801 -186.617937) (xy 28.978352 -186.608466)
			(xy 28.978352 -186.517534) (xy 28.977977 -186.508066) (xy 28.971193 -186.49039) (xy 28.958461 -186.476377)
			(xy 28.950158 -186.471814) (xy 28.913349 -186.453179) (xy 28.843027 -186.410019) (xy 28.777006 -186.360531)
			(xy 28.715853 -186.305139) (xy 28.660094 -186.244321) (xy 28.610208 -186.178599) (xy 28.566626 -186.108539)
			(xy 28.52972 -186.034743) (xy 28.49981 -185.957845) (xy 28.477151 -185.878507) (xy 28.461939 -185.797411)
			(xy 28.454305 -185.715255) (xy 28.453842 -185.674) (xy 28.454367 -185.632899) (xy 28.461951 -185.551048)
			(xy 28.477055 -185.470245) (xy 28.49955 -185.391181) (xy 28.529244 -185.314529) (xy 28.565883 -185.240944)
			(xy 28.609155 -185.171054) (xy 28.658692 -185.105454) (xy 28.714069 -185.044705) (xy 28.774816 -184.989324)
			(xy 28.840413 -184.939784) (xy 28.910301 -184.896507) (xy 28.983884 -184.859864) (xy 29.060533 -184.830166)
			(xy 29.139596 -184.807666) (xy 29.220398 -184.792558) (xy 29.302249 -184.784969) (xy 29.34335 -184.784492)
			(xy 29.384302 -184.784926) (xy 29.465858 -184.79246) (xy 29.546377 -184.807459) (xy 29.625176 -184.829796)
			(xy 29.701588 -184.859283) (xy 29.774966 -184.895669) (xy 29.844688 -184.938647) (xy 29.910164 -184.987852)
			(xy 29.970839 -185.042867) (xy 30.0262 -185.103228) (xy 30.075778 -185.168422) (xy 30.119153 -185.237897)
			(xy 30.155958 -185.311066) (xy 30.18588 -185.387308) (xy 30.208667 -185.465978) (xy 30.216856 -185.506106)
			(xy 30.219502 -185.517225) (xy 30.233039 -185.535613) (xy 30.253219 -185.546294) (xy 30.264608 -185.547254)
			(xy 30.307007 -185.549675) (xy 30.391117 -185.561439) (xy 30.473722 -185.581166) (xy 30.554072 -185.608676)
			(xy 30.631434 -185.643718) (xy 30.705104 -185.685973) (xy 30.774413 -185.735057) (xy 30.838727 -185.790522)
			(xy 30.897463 -185.851865) (xy 30.950086 -185.918526) (xy 30.996116 -185.989899) (xy 31.035134 -186.065333)
			(xy 31.066786 -186.144143) (xy 31.090783 -186.225611) (xy 31.106906 -186.308995) (xy 31.11501 -186.393536)
			(xy 31.115508 -186.436) (xy 31.114962 -186.479341) (xy 31.10653 -186.565613) (xy 31.089745 -186.650655)
			(xy 31.064767 -186.733662) (xy 31.031833 -186.813844) (xy 30.991255 -186.890443) (xy 30.943417 -186.96273)
			(xy 30.888775 -187.030022) (xy 30.873199 -187.045784) (xy 31.618678 -187.045784) (xy 31.618678 -186.961088)
			(xy 31.626729 -186.876774) (xy 31.642758 -186.793608) (xy 31.666619 -186.712341) (xy 31.698098 -186.633711)
			(xy 31.736909 -186.55843) (xy 31.782699 -186.487178) (xy 31.835055 -186.420602) (xy 31.893503 -186.359304)
			(xy 31.957513 -186.303839) (xy 32.026505 -186.25471) (xy 32.099855 -186.212361) (xy 32.176898 -186.177177)
			(xy 32.256937 -186.149475) (xy 32.339246 -186.129507) (xy 32.423081 -186.117454) (xy 32.507682 -186.113424)
			(xy 32.592283 -186.117454) (xy 32.676118 -186.129507) (xy 32.758427 -186.149475) (xy 32.838466 -186.177177)
			(xy 32.915509 -186.212361) (xy 32.988859 -186.25471) (xy 33.057851 -186.303839) (xy 33.121861 -186.359304)
			(xy 33.180309 -186.420602) (xy 33.232665 -186.487178) (xy 33.278455 -186.55843) (xy 33.317266 -186.633711)
			(xy 33.348745 -186.712341) (xy 33.372606 -186.793608) (xy 33.388635 -186.876774) (xy 33.396686 -186.961088)
			(xy 33.39719 -187.003436) (xy 33.396686 -187.045784) (xy 33.388635 -187.130098) (xy 33.372606 -187.213264)
			(xy 33.348745 -187.294531) (xy 33.317266 -187.373161) (xy 33.278455 -187.448442) (xy 33.232665 -187.519694)
			(xy 33.180309 -187.58627) (xy 33.121861 -187.647568) (xy 33.057851 -187.703033) (xy 32.988859 -187.752162)
			(xy 32.915509 -187.794511) (xy 32.838466 -187.829695) (xy 32.758427 -187.857397) (xy 32.676118 -187.877365)
			(xy 32.592283 -187.889418) (xy 32.507682 -187.893449) (xy 32.423081 -187.889418) (xy 32.339246 -187.877365)
			(xy 32.256937 -187.857397) (xy 32.176898 -187.829695) (xy 32.099855 -187.794511) (xy 32.026505 -187.752162)
			(xy 31.957513 -187.703033) (xy 31.893503 -187.647568) (xy 31.835055 -187.58627) (xy 31.782699 -187.519694)
			(xy 31.736909 -187.448442) (xy 31.698098 -187.373161) (xy 31.666619 -187.294531) (xy 31.642758 -187.213264)
			(xy 31.626729 -187.130098) (xy 31.618678 -187.045784) (xy 30.873199 -187.045784) (xy 30.827846 -187.091679)
			(xy 30.761208 -187.147116) (xy 30.689493 -187.195807) (xy 30.613381 -187.237292) (xy 30.533595 -187.271175)
			(xy 30.450891 -187.297137) (xy 30.366054 -187.31493) (xy 30.323028 -187.320174) (xy 30.313122 -187.32119)
			(xy 30.296358 -187.33008) (xy 30.238446 -187.396882) (xy 30.232096 -187.414662) (xy 30.23235 -187.424314)
			(xy 30.232858 -187.452) (xy 30.232347 -187.495896) (xy 30.223687 -187.583261) (xy 30.206461 -187.669347)
			(xy 30.180837 -187.753317) (xy 30.147064 -187.834353) (xy 30.10547 -187.911668) (xy 30.056461 -187.984508)
			(xy 30.028896 -188.018674) (xy 30.023672 -188.025424) (xy 30.017725 -188.041415) (xy 30.0174 -188.058473)
			(xy 30.019752 -188.06668) (xy 30.033518 -188.111089) (xy 30.052838 -188.20204) (xy 30.062566 -188.29451)
			(xy 30.063186 -188.341) (xy 30.062569 -188.38749) (xy 30.052846 -188.479961) (xy 30.046392 -188.510348)
			(xy 33.781996 -188.510348) (xy 33.781996 -188.425652) (xy 33.790047 -188.341338) (xy 33.806076 -188.258172)
			(xy 33.829937 -188.176905) (xy 33.861416 -188.098275) (xy 33.900227 -188.022994) (xy 33.946017 -187.951742)
			(xy 33.998373 -187.885166) (xy 34.056821 -187.823868) (xy 34.120831 -187.768403) (xy 34.189823 -187.719274)
			(xy 34.263173 -187.676925) (xy 34.340216 -187.641741) (xy 34.420255 -187.614039) (xy 34.502564 -187.594071)
			(xy 34.586399 -187.582018) (xy 34.671 -187.577988) (xy 34.755601 -187.582018) (xy 34.839436 -187.594071)
			(xy 34.921745 -187.614039) (xy 35.001784 -187.641741) (xy 35.078827 -187.676925) (xy 35.152177 -187.719274)
			(xy 35.221169 -187.768403) (xy 35.285179 -187.823868) (xy 35.343627 -187.885166) (xy 35.395983 -187.951742)
			(xy 35.441773 -188.022994) (xy 35.480584 -188.098275) (xy 35.512063 -188.176905) (xy 35.535924 -188.258172)
			(xy 35.551953 -188.341338) (xy 35.560004 -188.425652) (xy 35.560508 -188.468) (xy 35.560004 -188.510348)
			(xy 35.551953 -188.594662) (xy 35.535924 -188.677828) (xy 35.512063 -188.759095) (xy 35.480584 -188.837725)
			(xy 35.441773 -188.913006) (xy 35.395983 -188.984258) (xy 35.343627 -189.050834) (xy 35.285179 -189.112132)
			(xy 35.221169 -189.167597) (xy 35.152177 -189.216726) (xy 35.078827 -189.259075) (xy 35.001784 -189.294259)
			(xy 34.921745 -189.321961) (xy 34.839436 -189.341929) (xy 34.755601 -189.353982) (xy 34.671 -189.358013)
			(xy 34.586399 -189.353982) (xy 34.502564 -189.341929) (xy 34.420255 -189.321961) (xy 34.340216 -189.294259)
			(xy 34.263173 -189.259075) (xy 34.189823 -189.216726) (xy 34.120831 -189.167597) (xy 34.056821 -189.112132)
			(xy 33.998373 -189.050834) (xy 33.946017 -188.984258) (xy 33.900227 -188.913006) (xy 33.861416 -188.837725)
			(xy 33.829937 -188.759095) (xy 33.806076 -188.677828) (xy 33.790047 -188.594662) (xy 33.781996 -188.510348)
			(xy 30.046392 -188.510348) (xy 30.033528 -188.570913) (xy 30.019752 -188.61532) (xy 30.017464 -188.623533)
			(xy 30.017818 -188.640566) (xy 30.023732 -188.656544) (xy 30.028896 -188.663326) (xy 30.056458 -188.697494)
			(xy 30.105469 -188.770332) (xy 30.147063 -188.847646) (xy 30.180835 -188.928682) (xy 30.206455 -189.012653)
			(xy 30.223676 -189.098739) (xy 30.232328 -189.186104) (xy 30.232858 -189.23) (xy 30.232374 -189.271264)
			(xy 30.224709 -189.353437) (xy 30.209465 -189.434546) (xy 30.198568 -189.474348) (xy 30.19425 -189.489842)
			(xy 30.204918 -189.520322) (xy 30.309566 -189.59449) (xy 30.342078 -189.594236) (xy 30.355286 -189.585092)
			(xy 30.387519 -189.562727) (xy 30.455236 -189.523099) (xy 30.52618 -189.489589) (xy 30.5998 -189.462459)
			(xy 30.675523 -189.441919) (xy 30.752761 -189.428128) (xy 30.830914 -189.421195) (xy 30.870144 -189.420754)
			(xy 30.910757 -189.421203) (xy 30.991647 -189.428593) (xy 31.071526 -189.443325) (xy 31.14973 -189.465276)
			(xy 31.225608 -189.494264) (xy 31.298528 -189.530047) (xy 31.33344 -189.550802) (xy 31.341471 -189.555285)
			(xy 31.359524 -189.558736) (xy 31.377638 -189.55562) (xy 31.385764 -189.55131) (xy 31.420127 -189.531467)
			(xy 31.491718 -189.497232) (xy 31.566073 -189.469505) (xy 31.6426 -189.448506) (xy 31.720692 -189.434401)
			(xy 31.79973 -189.427303) (xy 31.839408 -189.42685) (xy 31.881757 -189.427342) (xy 31.966072 -189.435393)
			(xy 32.04924 -189.451422) (xy 32.130508 -189.475284) (xy 32.209139 -189.506763) (xy 32.284422 -189.545574)
			(xy 32.355675 -189.591366) (xy 32.422252 -189.643723) (xy 32.483551 -189.702171) (xy 32.539017 -189.766182)
			(xy 32.588147 -189.835175) (xy 32.630496 -189.908526) (xy 32.665681 -189.98557) (xy 32.693384 -190.06561)
			(xy 32.713352 -190.147921) (xy 32.725406 -190.231758) (xy 32.729436 -190.31636) (xy 32.725406 -190.400962)
			(xy 32.713352 -190.484799) (xy 32.693384 -190.56711) (xy 32.665681 -190.64715) (xy 32.630496 -190.724194)
			(xy 32.588147 -190.797545) (xy 32.539017 -190.866538) (xy 32.483551 -190.930549) (xy 32.422252 -190.988997)
			(xy 32.355675 -191.041354) (xy 32.284422 -191.087146) (xy 32.209139 -191.125957) (xy 32.130508 -191.157436)
			(xy 32.04924 -191.181298) (xy 31.966072 -191.197327) (xy 31.881757 -191.205378) (xy 31.839408 -191.205866)
			(xy 31.798794 -191.205436) (xy 31.717904 -191.198043) (xy 31.638025 -191.183307) (xy 31.559821 -191.161352)
			(xy 31.483943 -191.132361) (xy 31.411024 -191.096574) (xy 31.376112 -191.075818) (xy 31.368062 -191.071374)
			(xy 31.350021 -191.067908) (xy 31.331913 -191.071008) (xy 31.323788 -191.07531) (xy 31.289437 -191.095174)
			(xy 31.217843 -191.129406) (xy 31.143486 -191.157129) (xy 31.066956 -191.178125) (xy 30.988862 -191.192225)
			(xy 30.909822 -191.199319) (xy 30.870144 -191.19977) (xy 30.82904 -191.199306) (xy 30.747184 -191.191724)
			(xy 30.666376 -191.176622) (xy 30.587306 -191.154128) (xy 30.510649 -191.124433) (xy 30.43706 -191.087792)
			(xy 30.367165 -191.044517) (xy 30.301562 -190.994976) (xy 30.24081 -190.939594) (xy 30.185427 -190.878843)
			(xy 30.135887 -190.81324) (xy 30.092611 -190.743345) (xy 30.055969 -190.669756) (xy 30.026274 -190.5931)
			(xy 30.003779 -190.51403) (xy 29.988677 -190.433222) (xy 29.981094 -190.351366) (xy 29.980636 -190.310262)
			(xy 29.981112 -190.268997) (xy 29.98878 -190.186825) (xy 30.004027 -190.105716) (xy 30.014926 -190.065914)
			(xy 30.019244 -190.05042) (xy 30.008576 -190.01994) (xy 29.903928 -189.945772) (xy 29.871416 -189.946026)
			(xy 29.858208 -189.95517) (xy 29.825973 -189.977532) (xy 29.758257 -190.017162) (xy 29.687314 -190.050672)
			(xy 29.613694 -190.077803) (xy 29.537971 -190.098344) (xy 29.460733 -190.112134) (xy 29.38258 -190.119067)
			(xy 29.34335 -190.119508) (xy 29.302247 -190.119081) (xy 29.220391 -190.111492) (xy 29.139585 -190.096382)
			(xy 29.060517 -190.073882) (xy 28.983863 -190.044182) (xy 28.910276 -190.007536) (xy 28.840384 -189.964258)
			(xy 28.774784 -189.914715) (xy 28.714034 -189.859331) (xy 28.658653 -189.798578) (xy 28.609114 -189.732974)
			(xy 28.565839 -189.66308) (xy 28.529198 -189.589491) (xy 28.499502 -189.512835) (xy 28.477006 -189.433766)
			(xy 28.461901 -189.352959) (xy 28.454317 -189.271103) (xy 28.453842 -189.23) (xy 28.454463 -189.18351)
			(xy 28.464185 -189.091039) (xy 28.483501 -189.000087) (xy 28.497276 -188.95568) (xy 28.499558 -188.947466)
			(xy 28.499204 -188.930434) (xy 28.493293 -188.914457) (xy 28.488132 -188.907674) (xy 28.462386 -188.875804)
			(xy 28.416201 -188.808125) (xy 28.376438 -188.736484) (xy 28.343434 -188.661489) (xy 28.31747 -188.583776)
			(xy 28.298765 -188.504004) (xy 28.287478 -188.422849) (xy 28.283705 -188.341) (xy 23.990051 -188.341)
			(xy 23.989792 -188.402468) (xy 24.005032 -188.427106) (xy 24.017986 -188.433456) (xy 24.054616 -188.452163)
			(xy 24.124574 -188.49543) (xy 24.190238 -188.544971) (xy 24.251049 -188.600361) (xy 24.306487 -188.661129)
			(xy 24.356079 -188.726755) (xy 24.3994 -188.796679) (xy 24.436082 -188.870303) (xy 24.46581 -188.946999)
			(xy 24.488331 -189.026113) (xy 24.503453 -189.106967) (xy 24.511047 -189.188872) (xy 24.511508 -189.23)
			(xy 24.511004 -189.272348) (xy 24.502953 -189.356662) (xy 24.486924 -189.439828) (xy 24.463063 -189.521095)
			(xy 24.431584 -189.599725) (xy 24.392773 -189.675006) (xy 24.346983 -189.746258) (xy 24.294627 -189.812834)
			(xy 24.236179 -189.874132) (xy 24.172169 -189.929597) (xy 24.103177 -189.978726) (xy 24.029827 -190.021075)
			(xy 23.952784 -190.056259) (xy 23.872745 -190.083961) (xy 23.790436 -190.103929) (xy 23.706601 -190.115982)
			(xy 23.622 -190.120013) (xy 23.537399 -190.115982) (xy 23.453564 -190.103929) (xy 23.371255 -190.083961)
			(xy 23.291216 -190.056259) (xy 23.214173 -190.021075) (xy 23.140823 -189.978726) (xy 23.071831 -189.929597)
			(xy 23.007821 -189.874132) (xy 22.949373 -189.812834) (xy 22.897017 -189.746258) (xy 22.851227 -189.675006)
			(xy 22.812416 -189.599725) (xy 22.780937 -189.521095) (xy 22.757076 -189.439828) (xy 22.741047 -189.356662)
			(xy 22.732996 -189.272348) (xy 22.732492 -189.23) (xy 20.234907 -189.23) (xy 20.238986 -189.237816)
			(xy 20.271097 -189.317104) (xy 20.295441 -189.399112) (xy 20.311794 -189.483078) (xy 20.320003 -189.568228)
			(xy 20.320508 -189.611) (xy 20.320111 -189.649221) (xy 20.313543 -189.725379) (xy 20.300456 -189.800692)
			(xy 20.280946 -189.874602) (xy 20.268438 -189.91072) (xy 20.26526 -189.920931) (xy 20.266835 -189.942239)
			(xy 20.271486 -189.951868) (xy 20.291822 -189.99076) (xy 20.325594 -190.071771) (xy 20.351221 -190.155715)
			(xy 20.368451 -190.241776) (xy 20.377119 -190.329116) (xy 20.377658 -190.373) (xy 20.377133 -190.414101)
			(xy 20.369549 -190.495952) (xy 20.354445 -190.576755) (xy 20.33195 -190.655819) (xy 20.302256 -190.732471)
			(xy 20.265617 -190.806056) (xy 20.222345 -190.875946) (xy 20.172808 -190.941546) (xy 20.117431 -191.002295)
			(xy 20.056684 -191.057676) (xy 19.991087 -191.107216) (xy 19.921199 -191.150493) (xy 19.847616 -191.187136)
			(xy 19.770967 -191.216834) (xy 19.691904 -191.239334) (xy 19.611102 -191.254442) (xy 19.529251 -191.262031)
			(xy 19.48815 -191.262508) (xy 19.44687 -191.262022) (xy 19.364665 -191.254359) (xy 19.283524 -191.239114)
			(xy 19.204144 -191.216416) (xy 19.127208 -191.186462) (xy 19.053379 -191.149509) (xy 18.983291 -191.105874)
			(xy 18.917546 -191.055935) (xy 18.856711 -191.000118) (xy 18.801309 -190.938906) (xy 18.776188 -190.906146)
			(xy 18.769584 -190.897256) (xy 18.750788 -190.887096) (xy 18.653252 -190.878714) (xy 18.633186 -190.885572)
			(xy 18.625058 -190.893192) (xy 18.594163 -190.921695) (xy 18.527835 -190.973341) (xy 18.456928 -191.018496)
			(xy 18.382076 -191.056758) (xy 18.303947 -191.087785) (xy 18.223239 -191.111299) (xy 18.140671 -191.127092)
			(xy 18.056982 -191.135021) (xy 18.01495 -191.135508) (xy 17.972602 -191.135004) (xy 17.888288 -191.126953)
			(xy 17.805122 -191.110924) (xy 17.723855 -191.087063) (xy 17.645225 -191.055584) (xy 17.569944 -191.016773)
			(xy 17.498692 -190.970983) (xy 17.432116 -190.918627) (xy 17.370818 -190.860179) (xy 17.315353 -190.796169)
			(xy 17.266224 -190.727177) (xy 17.223875 -190.653827) (xy 17.188691 -190.576784) (xy 17.160989 -190.496745)
			(xy 17.141021 -190.414436) (xy 17.128968 -190.330601) (xy 17.124938 -190.246) (xy 5.297049 -190.246)
			(xy 5.288847 -190.274829) (xy 5.259151 -190.351483) (xy 5.222509 -190.42507) (xy 5.179234 -190.494962)
			(xy 5.129694 -190.560563) (xy 5.074313 -190.621313) (xy 5.013563 -190.676694) (xy 4.947962 -190.726234)
			(xy 4.87807 -190.769509) (xy 4.804483 -190.806151) (xy 4.727829 -190.835847) (xy 4.648762 -190.858343)
			(xy 4.567957 -190.873448) (xy 4.486102 -190.881033) (xy 4.445 -190.881508) (xy 4.399525 -190.88092)
			(xy 4.309051 -190.871635) (xy 4.264406 -190.862966) (xy 4.253738 -190.86068) (xy 4.232402 -190.865506)
			(xy 4.153916 -190.92418) (xy 4.143502 -190.94323) (xy 4.142486 -190.954152) (xy 4.138617 -190.995356)
			(xy 4.124182 -191.076853) (xy 4.102239 -191.156656) (xy 4.072977 -191.234075) (xy 4.036648 -191.308441)
			(xy 3.993569 -191.379111) (xy 3.94411 -191.445473) (xy 3.8887 -191.506953) (xy 3.827819 -191.56302)
			(xy 3.761991 -191.613188) (xy 3.691788 -191.657024) (xy 3.617817 -191.694149) (xy 3.540716 -191.724241)
			(xy 3.461153 -191.74704) (xy 3.379816 -191.762349) (xy 3.297409 -191.770036) (xy 3.256026 -191.770508)
			(xy 3.214923 -191.770037) (xy 3.133069 -191.762452) (xy 3.052264 -191.747346) (xy 2.973197 -191.72485)
			(xy 2.896543 -191.695153) (xy 2.822956 -191.658511) (xy 2.753064 -191.615236) (xy 2.687463 -191.565696)
			(xy 2.626713 -191.510314) (xy 2.571332 -191.449564) (xy 2.521792 -191.383963) (xy 2.478517 -191.314071)
			(xy 2.441875 -191.240483) (xy 2.412179 -191.163829) (xy 2.389683 -191.084762) (xy 2.374578 -191.003957)
			(xy 2.366993 -190.922103) (xy 2.366518 -190.881) (xy 1.665122 -190.881) (xy 1.651254 -190.897764)
			(xy 1.651254 -194.376294) (xy 2.264918 -194.376294) (xy 2.265383 -194.335467) (xy 2.272881 -194.254157)
			(xy 2.2878 -194.173876) (xy 2.310012 -194.095301) (xy 2.339332 -194.019091) (xy 2.375512 -193.945889)
			(xy 2.418248 -193.876311) (xy 2.467181 -193.810943) (xy 2.521899 -193.750333) (xy 2.58194 -193.694993)
			(xy 2.646801 -193.645388) (xy 2.715934 -193.601936) (xy 2.788759 -193.565002) (xy 2.864662 -193.534898)
			(xy 2.943004 -193.511876) (xy 2.982976 -193.50355) (xy 2.99302 -193.501088) (xy 3.010067 -193.489417)
			(xy 3.015996 -193.480944) (xy 3.03817 -193.44689) (xy 3.087831 -193.382559) (xy 3.143153 -193.323027)
			(xy 3.203675 -193.268788) (xy 3.268891 -193.220295) (xy 3.338258 -193.177952) (xy 3.411197 -193.142113)
			(xy 3.487102 -193.113076) (xy 3.565339 -193.091083) (xy 3.645255 -193.076317) (xy 3.726185 -193.068902)
			(xy 3.76682 -193.068448) (xy 3.807922 -193.068927) (xy 3.889776 -193.076512) (xy 3.920996 -193.082348)
			(xy 4.952996 -193.082348) (xy 4.952996 -192.997652) (xy 4.961047 -192.913338) (xy 4.977076 -192.830172)
			(xy 5.000937 -192.748905) (xy 5.032416 -192.670275) (xy 5.071227 -192.594994) (xy 5.117017 -192.523742)
			(xy 5.169373 -192.457166) (xy 5.227821 -192.395868) (xy 5.291831 -192.340403) (xy 5.360823 -192.291274)
			(xy 5.434173 -192.248925) (xy 5.511216 -192.213741) (xy 5.591255 -192.186039) (xy 5.673564 -192.166071)
			(xy 5.757399 -192.154018) (xy 5.842 -192.149988) (xy 5.926601 -192.154018) (xy 6.010436 -192.166071)
			(xy 6.092745 -192.186039) (xy 6.172784 -192.213741) (xy 6.249827 -192.248925) (xy 6.300186 -192.278)
			(xy 7.745988 -192.278) (xy 7.750018 -192.193399) (xy 7.762071 -192.109564) (xy 7.782039 -192.027255)
			(xy 7.809741 -191.947216) (xy 7.844925 -191.870173) (xy 7.887274 -191.796823) (xy 7.936403 -191.727831)
			(xy 7.991868 -191.663821) (xy 8.053166 -191.605373) (xy 8.119742 -191.553017) (xy 8.190994 -191.507227)
			(xy 8.266275 -191.468416) (xy 8.344905 -191.436937) (xy 8.426172 -191.413076) (xy 8.509338 -191.397047)
			(xy 8.593652 -191.388996) (xy 8.636 -191.388492) (xy 8.678705 -191.389013) (xy 8.763723 -191.397197)
			(xy 8.847565 -191.413488) (xy 8.929461 -191.437738) (xy 8.969248 -191.453262) (xy 8.979288 -191.456877)
			(xy 9.000598 -191.456218) (xy 9.010396 -191.451992) (xy 9.046697 -191.434919) (xy 9.121757 -191.406599)
			(xy 9.199064 -191.385155) (xy 9.277988 -191.370761) (xy 9.357887 -191.363535) (xy 9.398 -191.363092)
			(xy 9.440348 -191.363596) (xy 9.524662 -191.371647) (xy 9.607828 -191.387676) (xy 9.689095 -191.411537)
			(xy 9.767725 -191.443016) (xy 9.843006 -191.481827) (xy 9.914258 -191.527617) (xy 9.980834 -191.579973)
			(xy 9.992059 -191.590676) (xy 27.633168 -191.590676) (xy 27.633672 -191.548328) (xy 27.641723 -191.464014)
			(xy 27.657752 -191.380848) (xy 27.681613 -191.299581) (xy 27.713092 -191.220951) (xy 27.751903 -191.14567)
			(xy 27.797693 -191.074418) (xy 27.850049 -191.007842) (xy 27.908497 -190.946544) (xy 27.972507 -190.891079)
			(xy 28.041499 -190.84195) (xy 28.114849 -190.799601) (xy 28.191892 -190.764417) (xy 28.271931 -190.736715)
			(xy 28.35424 -190.716747) (xy 28.438075 -190.704694) (xy 28.522676 -190.700664) (xy 28.607277 -190.704694)
			(xy 28.691112 -190.716747) (xy 28.773421 -190.736715) (xy 28.85346 -190.764417) (xy 28.930503 -190.799601)
			(xy 29.003853 -190.84195) (xy 29.072845 -190.891079) (xy 29.136855 -190.946544) (xy 29.195303 -191.007842)
			(xy 29.247659 -191.074418) (xy 29.293449 -191.14567) (xy 29.33226 -191.220951) (xy 29.363739 -191.299581)
			(xy 29.3876 -191.380848) (xy 29.403629 -191.464014) (xy 29.41168 -191.548328) (xy 29.412184 -191.590676)
			(xy 29.411456 -191.642598) (xy 29.399355 -191.745734) (xy 29.388054 -191.796416) (xy 29.385514 -191.807084)
			(xy 29.389324 -191.827912) (xy 29.444188 -191.907922) (xy 29.462476 -191.919098) (xy 29.473144 -191.920622)
			(xy 29.514661 -191.926738) (xy 29.596377 -191.945871) (xy 29.675927 -191.972614) (xy 29.752606 -192.00673)
			(xy 29.825731 -192.047916) (xy 29.894652 -192.095804) (xy 29.958758 -192.149971) (xy 29.976363 -192.167948)
			(xy 37.541196 -192.167948) (xy 37.541196 -192.083252) (xy 37.549247 -191.998938) (xy 37.565276 -191.915772)
			(xy 37.589137 -191.834505) (xy 37.620616 -191.755875) (xy 37.659427 -191.680594) (xy 37.705217 -191.609342)
			(xy 37.757573 -191.542766) (xy 37.816021 -191.481468) (xy 37.880031 -191.426003) (xy 37.949023 -191.376874)
			(xy 38.022373 -191.334525) (xy 38.099416 -191.299341) (xy 38.179455 -191.271639) (xy 38.261764 -191.251671)
			(xy 38.345599 -191.239618) (xy 38.4302 -191.235588) (xy 38.514801 -191.239618) (xy 38.598636 -191.251671)
			(xy 38.680945 -191.271639) (xy 38.760984 -191.299341) (xy 38.838027 -191.334525) (xy 38.911377 -191.376874)
			(xy 38.980369 -191.426003) (xy 39.044379 -191.481468) (xy 39.102827 -191.542766) (xy 39.155183 -191.609342)
			(xy 39.200973 -191.680594) (xy 39.239784 -191.755875) (xy 39.271263 -191.834505) (xy 39.295124 -191.915772)
			(xy 39.311153 -191.998938) (xy 39.319204 -192.083252) (xy 39.319708 -192.1256) (xy 39.319406 -192.151)
			(xy 40.746938 -192.151) (xy 40.750968 -192.066399) (xy 40.763021 -191.982564) (xy 40.782989 -191.900255)
			(xy 40.810691 -191.820216) (xy 40.845875 -191.743173) (xy 40.888224 -191.669823) (xy 40.937353 -191.600831)
			(xy 40.992818 -191.536821) (xy 41.054116 -191.478373) (xy 41.120692 -191.426017) (xy 41.191944 -191.380227)
			(xy 41.267225 -191.341416) (xy 41.345855 -191.309937) (xy 41.427122 -191.286076) (xy 41.510288 -191.270047)
			(xy 41.594602 -191.261996) (xy 41.63695 -191.261492) (xy 41.676049 -191.261925) (xy 41.753944 -191.268812)
			(xy 41.830935 -191.282503) (xy 41.906429 -191.302893) (xy 41.979845 -191.329824) (xy 42.01541 -191.346074)
			(xy 42.025797 -191.350309) (xy 42.048203 -191.350309) (xy 42.05859 -191.346074) (xy 42.094143 -191.329794)
			(xy 42.167555 -191.302844) (xy 42.243051 -191.28245) (xy 42.320048 -191.26877) (xy 42.397949 -191.26191)
			(xy 42.43705 -191.261492) (xy 42.485282 -191.262132) (xy 42.581176 -191.272612) (xy 42.675375 -191.293399)
			(xy 42.721276 -191.308228) (xy 42.735246 -191.3128) (xy 42.76344 -191.306196) (xy 42.848276 -191.22009)
			(xy 42.854372 -191.191896) (xy 42.849546 -191.177926) (xy 42.837271 -191.14212) (xy 42.818143 -191.068878)
			(xy 42.805315 -190.994274) (xy 42.798882 -190.918849) (xy 42.798492 -190.881) (xy 42.798818 -190.845784)
			(xy 42.804358 -190.775569) (xy 42.815442 -190.706015) (xy 42.823384 -190.671704) (xy 42.825252 -190.662325)
			(xy 42.822644 -190.643395) (xy 42.818304 -190.634874) (xy 42.803572 -190.608458) (xy 42.798569 -190.600316)
			(xy 42.783822 -190.588182) (xy 42.77487 -190.584836) (xy 42.733956 -190.571204) (xy 42.654768 -190.537036)
			(xy 42.579259 -190.495362) (xy 42.508139 -190.446575) (xy 42.442075 -190.391133) (xy 42.381689 -190.329556)
			(xy 42.327547 -190.262422) (xy 42.280158 -190.190363) (xy 42.239967 -190.114055) (xy 42.207352 -190.034214)
			(xy 42.182619 -189.951592) (xy 42.166 -189.866963) (xy 42.157651 -189.781123) (xy 42.157142 -189.738)
			(xy 42.157565 -189.697131) (xy 42.165056 -189.615737) (xy 42.179984 -189.535374) (xy 42.202223 -189.456719)
			(xy 42.231585 -189.380437) (xy 42.267822 -189.30717) (xy 42.31063 -189.237538) (xy 42.359646 -189.172128)
			(xy 42.414457 -189.111491) (xy 42.474601 -189.056139) (xy 42.53957 -189.006539) (xy 42.608816 -188.96311)
			(xy 42.645076 -188.94425) (xy 42.653615 -188.939402) (xy 42.666502 -188.924616) (xy 42.672861 -188.906061)
			(xy 42.672762 -188.896244) (xy 42.671492 -188.849) (xy 42.672762 -188.801756) (xy 42.672798 -188.79195)
			(xy 42.666414 -188.773428) (xy 42.653587 -188.758619) (xy 42.645076 -188.75375) (xy 42.608804 -188.734917)
			(xy 42.53957 -188.691474) (xy 42.474612 -188.641863) (xy 42.414479 -188.586504) (xy 42.359677 -188.525862)
			(xy 42.310669 -188.460448) (xy 42.267868 -188.390816) (xy 42.231635 -188.31755) (xy 42.202274 -188.24127)
			(xy 42.180034 -188.162619) (xy 42.165103 -188.082259) (xy 42.157606 -188.000868) (xy 42.157142 -187.96)
			(xy 42.157627 -187.916959) (xy 42.165952 -187.831281) (xy 42.182514 -187.746808) (xy 42.207158 -187.664329)
			(xy 42.239654 -187.584617) (xy 42.279697 -187.508416) (xy 42.326914 -187.43644) (xy 42.380863 -187.369361)
			(xy 42.441039 -187.307807) (xy 42.506879 -187.252354) (xy 42.577768 -187.203519) (xy 42.653043 -187.161761)
			(xy 42.69232 -187.144152) (xy 42.700451 -187.140277) (xy 42.713481 -187.127856) (xy 42.721389 -187.111684)
			(xy 42.723191 -187.093772) (xy 42.721276 -187.08497) (xy 42.70883 -187.029344) (xy 42.705894 -187.017435)
			(xy 42.690749 -186.99819) (xy 42.679874 -186.992514) (xy 42.641398 -186.974506) (xy 42.567695 -186.93225)
			(xy 42.498356 -186.88316) (xy 42.434012 -186.827684) (xy 42.37525 -186.766327) (xy 42.322605 -186.699647)
			(xy 42.276556 -186.628253) (xy 42.237523 -186.552794) (xy 42.205861 -186.473957) (xy 42.181859 -186.392461)
			(xy 42.165735 -186.309048) (xy 42.157636 -186.224478) (xy 42.157142 -186.182) (xy 42.157667 -186.140899)
			(xy 42.165251 -186.059048) (xy 42.180355 -185.978245) (xy 42.20285 -185.899181) (xy 42.232544 -185.822529)
			(xy 42.269183 -185.748944) (xy 42.312455 -185.679054) (xy 42.361992 -185.613454) (xy 42.417369 -185.552705)
			(xy 42.478116 -185.497324) (xy 42.543713 -185.447784) (xy 42.613601 -185.404507) (xy 42.687184 -185.367864)
			(xy 42.763833 -185.338166) (xy 42.842896 -185.315666) (xy 42.923698 -185.300558) (xy 43.005549 -185.292969)
			(xy 43.04665 -185.292492) (xy 43.087671 -185.292949) (xy 43.169363 -185.300523) (xy 43.25001 -185.315584)
			(xy 43.328929 -185.338004) (xy 43.40545 -185.367593) (xy 43.478922 -185.404099) (xy 43.504665 -185.42)
			(xy 46.618906 -185.42) (xy 46.619403 -185.377447) (xy 46.627513 -185.292728) (xy 46.64368 -185.209171)
			(xy 46.667754 -185.127541) (xy 46.699517 -185.048583) (xy 46.738676 -184.973021) (xy 46.784874 -184.901545)
			(xy 46.837689 -184.83481) (xy 46.896638 -184.773424) (xy 46.961181 -184.717951) (xy 47.030727 -184.668896)
			(xy 47.104642 -184.626709) (xy 47.182249 -184.591777) (xy 47.262837 -184.564417) (xy 47.345671 -184.54488)
			(xy 47.387764 -184.53862) (xy 47.398432 -184.53735) (xy 47.41672 -184.52592) (xy 47.47133 -184.445402)
			(xy 47.47514 -184.42432) (xy 47.4726 -184.413652) (xy 47.464349 -184.378784) (xy 47.452835 -184.308055)
			(xy 47.447051 -184.23663) (xy 47.446692 -184.2008) (xy 47.447196 -184.158452) (xy 47.455247 -184.074138)
			(xy 47.471276 -183.990972) (xy 47.495137 -183.909705) (xy 47.526616 -183.831075) (xy 47.565427 -183.755794)
			(xy 47.611217 -183.684542) (xy 47.663573 -183.617966) (xy 47.722021 -183.556668) (xy 47.786031 -183.501203)
			(xy 47.855023 -183.452074) (xy 47.928373 -183.409725) (xy 48.005416 -183.374541) (xy 48.085455 -183.346839)
			(xy 48.167764 -183.326871) (xy 48.251599 -183.314818) (xy 48.3362 -183.310788) (xy 48.420801 -183.314818)
			(xy 48.504636 -183.326871) (xy 48.586945 -183.346839) (xy 48.666984 -183.374541) (xy 48.744027 -183.409725)
			(xy 48.817377 -183.452074) (xy 48.886369 -183.501203) (xy 48.950379 -183.556668) (xy 49.008827 -183.617966)
			(xy 49.061183 -183.684542) (xy 49.106973 -183.755794) (xy 49.145784 -183.831075) (xy 49.177263 -183.909705)
			(xy 49.201124 -183.990972) (xy 49.217153 -184.074138) (xy 49.225204 -184.158452) (xy 49.225708 -184.2008)
			(xy 49.225199 -184.243353) (xy 49.217089 -184.328071) (xy 49.200922 -184.411627) (xy 49.176848 -184.493257)
			(xy 49.145087 -184.572214) (xy 49.105928 -184.647775) (xy 49.059731 -184.719251) (xy 49.006917 -184.785986)
			(xy 48.947969 -184.847372) (xy 48.883428 -184.902846) (xy 48.813882 -184.9519) (xy 48.739968 -184.994087)
			(xy 48.662363 -185.029021) (xy 48.581775 -185.056382) (xy 48.498943 -185.075919) (xy 48.45685 -185.08218)
			(xy 48.446182 -185.08345) (xy 48.427894 -185.09488) (xy 48.373284 -185.175398) (xy 48.369474 -185.19648)
			(xy 48.372014 -185.207148) (xy 48.377544 -185.230233) (xy 48.386437 -185.276867) (xy 48.389794 -185.300366)
			(xy 48.391572 -185.312558) (xy 48.405034 -185.33237) (xy 48.499014 -185.38317) (xy 48.52289 -185.383932)
			(xy 48.534066 -185.378598) (xy 48.569903 -185.362065) (xy 48.643911 -185.334631) (xy 48.720058 -185.313862)
			(xy 48.797746 -185.299923) (xy 48.876364 -185.292923) (xy 48.915828 -185.292492) (xy 48.958176 -185.292997)
			(xy 49.042487 -185.30105) (xy 49.125652 -185.317081) (xy 49.206915 -185.340945) (xy 49.285543 -185.372425)
			(xy 49.360822 -185.411236) (xy 49.432072 -185.457027) (xy 49.498646 -185.509383) (xy 49.559942 -185.567831)
			(xy 49.615404 -185.63184) (xy 49.664532 -185.700831) (xy 49.706879 -185.77418) (xy 49.742062 -185.851222)
			(xy 49.769762 -185.931259) (xy 49.789729 -186.013567) (xy 49.801783 -186.097401) (xy 49.805813 -186.182)
			(xy 49.801783 -186.266599) (xy 49.789729 -186.350433) (xy 49.769762 -186.432741) (xy 49.742062 -186.512778)
			(xy 49.706879 -186.58982) (xy 49.664532 -186.663169) (xy 49.615404 -186.73216) (xy 49.559942 -186.796169)
			(xy 49.498646 -186.854617) (xy 49.432072 -186.906973) (xy 49.360822 -186.952764) (xy 49.285543 -186.991575)
			(xy 49.206915 -187.023055) (xy 49.125652 -187.046919) (xy 49.042487 -187.06295) (xy 48.958176 -187.071003)
			(xy 48.915828 -187.071508) (xy 48.873246 -187.071031) (xy 48.788472 -187.062884) (xy 48.704865 -187.046673)
			(xy 48.62319 -187.022545) (xy 48.544195 -186.990722) (xy 48.468603 -186.951494) (xy 48.397106 -186.905221)
			(xy 48.330359 -186.852326) (xy 48.268973 -186.793295) (xy 48.21351 -186.728666) (xy 48.164478 -186.659033)
			(xy 48.122326 -186.585032) (xy 48.087439 -186.507341) (xy 48.060137 -186.426672) (xy 48.04067 -186.343762)
			(xy 48.034448 -186.301634) (xy 48.03267 -186.289442) (xy 48.019208 -186.26963) (xy 47.925228 -186.21883)
			(xy 47.901352 -186.218068) (xy 47.890176 -186.223402) (xy 47.854348 -186.239956) (xy 47.780338 -186.267386)
			(xy 47.704188 -186.28815) (xy 47.626498 -186.302084) (xy 47.547879 -186.30908) (xy 47.508414 -186.309508)
			(xy 47.467311 -186.309034) (xy 47.385456 -186.301451) (xy 47.304649 -186.286347) (xy 47.225581 -186.263851)
			(xy 47.148926 -186.234156) (xy 47.075338 -186.197514) (xy 47.005445 -186.154239) (xy 46.939843 -186.1047)
			(xy 46.879092 -186.049318) (xy 46.823709 -185.988568) (xy 46.774169 -185.922967) (xy 46.730893 -185.853074)
			(xy 46.69425 -185.779486) (xy 46.664554 -185.702832) (xy 46.642057 -185.623764) (xy 46.626951 -185.542958)
			(xy 46.619366 -185.461103) (xy 46.618906 -185.42) (xy 43.504665 -185.42) (xy 43.548722 -185.447213)
			(xy 43.614258 -185.496569) (xy 43.674973 -185.551747) (xy 43.730351 -185.612279) (xy 43.779923 -185.677651)
			(xy 43.823267 -185.747309) (xy 43.860016 -185.82066) (xy 43.889858 -185.897082) (xy 43.912539 -185.975927)
			(xy 43.920664 -186.016138) (xy 43.923612 -186.028043) (xy 43.938749 -186.04729) (xy 43.94962 -186.052968)
			(xy 43.988111 -186.070944) (xy 44.061812 -186.113206) (xy 44.131148 -186.162301) (xy 44.195489 -186.217782)
			(xy 44.254248 -186.279143) (xy 44.306891 -186.345826) (xy 44.352938 -186.417223) (xy 44.39197 -186.492684)
			(xy 44.423631 -186.571522) (xy 44.447633 -186.653018) (xy 44.463757 -186.736432) (xy 44.471857 -186.821003)
			(xy 44.472352 -186.863482) (xy 44.471855 -186.906523) (xy 44.463531 -186.9922) (xy 44.446971 -187.076673)
			(xy 44.422329 -187.159152) (xy 44.389834 -187.238864) (xy 44.349792 -187.315065) (xy 44.302576 -187.387041)
			(xy 44.248628 -187.45412) (xy 44.188453 -187.515675) (xy 44.122613 -187.571128) (xy 44.051725 -187.619963)
			(xy 43.976451 -187.661721) (xy 43.937174 -187.67933) (xy 43.92907 -187.683259) (xy 43.91603 -187.695656)
			(xy 43.908112 -187.711812) (xy 43.906305 -187.729714) (xy 43.908218 -187.738512) (xy 43.917121 -187.774748)
			(xy 43.929555 -187.848327) (xy 43.935786 -187.922689) (xy 43.936158 -187.96) (xy 43.934888 -188.007244)
			(xy 43.934826 -188.017052) (xy 43.941216 -188.035579) (xy 43.954056 -188.050385) (xy 43.962574 -188.05525)
			(xy 44.000401 -188.07495) (xy 44.072472 -188.120562) (xy 44.139847 -188.172862) (xy 44.201907 -188.231372)
			(xy 44.258081 -188.295553) (xy 44.307855 -188.364816) (xy 44.35077 -188.438525) (xy 44.386433 -188.516003)
			(xy 44.414516 -188.596539) (xy 44.434762 -188.679394) (xy 44.446984 -188.763806) (xy 44.451071 -188.849)
			(xy 44.446984 -188.934194) (xy 44.434762 -189.018606) (xy 44.414516 -189.101461) (xy 44.386433 -189.181997)
			(xy 44.35077 -189.259475) (xy 44.307855 -189.333184) (xy 44.258081 -189.402447) (xy 44.201907 -189.466628)
			(xy 44.139847 -189.525138) (xy 44.072472 -189.577438) (xy 44.000401 -189.62305) (xy 43.962574 -189.64275)
			(xy 43.954025 -189.647581) (xy 43.941144 -189.662377) (xy 43.934789 -189.680937) (xy 43.934888 -189.690756)
			(xy 43.936158 -189.738) (xy 45.205142 -189.738) (xy 45.205588 -189.696747) (xy 45.213246 -189.614597)
			(xy 45.228476 -189.533509) (xy 45.251149 -189.454179) (xy 45.281069 -189.377289) (xy 45.317979 -189.3035)
			(xy 45.361562 -189.233444) (xy 45.411445 -189.167725) (xy 45.467198 -189.106907) (xy 45.528342 -189.051512)
			(xy 45.594353 -189.002015) (xy 45.664662 -188.958843) (xy 45.701458 -188.940186) (xy 45.709761 -188.935616)
			(xy 45.722514 -188.921614) (xy 45.72931 -188.903937) (xy 45.729652 -188.894466) (xy 45.729652 -188.803534)
			(xy 45.729277 -188.794066) (xy 45.722493 -188.77639) (xy 45.709761 -188.762377) (xy 45.701458 -188.757814)
			(xy 45.664649 -188.739179) (xy 45.594327 -188.696019) (xy 45.528306 -188.646531) (xy 45.467153 -188.591139)
			(xy 45.411394 -188.530321) (xy 45.361508 -188.464599) (xy 45.317926 -188.394539) (xy 45.28102 -188.320743)
			(xy 45.25111 -188.243845) (xy 45.228451 -188.164507) (xy 45.213239 -188.083411) (xy 45.205605 -188.001255)
			(xy 45.205142 -187.96) (xy 45.205589 -187.918925) (xy 45.213155 -187.837124) (xy 45.228231 -187.75637)
			(xy 45.25069 -187.677349) (xy 45.280339 -187.600737) (xy 45.316926 -187.527184) (xy 45.36014 -187.457319)
			(xy 45.409612 -187.391736) (xy 45.46492 -187.330994) (xy 45.525594 -187.275611) (xy 45.591116 -187.226059)
			(xy 45.660928 -187.182759) (xy 45.734436 -187.146081) (xy 45.811012 -187.116338) (xy 45.890005 -187.093782)
			(xy 45.970741 -187.078607) (xy 46.011592 -187.074302) (xy 46.020038 -187.073175) (xy 46.035522 -187.066087)
			(xy 46.047818 -187.054306) (xy 46.051978 -187.04687) (xy 46.070945 -187.010854) (xy 46.114486 -186.942074)
			(xy 46.16413 -186.877559) (xy 46.219461 -186.817851) (xy 46.280016 -186.763448) (xy 46.345288 -186.714805)
			(xy 46.414732 -186.67233) (xy 46.487767 -186.636378) (xy 46.563781 -186.60725) (xy 46.642139 -186.585189)
			(xy 46.722184 -186.570379) (xy 46.803248 -186.562946) (xy 46.84395 -186.562492) (xy 46.885053 -186.562919)
			(xy 46.966909 -186.570508) (xy 47.047715 -186.585618) (xy 47.126783 -186.608118) (xy 47.203437 -186.637818)
			(xy 47.277024 -186.674464) (xy 47.346916 -186.717742) (xy 47.412516 -186.767285) (xy 47.473266 -186.822669)
			(xy 47.528647 -186.883422) (xy 47.578186 -186.949026) (xy 47.621461 -187.01892) (xy 47.658102 -187.092509)
			(xy 47.687798 -187.169165) (xy 47.710294 -187.248234) (xy 47.725399 -187.329041) (xy 47.732983 -187.410897)
			(xy 47.733458 -187.452) (xy 47.733011 -187.493075) (xy 47.725445 -187.574876) (xy 47.710369 -187.65563)
			(xy 47.68791 -187.734651) (xy 47.658261 -187.811263) (xy 47.621674 -187.884816) (xy 47.57846 -187.954681)
			(xy 47.528988 -188.020264) (xy 47.47368 -188.081006) (xy 47.413006 -188.136389) (xy 47.347484 -188.185941)
			(xy 47.277672 -188.229241) (xy 47.204164 -188.265919) (xy 47.127588 -188.295662) (xy 47.048595 -188.318218)
			(xy 46.967859 -188.333393) (xy 46.927008 -188.337698) (xy 46.918562 -188.338825) (xy 46.903078 -188.345913)
			(xy 46.890782 -188.357694) (xy 46.886622 -188.36513) (xy 46.867677 -188.401127) (xy 46.824172 -188.469867)
			(xy 46.774567 -188.534343) (xy 46.719276 -188.594016) (xy 46.658763 -188.648385) (xy 46.593534 -188.696996)
			(xy 46.524135 -188.739442) (xy 46.487842 -188.757814) (xy 46.479539 -188.762384) (xy 46.466786 -188.776386)
			(xy 46.45999 -188.794063) (xy 46.459648 -188.803534) (xy 46.459648 -188.894466) (xy 46.460023 -188.903934)
			(xy 46.466807 -188.92161) (xy 46.479539 -188.935623) (xy 46.487842 -188.940186) (xy 46.524651 -188.958821)
			(xy 46.594973 -189.001981) (xy 46.660994 -189.051469) (xy 46.722147 -189.106861) (xy 46.777906 -189.167679)
			(xy 46.827792 -189.233401) (xy 46.871374 -189.303461) (xy 46.90828 -189.377257) (xy 46.93819 -189.454155)
			(xy 46.960849 -189.533493) (xy 46.976061 -189.614589) (xy 46.983695 -189.696745) (xy 46.984158 -189.738)
			(xy 46.983654 -189.780348) (xy 46.975603 -189.864662) (xy 46.959574 -189.947828) (xy 46.935713 -190.029095)
			(xy 46.904234 -190.107725) (xy 46.865423 -190.183006) (xy 46.819633 -190.254258) (xy 46.767277 -190.320834)
			(xy 46.708829 -190.382132) (xy 46.644819 -190.437597) (xy 46.575827 -190.486726) (xy 46.502477 -190.529075)
			(xy 46.425434 -190.564259) (xy 46.345395 -190.591961) (xy 46.263086 -190.611929) (xy 46.179251 -190.623982)
			(xy 46.09465 -190.628013) (xy 46.010049 -190.623982) (xy 45.926214 -190.611929) (xy 45.843905 -190.591961)
			(xy 45.763866 -190.564259) (xy 45.686823 -190.529075) (xy 45.613473 -190.486726) (xy 45.544481 -190.437597)
			(xy 45.480471 -190.382132) (xy 45.422023 -190.320834) (xy 45.369667 -190.254258) (xy 45.323877 -190.183006)
			(xy 45.285066 -190.107725) (xy 45.253587 -190.029095) (xy 45.229726 -189.947828) (xy 45.213697 -189.864662)
			(xy 45.205646 -189.780348) (xy 45.205142 -189.738) (xy 43.936158 -189.738) (xy 43.935831 -189.773216)
			(xy 43.930291 -189.843431) (xy 43.919208 -189.912985) (xy 43.911266 -189.947296) (xy 43.909404 -189.956676)
			(xy 43.91201 -189.975604) (xy 43.916346 -189.984126) (xy 43.931078 -190.010542) (xy 43.936062 -190.018698)
			(xy 43.950823 -190.030825) (xy 43.95978 -190.034164) (xy 44.000704 -190.047766) (xy 44.079892 -190.081938)
			(xy 44.1554 -190.123615) (xy 44.226519 -190.172406) (xy 44.292582 -190.227851) (xy 44.352967 -190.289431)
			(xy 44.407107 -190.356567) (xy 44.454495 -190.428629) (xy 44.494685 -190.504939) (xy 44.527299 -190.584781)
			(xy 44.552032 -190.667405) (xy 44.568651 -190.752035) (xy 44.576999 -190.837877) (xy 44.577508 -190.881)
			(xy 44.577033 -190.922102) (xy 44.569448 -191.003957) (xy 44.554343 -191.084762) (xy 44.531847 -191.163829)
			(xy 44.502151 -191.240483) (xy 44.465509 -191.31407) (xy 44.422234 -191.383962) (xy 44.372694 -191.449563)
			(xy 44.317313 -191.510313) (xy 44.256563 -191.565694) (xy 44.190962 -191.615234) (xy 44.12107 -191.658509)
			(xy 44.047483 -191.695151) (xy 43.970829 -191.724847) (xy 43.891762 -191.747343) (xy 43.810957 -191.762448)
			(xy 43.729102 -191.770033) (xy 43.688 -191.770508) (xy 43.639768 -191.769854) (xy 43.543874 -191.75938)
			(xy 43.449675 -191.738598) (xy 43.403774 -191.723772) (xy 43.389804 -191.7192) (xy 43.36161 -191.725804)
			(xy 43.276774 -191.81191) (xy 43.270678 -191.840104) (xy 43.275504 -191.854074) (xy 43.287781 -191.889879)
			(xy 43.306909 -191.963121) (xy 43.319735 -192.037726) (xy 43.326168 -192.113151) (xy 43.326558 -192.151)
			(xy 43.326033 -192.192101) (xy 43.318449 -192.273952) (xy 43.303345 -192.354755) (xy 43.28085 -192.433819)
			(xy 43.251156 -192.510471) (xy 43.214517 -192.584056) (xy 43.171245 -192.653946) (xy 43.121708 -192.719546)
			(xy 43.066331 -192.780295) (xy 43.005584 -192.835676) (xy 42.939987 -192.885216) (xy 42.870099 -192.928493)
			(xy 42.796516 -192.965136) (xy 42.719867 -192.994834) (xy 42.640804 -193.017334) (xy 42.560002 -193.032442)
			(xy 42.478151 -193.040031) (xy 42.43705 -193.040508) (xy 42.397951 -193.040075) (xy 42.320056 -193.033188)
			(xy 42.243065 -193.019497) (xy 42.167571 -192.999107) (xy 42.094155 -192.972176) (xy 42.05859 -192.955926)
			(xy 42.048203 -192.951691) (xy 42.025797 -192.951691) (xy 42.01541 -192.955926) (xy 41.979857 -192.972206)
			(xy 41.906445 -192.999156) (xy 41.830949 -193.01955) (xy 41.753952 -193.03323) (xy 41.676051 -193.04009)
			(xy 41.63695 -193.040508) (xy 41.594602 -193.040004) (xy 41.510288 -193.031953) (xy 41.427122 -193.015924)
			(xy 41.345855 -192.992063) (xy 41.267225 -192.960584) (xy 41.191944 -192.921773) (xy 41.120692 -192.875983)
			(xy 41.054116 -192.823627) (xy 40.992818 -192.765179) (xy 40.937353 -192.701169) (xy 40.888224 -192.632177)
			(xy 40.845875 -192.558827) (xy 40.810691 -192.481784) (xy 40.782989 -192.401745) (xy 40.763021 -192.319436)
			(xy 40.750968 -192.235601) (xy 40.746938 -192.151) (xy 39.319406 -192.151) (xy 39.319204 -192.167948)
			(xy 39.311153 -192.252262) (xy 39.295124 -192.335428) (xy 39.271263 -192.416695) (xy 39.239784 -192.495325)
			(xy 39.200973 -192.570606) (xy 39.155183 -192.641858) (xy 39.102827 -192.708434) (xy 39.044379 -192.769732)
			(xy 38.980369 -192.825197) (xy 38.911377 -192.874326) (xy 38.838027 -192.916675) (xy 38.760984 -192.951859)
			(xy 38.680945 -192.979561) (xy 38.598636 -192.999529) (xy 38.514801 -193.011582) (xy 38.4302 -193.015613)
			(xy 38.345599 -193.011582) (xy 38.261764 -192.999529) (xy 38.179455 -192.979561) (xy 38.099416 -192.951859)
			(xy 38.022373 -192.916675) (xy 37.949023 -192.874326) (xy 37.880031 -192.825197) (xy 37.816021 -192.769732)
			(xy 37.757573 -192.708434) (xy 37.705217 -192.641858) (xy 37.659427 -192.570606) (xy 37.620616 -192.495325)
			(xy 37.589137 -192.416695) (xy 37.565276 -192.335428) (xy 37.549247 -192.252262) (xy 37.541196 -192.167948)
			(xy 29.976363 -192.167948) (xy 30.017478 -192.209933) (xy 30.070289 -192.275159) (xy 30.116724 -192.345068)
			(xy 30.156369 -192.41904) (xy 30.188871 -192.496416) (xy 30.20187 -192.536318) (xy 30.205016 -192.54495)
			(xy 30.216332 -192.559405) (xy 30.223968 -192.564512) (xy 30.249368 -192.580006) (xy 30.257447 -192.584437)
			(xy 30.275542 -192.58783) (xy 30.284674 -192.58661) (xy 30.322782 -192.580331) (xy 30.399725 -192.573586)
			(xy 30.438344 -192.573148) (xy 30.480692 -192.57366) (xy 30.565005 -192.581711) (xy 30.648171 -192.59774)
			(xy 30.729436 -192.621602) (xy 30.808066 -192.653081) (xy 30.883347 -192.691891) (xy 30.954598 -192.737682)
			(xy 31.021173 -192.790038) (xy 31.082471 -192.848485) (xy 31.137935 -192.912495) (xy 31.187064 -192.981486)
			(xy 31.229412 -193.054836) (xy 31.264596 -193.131878) (xy 31.292297 -193.211916) (xy 31.312265 -193.294225)
			(xy 31.324318 -193.37806) (xy 31.328349 -193.46266) (xy 31.324318 -193.54726) (xy 31.312265 -193.631095)
			(xy 31.292297 -193.713404) (xy 31.264596 -193.793442) (xy 31.229412 -193.870484) (xy 31.187064 -193.943834)
			(xy 31.165662 -193.973888) (xy 35.897054 -193.973888) (xy 35.897054 -193.889192) (xy 35.905105 -193.804878)
			(xy 35.921134 -193.721712) (xy 35.944995 -193.640445) (xy 35.976474 -193.561815) (xy 36.015285 -193.486534)
			(xy 36.061075 -193.415282) (xy 36.113431 -193.348706) (xy 36.171879 -193.287408) (xy 36.235889 -193.231943)
			(xy 36.304881 -193.182814) (xy 36.378231 -193.140465) (xy 36.455274 -193.105281) (xy 36.535313 -193.077579)
			(xy 36.617622 -193.057611) (xy 36.701457 -193.045558) (xy 36.786058 -193.041528) (xy 36.870659 -193.045558)
			(xy 36.954494 -193.057611) (xy 37.036803 -193.077579) (xy 37.116842 -193.105281) (xy 37.193885 -193.140465)
			(xy 37.267235 -193.182814) (xy 37.336227 -193.231943) (xy 37.400237 -193.287408) (xy 37.458685 -193.348706)
			(xy 37.511041 -193.415282) (xy 37.556831 -193.486534) (xy 37.595642 -193.561815) (xy 37.627121 -193.640445)
			(xy 37.650982 -193.721712) (xy 37.667011 -193.804878) (xy 37.675062 -193.889192) (xy 37.675566 -193.93154)
			(xy 37.675062 -193.973888) (xy 37.667011 -194.058202) (xy 37.650982 -194.141368) (xy 37.627121 -194.222635)
			(xy 37.595642 -194.301265) (xy 37.556831 -194.376546) (xy 37.511041 -194.447798) (xy 37.458685 -194.514374)
			(xy 37.400237 -194.575672) (xy 37.336227 -194.631137) (xy 37.267235 -194.680266) (xy 37.193885 -194.722615)
			(xy 37.116842 -194.757799) (xy 37.036803 -194.785501) (xy 36.954494 -194.805469) (xy 36.870659 -194.817522)
			(xy 36.786058 -194.821553) (xy 36.701457 -194.817522) (xy 36.617622 -194.805469) (xy 36.535313 -194.785501)
			(xy 36.455274 -194.757799) (xy 36.378231 -194.722615) (xy 36.304881 -194.680266) (xy 36.235889 -194.631137)
			(xy 36.171879 -194.575672) (xy 36.113431 -194.514374) (xy 36.061075 -194.447798) (xy 36.015285 -194.376546)
			(xy 35.976474 -194.301265) (xy 35.944995 -194.222635) (xy 35.921134 -194.141368) (xy 35.905105 -194.058202)
			(xy 35.897054 -193.973888) (xy 31.165662 -193.973888) (xy 31.137935 -194.012825) (xy 31.082471 -194.076835)
			(xy 31.021173 -194.135282) (xy 30.954598 -194.187638) (xy 30.883347 -194.233429) (xy 30.808066 -194.272239)
			(xy 30.729436 -194.303718) (xy 30.648171 -194.32758) (xy 30.565005 -194.343609) (xy 30.480692 -194.35166)
			(xy 30.438344 -194.352164) (xy 30.394974 -194.351621) (xy 30.308648 -194.343173) (xy 30.223553 -194.326362)
			(xy 30.140499 -194.301349) (xy 30.060273 -194.26837) (xy 29.983639 -194.227739) (xy 29.911324 -194.179841)
			(xy 29.844013 -194.125132) (xy 29.782348 -194.064132) (xy 29.726913 -193.997418) (xy 29.678235 -193.925626)
			(xy 29.636776 -193.849437) (xy 29.602929 -193.769574) (xy 29.589476 -193.72834) (xy 29.586363 -193.719693)
			(xy 29.575025 -193.705245) (xy 29.567378 -193.700146) (xy 29.541978 -193.684652) (xy 29.533913 -193.680193)
			(xy 29.515807 -193.676819) (xy 29.506672 -193.678048) (xy 29.468565 -193.684334) (xy 29.391621 -193.691074)
			(xy 29.353002 -193.69151) (xy 29.3119 -193.691031) (xy 29.230045 -193.683447) (xy 29.14924 -193.668342)
			(xy 29.070174 -193.645846) (xy 28.99352 -193.61615) (xy 28.919933 -193.579508) (xy 28.850041 -193.536233)
			(xy 28.78444 -193.486694) (xy 28.72369 -193.431313) (xy 28.668309 -193.370563) (xy 28.618769 -193.304962)
			(xy 28.575494 -193.23507) (xy 28.538852 -193.161484) (xy 28.509156 -193.08483) (xy 28.486659 -193.005764)
			(xy 28.471554 -192.924959) (xy 28.463969 -192.843104) (xy 28.463494 -192.802002) (xy 28.464234 -192.750081)
			(xy 28.476327 -192.646945) (xy 28.487624 -192.596262) (xy 28.490164 -192.585594) (xy 28.486354 -192.564766)
			(xy 28.43149 -192.484756) (xy 28.413202 -192.47358) (xy 28.402534 -192.472056) (xy 28.360421 -192.465833)
			(xy 28.277552 -192.446325) (xy 28.196925 -192.418989) (xy 28.119279 -192.384075) (xy 28.045324 -192.341902)
			(xy 27.975737 -192.292857) (xy 27.911154 -192.237387) (xy 27.852166 -192.176) (xy 27.799312 -192.109258)
			(xy 27.753078 -192.037772) (xy 27.713884 -191.962196) (xy 27.682091 -191.883221) (xy 27.657988 -191.801569)
			(xy 27.641797 -191.717989) (xy 27.633665 -191.633243) (xy 27.633168 -191.590676) (xy 9.992059 -191.590676)
			(xy 10.042132 -191.638421) (xy 10.097597 -191.702431) (xy 10.146726 -191.771423) (xy 10.189075 -191.844773)
			(xy 10.224259 -191.921816) (xy 10.251961 -192.001855) (xy 10.271929 -192.084164) (xy 10.283982 -192.167999)
			(xy 10.288013 -192.2526) (xy 10.283982 -192.337201) (xy 10.271929 -192.421036) (xy 10.251961 -192.503345)
			(xy 10.224259 -192.583384) (xy 10.189075 -192.660427) (xy 10.146726 -192.733777) (xy 10.097597 -192.802769)
			(xy 10.042132 -192.866779) (xy 9.980834 -192.925227) (xy 9.914258 -192.977583) (xy 9.843006 -193.023373)
			(xy 9.767725 -193.062184) (xy 9.689095 -193.093663) (xy 9.607828 -193.117524) (xy 9.524662 -193.133553)
			(xy 9.440348 -193.141604) (xy 9.398 -193.142108) (xy 9.355295 -193.141587) (xy 9.270277 -193.133403)
			(xy 9.186435 -193.117112) (xy 9.104539 -193.092862) (xy 9.064752 -193.077338) (xy 9.054712 -193.073723)
			(xy 9.033402 -193.074382) (xy 9.023604 -193.078608) (xy 8.987303 -193.095681) (xy 8.912243 -193.124001)
			(xy 8.834936 -193.145445) (xy 8.756012 -193.159839) (xy 8.676113 -193.167065) (xy 8.636 -193.167508)
			(xy 8.593652 -193.167004) (xy 8.509338 -193.158953) (xy 8.426172 -193.142924) (xy 8.344905 -193.119063)
			(xy 8.266275 -193.087584) (xy 8.190994 -193.048773) (xy 8.119742 -193.002983) (xy 8.053166 -192.950627)
			(xy 7.991868 -192.892179) (xy 7.936403 -192.828169) (xy 7.887274 -192.759177) (xy 7.844925 -192.685827)
			(xy 7.809741 -192.608784) (xy 7.782039 -192.528745) (xy 7.762071 -192.446436) (xy 7.750018 -192.362601)
			(xy 7.745988 -192.278) (xy 6.300186 -192.278) (xy 6.323177 -192.291274) (xy 6.392169 -192.340403)
			(xy 6.456179 -192.395868) (xy 6.514627 -192.457166) (xy 6.566983 -192.523742) (xy 6.612773 -192.594994)
			(xy 6.651584 -192.670275) (xy 6.683063 -192.748905) (xy 6.706924 -192.830172) (xy 6.722953 -192.913338)
			(xy 6.731004 -192.997652) (xy 6.731508 -193.04) (xy 6.731004 -193.082348) (xy 6.722953 -193.166662)
			(xy 6.706924 -193.249828) (xy 6.683063 -193.331095) (xy 6.651584 -193.409725) (xy 6.612773 -193.485006)
			(xy 6.566983 -193.556258) (xy 6.514627 -193.622834) (xy 6.497164 -193.641148) (xy 14.7513 -193.641148)
			(xy 14.7513 -193.556452) (xy 14.759351 -193.472138) (xy 14.77538 -193.388972) (xy 14.799241 -193.307705)
			(xy 14.83072 -193.229075) (xy 14.869531 -193.153794) (xy 14.915321 -193.082542) (xy 14.967677 -193.015966)
			(xy 15.026125 -192.954668) (xy 15.090135 -192.899203) (xy 15.159127 -192.850074) (xy 15.232477 -192.807725)
			(xy 15.30952 -192.772541) (xy 15.389559 -192.744839) (xy 15.471868 -192.724871) (xy 15.555703 -192.712818)
			(xy 15.640304 -192.708788) (xy 15.724905 -192.712818) (xy 15.80874 -192.724871) (xy 15.891049 -192.744839)
			(xy 15.971088 -192.772541) (xy 16.048131 -192.807725) (xy 16.121481 -192.850074) (xy 16.190473 -192.899203)
			(xy 16.254483 -192.954668) (xy 16.312931 -193.015966) (xy 16.365287 -193.082542) (xy 16.411077 -193.153794)
			(xy 16.449888 -193.229075) (xy 16.481367 -193.307705) (xy 16.505228 -193.388972) (xy 16.521257 -193.472138)
			(xy 16.529308 -193.556452) (xy 16.529812 -193.5988) (xy 16.529308 -193.641148) (xy 16.521257 -193.725462)
			(xy 16.505228 -193.808628) (xy 16.481367 -193.889895) (xy 16.449888 -193.968525) (xy 16.411077 -194.043806)
			(xy 16.365287 -194.115058) (xy 16.312931 -194.181634) (xy 16.254483 -194.242932) (xy 16.190473 -194.298397)
			(xy 16.121481 -194.347526) (xy 16.048131 -194.389875) (xy 15.971088 -194.425059) (xy 15.891049 -194.452761)
			(xy 15.80874 -194.472729) (xy 15.724905 -194.484782) (xy 15.640304 -194.488813) (xy 15.555703 -194.484782)
			(xy 15.471868 -194.472729) (xy 15.389559 -194.452761) (xy 15.30952 -194.425059) (xy 15.232477 -194.389875)
			(xy 15.159127 -194.347526) (xy 15.090135 -194.298397) (xy 15.026125 -194.242932) (xy 14.967677 -194.181634)
			(xy 14.915321 -194.115058) (xy 14.869531 -194.043806) (xy 14.83072 -193.968525) (xy 14.799241 -193.889895)
			(xy 14.77538 -193.808628) (xy 14.759351 -193.725462) (xy 14.7513 -193.641148) (xy 6.497164 -193.641148)
			(xy 6.456179 -193.684132) (xy 6.392169 -193.739597) (xy 6.323177 -193.788726) (xy 6.249827 -193.831075)
			(xy 6.172784 -193.866259) (xy 6.092745 -193.893961) (xy 6.010436 -193.913929) (xy 5.926601 -193.925982)
			(xy 5.842 -193.930013) (xy 5.757399 -193.925982) (xy 5.673564 -193.913929) (xy 5.591255 -193.893961)
			(xy 5.511216 -193.866259) (xy 5.434173 -193.831075) (xy 5.360823 -193.788726) (xy 5.291831 -193.739597)
			(xy 5.227821 -193.684132) (xy 5.169373 -193.622834) (xy 5.117017 -193.556258) (xy 5.071227 -193.485006)
			(xy 5.032416 -193.409725) (xy 5.000937 -193.331095) (xy 4.977076 -193.249828) (xy 4.961047 -193.166662)
			(xy 4.952996 -193.082348) (xy 3.920996 -193.082348) (xy 3.970582 -193.091617) (xy 4.049648 -193.114113)
			(xy 4.126302 -193.143809) (xy 4.199889 -193.18045) (xy 4.269781 -193.223725) (xy 4.335381 -193.273265)
			(xy 4.396132 -193.328646) (xy 4.451513 -193.389395) (xy 4.501052 -193.454996) (xy 4.544328 -193.524888)
			(xy 4.58097 -193.598474) (xy 4.610666 -193.675128) (xy 4.633163 -193.754195) (xy 4.648268 -193.835)
			(xy 4.655853 -193.916854) (xy 4.656328 -193.957956) (xy 4.655858 -193.998783) (xy 4.64836 -194.080093)
			(xy 4.633442 -194.160373) (xy 4.61123 -194.238948) (xy 4.58191 -194.315158) (xy 4.54573 -194.388359)
			(xy 4.502994 -194.457937) (xy 4.454062 -194.523306) (xy 4.399344 -194.583915) (xy 4.339303 -194.639255)
			(xy 4.274443 -194.68886) (xy 4.20531 -194.732313) (xy 4.132486 -194.769247) (xy 4.056584 -194.799351)
			(xy 3.978242 -194.822374) (xy 3.93827 -194.8307) (xy 3.928224 -194.833155) (xy 3.91118 -194.844833)
			(xy 3.90525 -194.853306) (xy 3.883068 -194.887355) (xy 3.833408 -194.951686) (xy 3.778088 -195.01122)
			(xy 3.717568 -195.06546) (xy 3.652353 -195.113953) (xy 3.582986 -195.156297) (xy 3.510047 -195.192136)
			(xy 3.434143 -195.221174) (xy 3.355907 -195.243167) (xy 3.27599 -195.257933) (xy 3.19506 -195.265348)
			(xy 3.154426 -195.265802) (xy 3.113324 -195.265327) (xy 3.031469 -195.257742) (xy 2.950664 -195.242637)
			(xy 2.871598 -195.22014) (xy 2.794944 -195.190444) (xy 2.721357 -195.153802) (xy 2.651465 -195.110526)
			(xy 2.585864 -195.060987) (xy 2.525114 -195.005606) (xy 2.469733 -194.944856) (xy 2.420194 -194.879255)
			(xy 2.376918 -194.809363) (xy 2.340276 -194.735776) (xy 2.31058 -194.659122) (xy 2.288083 -194.580056)
			(xy 2.272978 -194.499251) (xy 2.265393 -194.417396) (xy 2.264918 -194.376294) (xy 1.651254 -194.376294)
			(xy 1.651254 -195.700904) (xy 1.652778 -195.75145) (xy 1.651254 -195.801996) (xy 1.651254 -200.780904)
			(xy 1.652778 -200.83145) (xy 1.651254 -200.881996) (xy 1.651254 -205.860904) (xy 1.652778 -205.91145)
			(xy 1.651254 -205.961996) (xy 1.651254 -210.940904) (xy 1.652778 -210.99145) (xy 1.652219 -211.009992)
			(xy 5.378704 -211.009992) (xy 5.379203 -210.958501) (xy 5.387219 -210.855831) (xy 5.403202 -210.754097)
			(xy 5.427055 -210.653915) (xy 5.458633 -210.555893) (xy 5.497745 -210.460627) (xy 5.544153 -210.368694)
			(xy 5.597576 -210.280653) (xy 5.657689 -210.197036) (xy 5.724128 -210.118352) (xy 5.759958 -210.081368)
			(xy 5.767324 -210.074256) (xy 5.77469 -210.055968) (xy 5.77469 -209.96402) (xy 5.767324 -209.945732)
			(xy 5.759958 -209.93862) (xy 5.724127 -209.901637) (xy 5.657687 -209.822953) (xy 5.597573 -209.739337)
			(xy 5.54415 -209.651295) (xy 5.497741 -209.559362) (xy 5.458629 -209.464096) (xy 5.427051 -209.366074)
			(xy 5.403198 -209.265892) (xy 5.387215 -209.164157) (xy 5.379199 -209.061487) (xy 5.379199 -208.958505)
			(xy 5.387215 -208.855835) (xy 5.403198 -208.7541) (xy 5.427051 -208.653918) (xy 5.458629 -208.555896)
			(xy 5.497741 -208.46063) (xy 5.54415 -208.368697) (xy 5.597573 -208.280655) (xy 5.657687 -208.197039)
			(xy 5.724127 -208.118355) (xy 5.759958 -208.081372) (xy 5.767324 -208.07426) (xy 5.77469 -208.055972)
			(xy 5.77469 -207.964024) (xy 5.767324 -207.945736) (xy 5.759958 -207.938624) (xy 5.724127 -207.901641)
			(xy 5.657687 -207.822957) (xy 5.597573 -207.739341) (xy 5.54415 -207.651299) (xy 5.497742 -207.559366)
			(xy 5.45863 -207.4641) (xy 5.427051 -207.366078) (xy 5.403198 -207.265896) (xy 5.387216 -207.164161)
			(xy 5.3792 -207.061491) (xy 5.3792 -206.958509) (xy 5.387216 -206.855839) (xy 5.403198 -206.754104)
			(xy 5.427051 -206.653922) (xy 5.45863 -206.5559) (xy 5.497742 -206.460634) (xy 5.54415 -206.368701)
			(xy 5.597573 -206.280659) (xy 5.657687 -206.197043) (xy 5.724127 -206.118359) (xy 5.759958 -206.081376)
			(xy 5.767324 -206.074264) (xy 5.77469 -206.055976) (xy 5.77469 -205.964028) (xy 5.767324 -205.94574)
			(xy 5.759958 -205.938628) (xy 5.724127 -205.901645) (xy 5.657687 -205.822961) (xy 5.597573 -205.739345)
			(xy 5.54415 -205.651303) (xy 5.497741 -205.55937) (xy 5.458629 -205.464104) (xy 5.427051 -205.366082)
			(xy 5.403198 -205.2659) (xy 5.387215 -205.164165) (xy 5.379199 -205.061495) (xy 5.379199 -204.958513)
			(xy 5.387215 -204.855843) (xy 5.403198 -204.754108) (xy 5.427051 -204.653926) (xy 5.458629 -204.555904)
			(xy 5.497741 -204.460638) (xy 5.54415 -204.368705) (xy 5.597573 -204.280663) (xy 5.657687 -204.197047)
			(xy 5.724127 -204.118363) (xy 5.759958 -204.08138) (xy 5.767324 -204.074268) (xy 5.77469 -204.05598)
			(xy 5.77469 -203.964032) (xy 5.767324 -203.945744) (xy 5.759958 -203.938632) (xy 5.724125 -203.901651)
			(xy 5.657685 -203.822967) (xy 5.597571 -203.73935) (xy 5.544148 -203.651308) (xy 5.49774 -203.559375)
			(xy 5.458628 -203.464109) (xy 5.42705 -203.366087) (xy 5.403197 -203.265905) (xy 5.387214 -203.16417)
			(xy 5.379198 -203.0615) (xy 5.379199 -202.958517) (xy 5.387214 -202.855847) (xy 5.403197 -202.754112)
			(xy 5.42705 -202.65393) (xy 5.458629 -202.555909) (xy 5.497741 -202.460642) (xy 5.54415 -202.368709)
			(xy 5.597573 -202.280667) (xy 5.657687 -202.197051) (xy 5.724127 -202.118367) (xy 5.759958 -202.081384)
			(xy 5.767324 -202.074272) (xy 5.77469 -202.055984) (xy 5.77469 -201.964036) (xy 5.767324 -201.945748)
			(xy 5.759958 -201.938636) (xy 5.724129 -201.901651) (xy 5.657689 -201.822967) (xy 5.597575 -201.739351)
			(xy 5.544152 -201.651309) (xy 5.497743 -201.559377) (xy 5.458631 -201.464111) (xy 5.427053 -201.366089)
			(xy 5.4032 -201.265907) (xy 5.387217 -201.164173) (xy 5.379201 -201.061503) (xy 5.379201 -200.95852)
			(xy 5.387217 -200.85585) (xy 5.4032 -200.754116) (xy 5.427052 -200.653934) (xy 5.45863 -200.555912)
			(xy 5.497742 -200.460646) (xy 5.544151 -200.368713) (xy 5.597574 -200.280671) (xy 5.657688 -200.197055)
			(xy 5.724128 -200.118371) (xy 5.759958 -200.081388) (xy 5.767324 -200.074276) (xy 5.77469 -200.055988)
			(xy 5.77469 -199.96404) (xy 5.767324 -199.945752) (xy 5.759958 -199.93864) (xy 5.724127 -199.901657)
			(xy 5.657687 -199.822973) (xy 5.597573 -199.739357) (xy 5.54415 -199.651315) (xy 5.497741 -199.559382)
			(xy 5.458629 -199.464116) (xy 5.427051 -199.366094) (xy 5.403198 -199.265912) (xy 5.387215 -199.164177)
			(xy 5.379199 -199.061507) (xy 5.379199 -198.958525) (xy 5.387215 -198.855855) (xy 5.403198 -198.75412)
			(xy 5.427051 -198.653938) (xy 5.458629 -198.555916) (xy 5.497741 -198.46065) (xy 5.54415 -198.368717)
			(xy 5.597573 -198.280675) (xy 5.657687 -198.197059) (xy 5.724127 -198.118375) (xy 5.759958 -198.081392)
			(xy 5.767324 -198.07428) (xy 5.77469 -198.055992) (xy 5.77469 -197.964044) (xy 5.767324 -197.945756)
			(xy 5.759958 -197.938644) (xy 5.724129 -197.901659) (xy 5.657688 -197.822976) (xy 5.597574 -197.73936)
			(xy 5.54415 -197.651318) (xy 5.49774 -197.559386) (xy 5.458628 -197.46412) (xy 5.427049 -197.366098)
			(xy 5.403196 -197.265916) (xy 5.387213 -197.164181) (xy 5.379197 -197.061511) (xy 5.378704 -197.01002)
			(xy 5.379168 -196.959201) (xy 5.386976 -196.857862) (xy 5.402548 -196.757423) (xy 5.425791 -196.658477)
			(xy 5.456568 -196.56161) (xy 5.494697 -196.467394) (xy 5.539952 -196.376386) (xy 5.592067 -196.289125)
			(xy 5.650732 -196.206126) (xy 5.715601 -196.12788) (xy 5.786291 -196.054849) (xy 5.862383 -195.987466)
			(xy 5.943428 -195.926129) (xy 6.028946 -195.871201) (xy 6.118431 -195.823006) (xy 6.211356 -195.781829)
			(xy 6.307169 -195.747914) (xy 6.405306 -195.721461) (xy 6.455156 -195.711572) (xy 6.466586 -195.70954)
			(xy 6.484874 -195.696332) (xy 6.533642 -195.607432) (xy 6.535166 -195.584826) (xy 6.530848 -195.574158)
			(xy 6.512841 -195.527477) (xy 6.483432 -195.431834) (xy 6.461716 -195.334157) (xy 6.447829 -195.235063)
			(xy 6.441858 -195.135179) (xy 6.443843 -195.035136) (xy 6.453771 -194.935568) (xy 6.471577 -194.837103)
			(xy 6.497151 -194.740364) (xy 6.53033 -194.645962) (xy 6.570905 -194.554496) (xy 6.618619 -194.466542)
			(xy 6.67317 -194.382657) (xy 6.734213 -194.303372) (xy 6.801363 -194.229187) (xy 6.874194 -194.160572)
			(xy 6.952248 -194.097961) (xy 7.035028 -194.041749) (xy 7.122014 -193.992292) (xy 7.212654 -193.949903)
			(xy 7.306375 -193.914849) (xy 7.402585 -193.887352) (xy 7.500676 -193.867586) (xy 7.600027 -193.855677)
			(xy 7.70001 -193.851699) (xy 7.799993 -193.855677) (xy 7.899344 -193.867586) (xy 7.997435 -193.887352)
			(xy 8.093645 -193.914849) (xy 8.187366 -193.949903) (xy 8.278006 -193.992292) (xy 8.364992 -194.041749)
			(xy 8.447772 -194.097961) (xy 8.525826 -194.160572) (xy 8.598657 -194.229187) (xy 8.665807 -194.303372)
			(xy 8.72685 -194.382657) (xy 8.781401 -194.466542) (xy 8.829115 -194.554496) (xy 8.86969 -194.645962)
			(xy 8.902869 -194.740364) (xy 8.928443 -194.837103) (xy 8.946249 -194.935568) (xy 8.956177 -195.035136)
			(xy 8.958162 -195.135179) (xy 8.952191 -195.235063) (xy 8.938304 -195.334157) (xy 8.916588 -195.431834)
			(xy 8.887179 -195.527477) (xy 8.869172 -195.574158) (xy 8.864854 -195.584826) (xy 8.866378 -195.607432)
			(xy 8.915146 -195.696332) (xy 8.933434 -195.70954) (xy 8.944864 -195.711572) (xy 8.994714 -195.721461)
			(xy 9.092847 -195.747917) (xy 9.188658 -195.781836) (xy 9.28158 -195.823015) (xy 9.371063 -195.871212)
			(xy 9.456579 -195.926142) (xy 9.537621 -195.98748) (xy 9.613711 -196.054863) (xy 9.684399 -196.127893)
			(xy 9.749266 -196.206139) (xy 9.80793 -196.289137) (xy 9.860044 -196.376397) (xy 9.905299 -196.467403)
			(xy 9.943429 -196.561618) (xy 9.974206 -196.658483) (xy 9.997451 -196.757427) (xy 10.013024 -196.857864)
			(xy 10.020835 -196.959201) (xy 10.021316 -197.01002) (xy 10.020899 -197.0532) (xy 14.012912 -197.0532)
			(xy 14.016942 -196.968597) (xy 14.028996 -196.884761) (xy 14.048964 -196.80245) (xy 14.076667 -196.72241)
			(xy 14.111852 -196.645365) (xy 14.154201 -196.572014) (xy 14.203331 -196.503021) (xy 14.258797 -196.43901)
			(xy 14.320096 -196.380561) (xy 14.386674 -196.328204) (xy 14.457927 -196.282412) (xy 14.53321 -196.243601)
			(xy 14.611842 -196.212122) (xy 14.69311 -196.18826) (xy 14.776278 -196.172231) (xy 14.860593 -196.16418)
			(xy 14.902942 -196.163692) (xy 14.945638 -196.164214) (xy 15.030639 -196.172383) (xy 15.114465 -196.188662)
			(xy 15.196346 -196.2129) (xy 15.275526 -196.244875) (xy 15.351277 -196.284292) (xy 15.422901 -196.330787)
			(xy 15.489739 -196.383934) (xy 15.551175 -196.443242) (xy 15.606644 -196.508165) (xy 15.655635 -196.578106)
			(xy 15.697697 -196.652421) (xy 15.732443 -196.730425) (xy 15.746476 -196.770752) (xy 15.751556 -196.786246)
			(xy 15.776956 -196.805042) (xy 15.904718 -196.808344) (xy 15.931134 -196.791072) (xy 15.93723 -196.776086)
			(xy 15.953752 -196.735922) (xy 15.993459 -196.658678) (xy 16.04051 -196.585675) (xy 16.094455 -196.517608)
			(xy 16.154781 -196.455127) (xy 16.220913 -196.398826) (xy 16.292221 -196.349242) (xy 16.368023 -196.306849)
			(xy 16.447599 -196.27205) (xy 16.530189 -196.245178) (xy 16.572484 -196.23532) (xy 16.582136 -196.233288)
			(xy 16.598138 -196.222366) (xy 16.64843 -196.146928) (xy 16.65224 -196.128132) (xy 16.650462 -196.118226)
			(xy 16.643906 -196.079251) (xy 16.63691 -196.00052) (xy 16.636492 -195.961) (xy 16.636959 -195.920642)
			(xy 16.644272 -195.840258) (xy 16.658838 -195.760868) (xy 16.680537 -195.683124) (xy 16.709191 -195.607665)
			(xy 16.744563 -195.535113) (xy 16.786364 -195.466064) (xy 16.834249 -195.401087) (xy 16.887823 -195.340715)
			(xy 16.946648 -195.285445) (xy 17.010238 -195.235733) (xy 17.043908 -195.213478) (xy 17.055338 -195.206112)
			(xy 17.06753 -195.182236) (xy 17.06245 -195.067174) (xy 17.047972 -195.044568) (xy 17.03578 -195.038218)
			(xy 16.997032 -195.017309) (xy 16.923435 -194.968967) (xy 16.854976 -194.91359) (xy 16.792323 -194.85172)
			(xy 16.736089 -194.783962) (xy 16.686826 -194.710979) (xy 16.645015 -194.633486) (xy 16.611065 -194.552241)
			(xy 16.585308 -194.46804) (xy 16.567998 -194.381705) (xy 16.559302 -194.294083) (xy 16.558768 -194.250056)
			(xy 16.559272 -194.207708) (xy 16.567323 -194.123394) (xy 16.583352 -194.040228) (xy 16.607213 -193.958961)
			(xy 16.638692 -193.880331) (xy 16.677503 -193.80505) (xy 16.723293 -193.733798) (xy 16.775649 -193.667222)
			(xy 16.834097 -193.605924) (xy 16.898107 -193.550459) (xy 16.967099 -193.50133) (xy 17.040449 -193.458981)
			(xy 17.117492 -193.423797) (xy 17.197531 -193.396095) (xy 17.27984 -193.376127) (xy 17.363675 -193.364074)
			(xy 17.448276 -193.360044) (xy 17.532877 -193.364074) (xy 17.616712 -193.376127) (xy 17.699021 -193.396095)
			(xy 17.77906 -193.423797) (xy 17.856103 -193.458981) (xy 17.929453 -193.50133) (xy 17.998445 -193.550459)
			(xy 18.062455 -193.605924) (xy 18.120903 -193.667222) (xy 18.173259 -193.733798) (xy 18.219049 -193.80505)
			(xy 18.25786 -193.880331) (xy 18.289339 -193.958961) (xy 18.3132 -194.040228) (xy 18.329229 -194.123394)
			(xy 18.33728 -194.207708) (xy 18.337784 -194.250056) (xy 18.337327 -194.290414) (xy 18.337146 -194.292404)
			(xy 18.87626 -194.292404) (xy 18.87626 -194.207708) (xy 18.884311 -194.123394) (xy 18.90034 -194.040228)
			(xy 18.924201 -193.958961) (xy 18.95568 -193.880331) (xy 18.994491 -193.80505) (xy 19.040281 -193.733798)
			(xy 19.092637 -193.667222) (xy 19.151085 -193.605924) (xy 19.215095 -193.550459) (xy 19.284087 -193.50133)
			(xy 19.357437 -193.458981) (xy 19.43448 -193.423797) (xy 19.514519 -193.396095) (xy 19.596828 -193.376127)
			(xy 19.680663 -193.364074) (xy 19.765264 -193.360044) (xy 19.849865 -193.364074) (xy 19.9337 -193.376127)
			(xy 20.016009 -193.396095) (xy 20.096048 -193.423797) (xy 20.173091 -193.458981) (xy 20.246441 -193.50133)
			(xy 20.315433 -193.550459) (xy 20.379443 -193.605924) (xy 20.437891 -193.667222) (xy 20.490247 -193.733798)
			(xy 20.536037 -193.80505) (xy 20.574848 -193.880331) (xy 20.606327 -193.958961) (xy 20.630188 -194.040228)
			(xy 20.646217 -194.123394) (xy 20.654268 -194.207708) (xy 20.654772 -194.250056) (xy 20.654268 -194.292404)
			(xy 20.646217 -194.376718) (xy 20.630188 -194.459884) (xy 20.606327 -194.541151) (xy 20.574848 -194.619781)
			(xy 20.536037 -194.695062) (xy 20.490247 -194.766314) (xy 20.437891 -194.83289) (xy 20.379443 -194.894188)
			(xy 20.315433 -194.949653) (xy 20.246441 -194.998782) (xy 20.173091 -195.041131) (xy 20.096048 -195.076315)
			(xy 20.016009 -195.104017) (xy 19.9337 -195.123985) (xy 19.849865 -195.136038) (xy 19.765264 -195.140069)
			(xy 19.680663 -195.136038) (xy 19.596828 -195.123985) (xy 19.514519 -195.104017) (xy 19.43448 -195.076315)
			(xy 19.357437 -195.041131) (xy 19.284087 -194.998782) (xy 19.215095 -194.949653) (xy 19.151085 -194.894188)
			(xy 19.092637 -194.83289) (xy 19.040281 -194.766314) (xy 18.994491 -194.695062) (xy 18.95568 -194.619781)
			(xy 18.924201 -194.541151) (xy 18.90034 -194.459884) (xy 18.884311 -194.376718) (xy 18.87626 -194.292404)
			(xy 18.337146 -194.292404) (xy 18.33001 -194.370797) (xy 18.31544 -194.450187) (xy 18.293738 -194.52793)
			(xy 18.265083 -194.603388) (xy 18.229709 -194.675939) (xy 18.187908 -194.744987) (xy 18.140023 -194.809965)
			(xy 18.086449 -194.870337) (xy 18.027626 -194.925608) (xy 17.964037 -194.975322) (xy 17.930368 -194.997578)
			(xy 17.918938 -195.004944) (xy 17.906746 -195.02882) (xy 17.911826 -195.143882) (xy 17.926304 -195.166488)
			(xy 17.938496 -195.172838) (xy 17.977262 -195.193716) (xy 18.05086 -195.24206) (xy 18.11932 -195.297439)
			(xy 18.181974 -195.359312) (xy 18.238207 -195.427073) (xy 18.287469 -195.500059) (xy 18.329279 -195.577556)
			(xy 18.363226 -195.658804) (xy 18.388979 -195.743009) (xy 18.406286 -195.829347) (xy 18.414977 -195.916972)
			(xy 18.415508 -195.961) (xy 18.414945 -196.004017) (xy 18.406647 -196.089649) (xy 18.39012 -196.17408)
			(xy 18.365518 -196.25652) (xy 18.333071 -196.3362) (xy 18.293082 -196.412375) (xy 18.245925 -196.484332)
			(xy 18.19204 -196.5514) (xy 18.131932 -196.612952) (xy 18.06616 -196.668412) (xy 17.995342 -196.717263)
			(xy 17.920137 -196.759048) (xy 17.841249 -196.793375) (xy 17.759415 -196.819926) (xy 17.717516 -196.82968)
			(xy 17.707864 -196.831712) (xy 17.691862 -196.842634) (xy 17.658719 -196.892348) (xy 18.770596 -196.892348)
			(xy 18.770596 -196.807652) (xy 18.778647 -196.723338) (xy 18.794676 -196.640172) (xy 18.818537 -196.558905)
			(xy 18.850016 -196.480275) (xy 18.888827 -196.404994) (xy 18.934617 -196.333742) (xy 18.986973 -196.267166)
			(xy 19.045421 -196.205868) (xy 19.109431 -196.150403) (xy 19.178423 -196.101274) (xy 19.251773 -196.058925)
			(xy 19.328816 -196.023741) (xy 19.408855 -195.996039) (xy 19.491164 -195.976071) (xy 19.574999 -195.964018)
			(xy 19.6596 -195.959988) (xy 19.744201 -195.964018) (xy 19.828036 -195.976071) (xy 19.910345 -195.996039)
			(xy 19.990384 -196.023741) (xy 20.067427 -196.058925) (xy 20.140777 -196.101274) (xy 20.209769 -196.150403)
			(xy 20.273779 -196.205868) (xy 20.332227 -196.267166) (xy 20.384583 -196.333742) (xy 20.430373 -196.404994)
			(xy 20.469184 -196.480275) (xy 20.500663 -196.558905) (xy 20.524524 -196.640172) (xy 20.540553 -196.723338)
			(xy 20.548604 -196.807652) (xy 20.549108 -196.85) (xy 20.548604 -196.892348) (xy 20.540553 -196.976662)
			(xy 20.524524 -197.059828) (xy 20.511256 -197.105016) (xy 26.381202 -197.105016) (xy 26.381706 -197.062668)
			(xy 26.389757 -196.978354) (xy 26.405786 -196.895188) (xy 26.429647 -196.813921) (xy 26.461126 -196.735291)
			(xy 26.499937 -196.66001) (xy 26.545727 -196.588758) (xy 26.598083 -196.522182) (xy 26.656531 -196.460884)
			(xy 26.720541 -196.405419) (xy 26.789533 -196.35629) (xy 26.862883 -196.313941) (xy 26.939926 -196.278757)
			(xy 27.019965 -196.251055) (xy 27.102274 -196.231087) (xy 27.186109 -196.219034) (xy 27.27071 -196.215004)
			(xy 27.355311 -196.219034) (xy 27.439146 -196.231087) (xy 27.521455 -196.251055) (xy 27.601494 -196.278757)
			(xy 27.678537 -196.313941) (xy 27.751887 -196.35629) (xy 27.820879 -196.405419) (xy 27.884889 -196.460884)
			(xy 27.943337 -196.522182) (xy 27.995693 -196.588758) (xy 28.041483 -196.66001) (xy 28.080294 -196.735291)
			(xy 28.111773 -196.813921) (xy 28.135634 -196.895188) (xy 28.151663 -196.978354) (xy 28.159714 -197.062668)
			(xy 28.160106 -197.095618) (xy 30.058106 -197.095618) (xy 30.058668 -197.052544) (xy 30.067005 -196.966801)
			(xy 30.083591 -196.882265) (xy 30.108271 -196.799728) (xy 30.140816 -196.719965) (xy 30.180919 -196.64372)
			(xy 30.228204 -196.57171) (xy 30.28223 -196.504608) (xy 30.34249 -196.443044) (xy 30.408419 -196.387593)
			(xy 30.4794 -196.338776) (xy 30.554767 -196.297049) (xy 30.633816 -196.262804) (xy 30.715805 -196.236361)
			(xy 30.799966 -196.217968) (xy 30.885511 -196.207797) (xy 30.928564 -196.206364) (xy 30.93847 -196.20611)
			(xy 30.955996 -196.198744) (xy 31.019496 -196.137276) (xy 31.02737 -196.120004) (xy 31.027878 -196.110352)
			(xy 31.030745 -196.068307) (xy 31.043338 -195.984976) (xy 31.063756 -195.903209) (xy 31.091814 -195.82374)
			(xy 31.127263 -195.74728) (xy 31.169784 -195.674516) (xy 31.218996 -195.606099) (xy 31.274458 -195.542642)
			(xy 31.335672 -195.484716) (xy 31.40209 -195.432838) (xy 31.473117 -195.387474) (xy 31.548116 -195.349031)
			(xy 31.626414 -195.317852) (xy 31.70731 -195.294219) (xy 31.790078 -195.278342) (xy 31.873977 -195.270363)
			(xy 31.916116 -195.269866) (xy 31.957218 -195.270351) (xy 32.039071 -195.277937) (xy 32.119875 -195.293043)
			(xy 32.198941 -195.31554) (xy 32.275594 -195.345236) (xy 32.34918 -195.381878) (xy 32.419071 -195.425153)
			(xy 32.484671 -195.474692) (xy 32.545421 -195.530072) (xy 32.600802 -195.590821) (xy 32.650341 -195.656421)
			(xy 32.693617 -195.726312) (xy 32.73026 -195.799897) (xy 32.759957 -195.876549) (xy 32.782454 -195.955615)
			(xy 32.797561 -196.036419) (xy 32.805148 -196.118272) (xy 32.805624 -196.159374) (xy 32.80523 -196.198136)
			(xy 32.798497 -196.275367) (xy 32.785062 -196.351718) (xy 32.765028 -196.426608) (xy 32.738547 -196.499469)
			(xy 32.722566 -196.534786) (xy 32.71647 -196.547486) (xy 32.719264 -196.574918) (xy 32.788606 -196.669406)
			(xy 32.814006 -196.680328) (xy 32.827976 -196.678296) (xy 32.857115 -196.674696) (xy 32.91571 -196.670879)
			(xy 32.94507 -196.670676) (xy 32.983563 -196.671066) (xy 33.060265 -196.677685) (xy 33.136105 -196.690917)
			(xy 33.173416 -196.700394) (xy 33.184467 -196.702674) (xy 33.206622 -196.698558) (xy 33.224876 -196.685346)
			(xy 33.23082 -196.675756) (xy 33.2521 -196.638139) (xy 33.30087 -196.566781) (xy 33.35633 -196.50049)
			(xy 33.417957 -196.439888) (xy 33.485171 -196.385549) (xy 33.557337 -196.337984) (xy 33.633775 -196.29764)
			(xy 33.713766 -196.2649) (xy 33.796554 -196.240071) (xy 33.88136 -196.223387) (xy 33.967384 -196.215005)
			(xy 34.0106 -196.214492) (xy 34.052948 -196.214996) (xy 34.137262 -196.223047) (xy 34.220428 -196.239076)
			(xy 34.301695 -196.262937) (xy 34.380325 -196.294416) (xy 34.455606 -196.333227) (xy 34.526858 -196.379017)
			(xy 34.593434 -196.431373) (xy 34.654732 -196.489821) (xy 34.710197 -196.553831) (xy 34.759326 -196.622823)
			(xy 34.801675 -196.696173) (xy 34.836859 -196.773216) (xy 34.864561 -196.853255) (xy 34.884529 -196.935564)
			(xy 34.896582 -197.019399) (xy 34.900613 -197.104) (xy 34.896582 -197.188601) (xy 34.884529 -197.272436)
			(xy 34.864561 -197.354745) (xy 34.836859 -197.434784) (xy 34.801675 -197.511827) (xy 34.759326 -197.585177)
			(xy 34.710197 -197.654169) (xy 34.654732 -197.718179) (xy 34.593434 -197.776627) (xy 34.526858 -197.828983)
			(xy 34.455606 -197.874773) (xy 34.380325 -197.913584) (xy 34.301695 -197.945063) (xy 34.220428 -197.968924)
			(xy 34.137262 -197.984953) (xy 34.052948 -197.993004) (xy 34.0106 -197.993508) (xy 33.972106 -197.993125)
			(xy 33.895405 -197.986504) (xy 33.819565 -197.973268) (xy 33.782254 -197.96379) (xy 33.771206 -197.96149)
			(xy 33.749049 -197.965617) (xy 33.730794 -197.978835) (xy 33.72485 -197.988428) (xy 33.705506 -198.022718)
			(xy 33.661624 -198.08809) (xy 33.63722 -198.118984) (xy 33.631399 -198.126827) (xy 33.625697 -198.145494)
			(xy 33.627367 -198.16494) (xy 33.631378 -198.173848) (xy 33.649885 -198.211376) (xy 33.680612 -198.289212)
			(xy 33.703902 -198.369588) (xy 33.719548 -198.451794) (xy 33.727413 -198.535105) (xy 33.727898 -198.576946)
			(xy 33.727363 -198.619692) (xy 33.719166 -198.704789) (xy 33.702841 -198.788707) (xy 33.67854 -198.870672)
			(xy 33.646487 -198.949927) (xy 33.606977 -199.025741) (xy 33.560375 -199.097414) (xy 33.507111 -199.164285)
			(xy 33.447677 -199.225737) (xy 33.415478 -199.253856) (xy 33.408964 -199.259943) (xy 33.400204 -199.275453)
			(xy 33.397287 -199.293026) (xy 33.400565 -199.310535) (xy 33.40481 -199.318372) (xy 33.423988 -199.351672)
			(xy 33.457183 -199.420984) (xy 33.471104 -199.456802) (xy 33.475643 -199.46708) (xy 33.491749 -199.4827)
			(xy 33.512976 -199.489966) (xy 33.52419 -199.489314) (xy 33.548559 -199.486804) (xy 33.597482 -199.484135)
			(xy 33.62198 -199.48398) (xy 33.663082 -199.484471) (xy 33.744937 -199.492054) (xy 33.825743 -199.507158)
			(xy 33.90481 -199.529653) (xy 33.981464 -199.559347) (xy 34.055052 -199.595987) (xy 34.093626 -199.61987)
			(xy 34.581592 -199.61987) (xy 34.582096 -199.577522) (xy 34.590147 -199.493208) (xy 34.606176 -199.410042)
			(xy 34.630037 -199.328775) (xy 34.661516 -199.250145) (xy 34.700327 -199.174864) (xy 34.746117 -199.103612)
			(xy 34.798473 -199.037036) (xy 34.856921 -198.975738) (xy 34.920931 -198.920273) (xy 34.989923 -198.871144)
			(xy 35.063273 -198.828795) (xy 35.140316 -198.793611) (xy 35.220355 -198.765909) (xy 35.302664 -198.745941)
			(xy 35.386499 -198.733888) (xy 35.4711 -198.729858) (xy 35.555701 -198.733888) (xy 35.639536 -198.745941)
			(xy 35.721845 -198.765909) (xy 35.801884 -198.793611) (xy 35.878927 -198.828795) (xy 35.952277 -198.871144)
			(xy 36.021269 -198.920273) (xy 36.085279 -198.975738) (xy 36.143727 -199.037036) (xy 36.196083 -199.103612)
			(xy 36.241873 -199.174864) (xy 36.280684 -199.250145) (xy 36.312163 -199.328775) (xy 36.336024 -199.410042)
			(xy 36.352053 -199.493208) (xy 36.360104 -199.577522) (xy 36.360608 -199.61987) (xy 36.360145 -199.660404)
			(xy 36.352769 -199.741136) (xy 36.338085 -199.820863) (xy 36.316214 -199.898925) (xy 36.287338 -199.974675)
			(xy 36.26993 -200.011284) (xy 36.264342 -200.022206) (xy 36.265104 -200.047098) (xy 36.317174 -200.141586)
			(xy 36.337748 -200.155556) (xy 36.34994 -200.156826) (xy 36.392953 -200.162118) (xy 36.477771 -200.179926)
			(xy 36.560454 -200.2059) (xy 36.64022 -200.239793) (xy 36.71631 -200.281283) (xy 36.788005 -200.329977)
			(xy 36.854623 -200.385414) (xy 36.915534 -200.447067) (xy 36.970159 -200.514353) (xy 37.01798 -200.586632)
			(xy 37.058545 -200.66322) (xy 37.091469 -200.74339) (xy 37.116438 -200.826382) (xy 37.133217 -200.91141)
			(xy 37.141647 -200.997666) (xy 37.142166 -201.041) (xy 37.141662 -201.083348) (xy 37.133611 -201.167662)
			(xy 37.117582 -201.250828) (xy 37.093721 -201.332095) (xy 37.062242 -201.410725) (xy 37.023431 -201.486006)
			(xy 36.977641 -201.557258) (xy 36.925285 -201.623834) (xy 36.866837 -201.685132) (xy 36.802827 -201.740597)
			(xy 36.733835 -201.789726) (xy 36.660485 -201.832075) (xy 36.583442 -201.867259) (xy 36.503403 -201.894961)
			(xy 36.421094 -201.914929) (xy 36.337259 -201.926982) (xy 36.252658 -201.931013) (xy 36.168057 -201.926982)
			(xy 36.084222 -201.914929) (xy 36.001913 -201.894961) (xy 35.921874 -201.867259) (xy 35.844831 -201.832075)
			(xy 35.771481 -201.789726) (xy 35.702489 -201.740597) (xy 35.638479 -201.685132) (xy 35.580031 -201.623834)
			(xy 35.527675 -201.557258) (xy 35.481885 -201.486006) (xy 35.443074 -201.410725) (xy 35.411595 -201.332095)
			(xy 35.387734 -201.250828) (xy 35.371705 -201.167662) (xy 35.363654 -201.083348) (xy 35.36315 -201.041)
			(xy 35.363605 -201.000466) (xy 35.370984 -200.919734) (xy 35.38567 -200.840007) (xy 35.407542 -200.761945)
			(xy 35.43642 -200.686195) (xy 35.453828 -200.649586) (xy 35.459416 -200.638664) (xy 35.458654 -200.613772)
			(xy 35.406584 -200.519284) (xy 35.38601 -200.505314) (xy 35.373818 -200.504044) (xy 35.330796 -200.498816)
			(xy 35.245976 -200.481003) (xy 35.163291 -200.455024) (xy 35.083525 -200.421127) (xy 35.007433 -200.379632)
			(xy 34.935738 -200.330932) (xy 34.86912 -200.275491) (xy 34.80821 -200.213833) (xy 34.753586 -200.146543)
			(xy 34.705765 -200.074259) (xy 34.665202 -199.997667) (xy 34.632281 -199.917492) (xy 34.607313 -199.834496)
			(xy 34.590536 -199.749465) (xy 34.58211 -199.663205) (xy 34.581592 -199.61987) (xy 34.093626 -199.61987)
			(xy 34.124945 -199.639261) (xy 34.190547 -199.6888) (xy 34.251298 -199.74418) (xy 34.30668 -199.804929)
			(xy 34.356221 -199.870529) (xy 34.399497 -199.94042) (xy 34.43614 -200.014006) (xy 34.465837 -200.09066)
			(xy 34.488335 -200.169726) (xy 34.503441 -200.250531) (xy 34.511027 -200.332386) (xy 34.511488 -200.373488)
			(xy 34.511023 -200.413879) (xy 34.503691 -200.494328) (xy 34.489096 -200.57378) (xy 34.467359 -200.651583)
			(xy 34.438657 -200.727094) (xy 34.403228 -200.799692) (xy 34.361363 -200.86878) (xy 34.337752 -200.901554)
			(xy 34.331865 -200.91053) (xy 34.32732 -200.931482) (xy 34.331687 -200.952472) (xy 34.337498 -200.961498)
			(xy 34.360505 -200.994009) (xy 34.401248 -201.062451) (xy 34.435707 -201.134263) (xy 34.463606 -201.208869)
			(xy 34.484721 -201.285671) (xy 34.498883 -201.364053) (xy 34.505978 -201.443388) (xy 34.506408 -201.483214)
			(xy 34.505947 -201.524317) (xy 34.498361 -201.606171) (xy 34.483254 -201.686977) (xy 34.460757 -201.766044)
			(xy 34.43106 -201.842698) (xy 34.394417 -201.916285) (xy 34.35114 -201.986177) (xy 34.3016 -202.051778)
			(xy 34.246218 -202.112528) (xy 34.185467 -202.167909) (xy 34.119865 -202.217448) (xy 34.049973 -202.260724)
			(xy 33.976385 -202.297365) (xy 33.899731 -202.327061) (xy 33.820663 -202.349557) (xy 33.739858 -202.364662)
			(xy 33.658003 -202.372247) (xy 33.6169 -202.372722) (xy 33.575164 -202.372253) (xy 33.492059 -202.364442)
			(xy 33.410052 -202.348879) (xy 33.329863 -202.3257) (xy 33.252199 -202.295111) (xy 33.177742 -202.257379)
			(xy 33.107148 -202.212838) (xy 33.041038 -202.161878) (xy 32.979993 -202.104949) (xy 32.92455 -202.04255)
			(xy 32.875197 -201.975232) (xy 32.853376 -201.939652) (xy 32.847675 -201.931032) (xy 32.83093 -201.918945)
			(xy 32.810787 -201.914389) (xy 32.800544 -201.915776) (xy 32.760517 -201.922691) (xy 32.679618 -201.930067)
			(xy 32.639 -201.930508) (xy 32.597898 -201.930033) (xy 32.516043 -201.922448) (xy 32.435238 -201.907343)
			(xy 32.356171 -201.884847) (xy 32.279517 -201.855151) (xy 32.20593 -201.818509) (xy 32.136038 -201.775234)
			(xy 32.070437 -201.725694) (xy 32.009687 -201.670313) (xy 31.954306 -201.609563) (xy 31.904766 -201.543962)
			(xy 31.861491 -201.47407) (xy 31.824849 -201.400483) (xy 31.795153 -201.323829) (xy 31.772657 -201.244762)
			(xy 31.757552 -201.163957) (xy 31.749967 -201.082102) (xy 31.749492 -201.041) (xy 31.749913 -201.000946)
			(xy 31.757124 -200.921165) (xy 31.771479 -200.842354) (xy 31.792862 -200.765153) (xy 31.821098 -200.690188)
			(xy 31.855961 -200.618064) (xy 31.897167 -200.549368) (xy 31.944382 -200.484654) (xy 31.970472 -200.45426)
			(xy 31.976157 -200.44714) (xy 31.982541 -200.430089) (xy 31.982918 -200.420986) (xy 31.982918 -200.391014)
			(xy 31.982534 -200.381912) (xy 31.976154 -200.364861) (xy 31.970472 -200.35774) (xy 31.944386 -200.327343)
			(xy 31.897168 -200.262632) (xy 31.855961 -200.193936) (xy 31.821099 -200.121813) (xy 31.792865 -200.046847)
			(xy 31.771486 -199.969646) (xy 31.757136 -199.890835) (xy 31.749932 -199.811053) (xy 31.749492 -199.771)
			(xy 31.749992 -199.728254) (xy 31.758194 -199.643155) (xy 31.774524 -199.559236) (xy 31.79883 -199.477271)
			(xy 31.830887 -199.398016) (xy 31.870401 -199.322203) (xy 31.917007 -199.25053) (xy 31.970274 -199.18366)
			(xy 32.029711 -199.122208) (xy 32.061912 -199.09409) (xy 32.06847 -199.088045) (xy 32.077226 -199.072518)
			(xy 32.080132 -199.054931) (xy 32.076836 -199.037413) (xy 32.07258 -199.029574) (xy 32.052837 -198.995272)
			(xy 32.018797 -198.923813) (xy 31.991234 -198.849615) (xy 31.970367 -198.773263) (xy 31.956358 -198.69536)
			(xy 31.949319 -198.616522) (xy 31.948882 -198.576946) (xy 31.949407 -198.533782) (xy 31.957764 -198.447861)
			(xy 31.974404 -198.363152) (xy 31.99917 -198.280454) (xy 32.03183 -198.200543) (xy 32.072076 -198.124171)
			(xy 32.119529 -198.052056) (xy 32.14624 -198.018146) (xy 32.152038 -198.010289) (xy 32.157741 -197.99163)
			(xy 32.156084 -197.97219) (xy 32.152082 -197.963282) (xy 32.133553 -197.925764) (xy 32.10283 -197.847925)
			(xy 32.079544 -197.767547) (xy 32.063903 -197.685339) (xy 32.056044 -197.602025) (xy 32.055562 -197.560184)
			(xy 32.055979 -197.521422) (xy 32.062707 -197.444192) (xy 32.076137 -197.367842) (xy 32.096165 -197.292951)
			(xy 32.122641 -197.220089) (xy 32.13862 -197.184772) (xy 32.144716 -197.172072) (xy 32.141922 -197.14464)
			(xy 32.07258 -197.050152) (xy 32.04718 -197.03923) (xy 32.03321 -197.041262) (xy 32.008802 -197.044289)
			(xy 31.959752 -197.047975) (xy 31.935166 -197.048628) (xy 31.92526 -197.048882) (xy 31.907734 -197.056248)
			(xy 31.844234 -197.117716) (xy 31.83636 -197.134988) (xy 31.835852 -197.14464) (xy 31.833047 -197.18669)
			(xy 31.820454 -197.270025) (xy 31.800035 -197.351796) (xy 31.771974 -197.431268) (xy 31.736522 -197.507731)
			(xy 31.693998 -197.580498) (xy 31.644782 -197.648917) (xy 31.589315 -197.712374) (xy 31.528096 -197.770301)
			(xy 31.461673 -197.822179) (xy 31.39064 -197.867541) (xy 31.315636 -197.905982) (xy 31.237333 -197.937158)
			(xy 31.156431 -197.960787) (xy 31.073658 -197.976659) (xy 30.989755 -197.984632) (xy 30.947614 -197.985126)
			(xy 30.906512 -197.98462) (xy 30.824659 -197.977037) (xy 30.743855 -197.961933) (xy 30.66479 -197.939438)
			(xy 30.588137 -197.909744) (xy 30.51455 -197.873104) (xy 30.444659 -197.829831) (xy 30.379058 -197.780293)
			(xy 30.318308 -197.724914) (xy 30.262927 -197.664166) (xy 30.213387 -197.598567) (xy 30.170111 -197.528678)
			(xy 30.133469 -197.455093) (xy 30.103772 -197.378441) (xy 30.081274 -197.299376) (xy 30.066168 -197.218572)
			(xy 30.058581 -197.13672) (xy 30.058106 -197.095618) (xy 28.160106 -197.095618) (xy 28.160218 -197.105016)
			(xy 28.159685 -197.148165) (xy 28.151328 -197.234059) (xy 28.134695 -197.31874) (xy 28.109941 -197.401412)
			(xy 28.0773 -197.4813) (xy 28.037078 -197.557653) (xy 27.989653 -197.629752) (xy 27.935471 -197.696922)
			(xy 27.875039 -197.75853) (xy 27.808927 -197.813998) (xy 27.77363 -197.838822) (xy 27.762708 -197.846188)
			(xy 27.751278 -197.868794) (xy 27.753564 -197.979538) (xy 27.76601 -198.00189) (xy 27.776932 -198.008748)
			(xy 27.811372 -198.030819) (xy 27.87644 -198.080398) (xy 27.936679 -198.135744) (xy 27.991581 -198.196389)
			(xy 28.040681 -198.26182) (xy 28.083565 -198.331483) (xy 28.119869 -198.404791) (xy 28.149288 -198.481123)
			(xy 28.171572 -198.559834) (xy 28.186532 -198.640259) (xy 28.194043 -198.721718) (xy 28.194508 -198.76262)
			(xy 28.194004 -198.804968) (xy 28.185953 -198.889282) (xy 28.169924 -198.972448) (xy 28.146063 -199.053715)
			(xy 28.114584 -199.132345) (xy 28.075773 -199.207626) (xy 28.029983 -199.278878) (xy 27.977627 -199.345454)
			(xy 27.919179 -199.406752) (xy 27.855169 -199.462217) (xy 27.786177 -199.511346) (xy 27.712827 -199.553695)
			(xy 27.635784 -199.588879) (xy 27.555745 -199.616581) (xy 27.473436 -199.636549) (xy 27.389601 -199.648602)
			(xy 27.305 -199.652633) (xy 27.220399 -199.648602) (xy 27.136564 -199.636549) (xy 27.054255 -199.616581)
			(xy 26.974216 -199.588879) (xy 26.897173 -199.553695) (xy 26.823823 -199.511346) (xy 26.754831 -199.462217)
			(xy 26.690821 -199.406752) (xy 26.632373 -199.345454) (xy 26.580017 -199.278878) (xy 26.534227 -199.207626)
			(xy 26.495416 -199.132345) (xy 26.463937 -199.053715) (xy 26.440076 -198.972448) (xy 26.424047 -198.889282)
			(xy 26.415996 -198.804968) (xy 26.415492 -198.76262) (xy 26.415971 -198.719469) (xy 26.424334 -198.633574)
			(xy 26.440974 -198.548892) (xy 26.465733 -198.466218) (xy 26.49838 -198.38633) (xy 26.538608 -198.309978)
			(xy 26.586039 -198.237879) (xy 26.640227 -198.17071) (xy 26.700663 -198.109103) (xy 26.76678 -198.053637)
			(xy 26.80208 -198.028814) (xy 26.813002 -198.021448) (xy 26.824432 -197.998842) (xy 26.822146 -197.888098)
			(xy 26.8097 -197.865746) (xy 26.798778 -197.858888) (xy 26.764357 -197.836789) (xy 26.699289 -197.787212)
			(xy 26.639049 -197.731869) (xy 26.584146 -197.671228) (xy 26.535044 -197.6058) (xy 26.492159 -197.53614)
			(xy 26.455853 -197.462835) (xy 26.426432 -197.386506) (xy 26.404146 -197.307797) (xy 26.389183 -197.227375)
			(xy 26.381668 -197.145917) (xy 26.381202 -197.105016) (xy 20.511256 -197.105016) (xy 20.500663 -197.141095)
			(xy 20.469184 -197.219725) (xy 20.430373 -197.295006) (xy 20.384583 -197.366258) (xy 20.332227 -197.432834)
			(xy 20.273779 -197.494132) (xy 20.209769 -197.549597) (xy 20.140777 -197.598726) (xy 20.067427 -197.641075)
			(xy 19.990384 -197.676259) (xy 19.910345 -197.703961) (xy 19.828036 -197.723929) (xy 19.744201 -197.735982)
			(xy 19.6596 -197.740013) (xy 19.574999 -197.735982) (xy 19.491164 -197.723929) (xy 19.408855 -197.703961)
			(xy 19.328816 -197.676259) (xy 19.251773 -197.641075) (xy 19.178423 -197.598726) (xy 19.109431 -197.549597)
			(xy 19.045421 -197.494132) (xy 18.986973 -197.432834) (xy 18.934617 -197.366258) (xy 18.888827 -197.295006)
			(xy 18.850016 -197.219725) (xy 18.818537 -197.141095) (xy 18.794676 -197.059828) (xy 18.778647 -196.976662)
			(xy 18.770596 -196.892348) (xy 17.658719 -196.892348) (xy 17.64157 -196.918072) (xy 17.63776 -196.936868)
			(xy 17.639538 -196.946774) (xy 17.646094 -196.985749) (xy 17.65309 -197.06448) (xy 17.653508 -197.104)
			(xy 17.653033 -197.145102) (xy 17.645448 -197.226957) (xy 17.630343 -197.307762) (xy 17.607847 -197.386829)
			(xy 17.578151 -197.463483) (xy 17.541509 -197.53707) (xy 17.498234 -197.606962) (xy 17.448694 -197.672563)
			(xy 17.393313 -197.733313) (xy 17.332563 -197.788694) (xy 17.266962 -197.838234) (xy 17.19707 -197.881509)
			(xy 17.123483 -197.918151) (xy 17.046829 -197.947847) (xy 16.967762 -197.970343) (xy 16.886957 -197.985448)
			(xy 16.805102 -197.993033) (xy 16.764 -197.993508) (xy 16.721303 -197.993039) (xy 16.6363 -197.984864)
			(xy 16.552472 -197.96858) (xy 16.470591 -197.944336) (xy 16.391411 -197.912356) (xy 16.31566 -197.872935)
			(xy 16.244036 -197.826435) (xy 16.177198 -197.773284) (xy 16.115763 -197.713973) (xy 16.060294 -197.649046)
			(xy 16.011304 -197.579101) (xy 15.969243 -197.504783) (xy 15.934499 -197.426777) (xy 15.920466 -197.386448)
			(xy 15.915386 -197.370954) (xy 15.889986 -197.352158) (xy 15.762224 -197.348856) (xy 15.735808 -197.366128)
			(xy 15.729712 -197.381114) (xy 15.714272 -197.418912) (xy 15.677338 -197.491739) (xy 15.633884 -197.560873)
			(xy 15.584277 -197.625734) (xy 15.528934 -197.685775) (xy 15.468321 -197.740491) (xy 15.402948 -197.789421)
			(xy 15.333366 -197.832154) (xy 15.26016 -197.868329) (xy 15.183946 -197.897642) (xy 15.105367 -197.919847)
			(xy 15.025083 -197.934756) (xy 14.94377 -197.942244) (xy 14.902942 -197.942708) (xy 14.860593 -197.94222)
			(xy 14.776278 -197.934169) (xy 14.69311 -197.91814) (xy 14.611842 -197.894278) (xy 14.53321 -197.862799)
			(xy 14.457927 -197.823988) (xy 14.386674 -197.778196) (xy 14.320096 -197.725839) (xy 14.258797 -197.66739)
			(xy 14.203331 -197.603379) (xy 14.154201 -197.534386) (xy 14.111852 -197.461035) (xy 14.076667 -197.38399)
			(xy 14.048964 -197.30395) (xy 14.028996 -197.221639) (xy 14.016942 -197.137803) (xy 14.012912 -197.0532)
			(xy 10.020899 -197.0532) (xy 10.020819 -197.061511) (xy 10.012802 -197.164181) (xy 9.996818 -197.265915)
			(xy 9.972965 -197.366097) (xy 9.941386 -197.464118) (xy 9.902275 -197.559384) (xy 9.855867 -197.651317)
			(xy 9.802444 -197.739359) (xy 9.742331 -197.822976) (xy 9.675892 -197.90166) (xy 9.640062 -197.938644)
			(xy 9.632696 -197.945756) (xy 9.62533 -197.964044) (xy 9.62533 -198.055992) (xy 9.632696 -198.07428)
			(xy 9.640062 -198.081392) (xy 9.675889 -198.118379) (xy 9.742329 -198.197063) (xy 9.802443 -198.280679)
			(xy 9.855866 -198.36872) (xy 9.902275 -198.460653) (xy 9.941387 -198.555919) (xy 9.972965 -198.65394)
			(xy 9.996818 -198.754122) (xy 10.012801 -198.855856) (xy 10.020817 -198.958526) (xy 10.020817 -199.061508)
			(xy 10.016375 -199.118404) (xy 16.641568 -199.118404) (xy 16.641568 -199.033708) (xy 16.649619 -198.949394)
			(xy 16.665648 -198.866228) (xy 16.689509 -198.784961) (xy 16.720988 -198.706331) (xy 16.759799 -198.63105)
			(xy 16.805589 -198.559798) (xy 16.857945 -198.493222) (xy 16.916393 -198.431924) (xy 16.980403 -198.376459)
			(xy 17.049395 -198.32733) (xy 17.122745 -198.284981) (xy 17.199788 -198.249797) (xy 17.279827 -198.222095)
			(xy 17.362136 -198.202127) (xy 17.445971 -198.190074) (xy 17.530572 -198.186044) (xy 17.615173 -198.190074)
			(xy 17.699008 -198.202127) (xy 17.781317 -198.222095) (xy 17.861356 -198.249797) (xy 17.938399 -198.284981)
			(xy 18.011749 -198.32733) (xy 18.080741 -198.376459) (xy 18.144751 -198.431924) (xy 18.203199 -198.493222)
			(xy 18.255555 -198.559798) (xy 18.301345 -198.63105) (xy 18.340156 -198.706331) (xy 18.371635 -198.784961)
			(xy 18.375272 -198.797348) (xy 18.922996 -198.797348) (xy 18.922996 -198.712652) (xy 18.931047 -198.628338)
			(xy 18.947076 -198.545172) (xy 18.970937 -198.463905) (xy 19.002416 -198.385275) (xy 19.041227 -198.309994)
			(xy 19.087017 -198.238742) (xy 19.139373 -198.172166) (xy 19.197821 -198.110868) (xy 19.261831 -198.055403)
			(xy 19.330823 -198.006274) (xy 19.404173 -197.963925) (xy 19.481216 -197.928741) (xy 19.561255 -197.901039)
			(xy 19.643564 -197.881071) (xy 19.727399 -197.869018) (xy 19.812 -197.864988) (xy 19.896601 -197.869018)
			(xy 19.980436 -197.881071) (xy 20.062745 -197.901039) (xy 20.142784 -197.928741) (xy 20.219827 -197.963925)
			(xy 20.293177 -198.006274) (xy 20.362169 -198.055403) (xy 20.426179 -198.110868) (xy 20.484627 -198.172166)
			(xy 20.536983 -198.238742) (xy 20.582773 -198.309994) (xy 20.621584 -198.385275) (xy 20.653063 -198.463905)
			(xy 20.676924 -198.545172) (xy 20.690048 -198.613268) (xy 24.327358 -198.613268) (xy 24.327862 -198.57092)
			(xy 24.335913 -198.486606) (xy 24.351942 -198.40344) (xy 24.375803 -198.322173) (xy 24.407282 -198.243543)
			(xy 24.446093 -198.168262) (xy 24.491883 -198.09701) (xy 24.544239 -198.030434) (xy 24.602687 -197.969136)
			(xy 24.666697 -197.913671) (xy 24.735689 -197.864542) (xy 24.809039 -197.822193) (xy 24.886082 -197.787009)
			(xy 24.966121 -197.759307) (xy 25.04843 -197.739339) (xy 25.132265 -197.727286) (xy 25.216866 -197.723256)
			(xy 25.301467 -197.727286) (xy 25.385302 -197.739339) (xy 25.467611 -197.759307) (xy 25.54765 -197.787009)
			(xy 25.624693 -197.822193) (xy 25.698043 -197.864542) (xy 25.767035 -197.913671) (xy 25.831045 -197.969136)
			(xy 25.889493 -198.030434) (xy 25.941849 -198.09701) (xy 25.987639 -198.168262) (xy 26.02645 -198.243543)
			(xy 26.057929 -198.322173) (xy 26.08179 -198.40344) (xy 26.097819 -198.486606) (xy 26.10587 -198.57092)
			(xy 26.106374 -198.613268) (xy 26.105849 -198.656973) (xy 26.097278 -198.743961) (xy 26.080215 -198.829689)
			(xy 26.054825 -198.91333) (xy 26.021354 -198.994077) (xy 25.980123 -199.071151) (xy 25.931531 -199.143809)
			(xy 25.90419 -199.17791) (xy 25.898613 -199.1854) (xy 25.892755 -199.203116) (xy 25.89276 -199.212454)
			(xy 25.89403 -199.242172) (xy 25.894834 -199.251513) (xy 25.902259 -199.268711) (xy 25.908508 -199.2757)
			(xy 25.938313 -199.306821) (xy 25.992373 -199.373932) (xy 26.039689 -199.445958) (xy 26.079817 -199.522222)
			(xy 26.11238 -199.60201) (xy 26.137074 -199.684574) (xy 26.153666 -199.769138) (xy 26.162001 -199.854911)
			(xy 26.162508 -199.898) (xy 26.162004 -199.940348) (xy 26.153953 -200.024662) (xy 26.137924 -200.107828)
			(xy 26.114063 -200.189095) (xy 26.082584 -200.267725) (xy 26.043773 -200.343006) (xy 25.997983 -200.414258)
			(xy 25.945627 -200.480834) (xy 25.887179 -200.542132) (xy 25.823169 -200.597597) (xy 25.754177 -200.646726)
			(xy 25.680827 -200.689075) (xy 25.603784 -200.724259) (xy 25.523745 -200.751961) (xy 25.441436 -200.771929)
			(xy 25.357601 -200.783982) (xy 25.273 -200.788013) (xy 25.188399 -200.783982) (xy 25.104564 -200.771929)
			(xy 25.022255 -200.751961) (xy 24.942216 -200.724259) (xy 24.865173 -200.689075) (xy 24.791823 -200.646726)
			(xy 24.722831 -200.597597) (xy 24.658821 -200.542132) (xy 24.600373 -200.480834) (xy 24.548017 -200.414258)
			(xy 24.502227 -200.343006) (xy 24.463416 -200.267725) (xy 24.431937 -200.189095) (xy 24.408076 -200.107828)
			(xy 24.392047 -200.024662) (xy 24.383996 -199.940348) (xy 24.383492 -199.898) (xy 24.384006 -199.854295)
			(xy 24.39258 -199.767307) (xy 24.409645 -199.681579) (xy 24.435037 -199.597938) (xy 24.46851 -199.517191)
			(xy 24.509742 -199.440117) (xy 24.558335 -199.367459) (xy 24.585676 -199.333358) (xy 24.59123 -199.325854)
			(xy 24.5971 -199.308149) (xy 24.597106 -199.298814) (xy 24.595836 -199.269096) (xy 24.595056 -199.259751)
			(xy 24.587615 -199.242554) (xy 24.581358 -199.235568) (xy 24.551598 -199.204405) (xy 24.497533 -199.137301)
			(xy 24.450211 -199.065283) (xy 24.410078 -198.989025) (xy 24.377509 -198.909243) (xy 24.352809 -198.826685)
			(xy 24.33621 -198.742124) (xy 24.327869 -198.656355) (xy 24.327358 -198.613268) (xy 20.690048 -198.613268)
			(xy 20.692953 -198.628338) (xy 20.701004 -198.712652) (xy 20.701508 -198.755) (xy 20.701004 -198.797348)
			(xy 20.692953 -198.881662) (xy 20.676924 -198.964828) (xy 20.653063 -199.046095) (xy 20.621584 -199.124725)
			(xy 20.582773 -199.200006) (xy 20.536983 -199.271258) (xy 20.484627 -199.337834) (xy 20.426179 -199.399132)
			(xy 20.362169 -199.454597) (xy 20.293177 -199.503726) (xy 20.219827 -199.546075) (xy 20.142784 -199.581259)
			(xy 20.062745 -199.608961) (xy 19.980436 -199.628929) (xy 19.896601 -199.640982) (xy 19.812 -199.645013)
			(xy 19.727399 -199.640982) (xy 19.643564 -199.628929) (xy 19.561255 -199.608961) (xy 19.481216 -199.581259)
			(xy 19.404173 -199.546075) (xy 19.330823 -199.503726) (xy 19.261831 -199.454597) (xy 19.197821 -199.399132)
			(xy 19.139373 -199.337834) (xy 19.087017 -199.271258) (xy 19.041227 -199.200006) (xy 19.002416 -199.124725)
			(xy 18.970937 -199.046095) (xy 18.947076 -198.964828) (xy 18.931047 -198.881662) (xy 18.922996 -198.797348)
			(xy 18.375272 -198.797348) (xy 18.395496 -198.866228) (xy 18.411525 -198.949394) (xy 18.419576 -199.033708)
			(xy 18.42008 -199.076056) (xy 18.419576 -199.118404) (xy 18.411525 -199.202718) (xy 18.395496 -199.285884)
			(xy 18.371635 -199.367151) (xy 18.340156 -199.445781) (xy 18.301345 -199.521062) (xy 18.255555 -199.592314)
			(xy 18.203199 -199.65889) (xy 18.144751 -199.720188) (xy 18.080741 -199.775653) (xy 18.011749 -199.824782)
			(xy 17.938399 -199.867131) (xy 17.861356 -199.902315) (xy 17.781317 -199.930017) (xy 17.699008 -199.949985)
			(xy 17.615173 -199.962038) (xy 17.530572 -199.966069) (xy 17.445971 -199.962038) (xy 17.362136 -199.949985)
			(xy 17.279827 -199.930017) (xy 17.199788 -199.902315) (xy 17.122745 -199.867131) (xy 17.049395 -199.824782)
			(xy 16.980403 -199.775653) (xy 16.916393 -199.720188) (xy 16.857945 -199.65889) (xy 16.805589 -199.592314)
			(xy 16.759799 -199.521062) (xy 16.720988 -199.445781) (xy 16.689509 -199.367151) (xy 16.665648 -199.285884)
			(xy 16.649619 -199.202718) (xy 16.641568 -199.118404) (xy 10.016375 -199.118404) (xy 10.012802 -199.164178)
			(xy 9.996819 -199.265913) (xy 9.972967 -199.366095) (xy 9.941389 -199.464116) (xy 9.902277 -199.559382)
			(xy 9.855869 -199.651315) (xy 9.802446 -199.739357) (xy 9.742332 -199.822973) (xy 9.675892 -199.901657)
			(xy 9.640062 -199.93864) (xy 9.632696 -199.945752) (xy 9.62533 -199.96404) (xy 9.62533 -200.055988)
			(xy 9.632696 -200.074276) (xy 9.640062 -200.081388) (xy 9.675895 -200.118369) (xy 9.742335 -200.197053)
			(xy 9.802449 -200.28067) (xy 9.855872 -200.368712) (xy 9.90228 -200.460645) (xy 9.941392 -200.555911)
			(xy 9.97297 -200.653933) (xy 9.996823 -200.754115) (xy 10.012806 -200.85585) (xy 10.020822 -200.95852)
			(xy 10.020821 -201.061503) (xy 10.012806 -201.164173) (xy 9.996823 -201.265908) (xy 9.97297 -201.36609)
			(xy 9.941391 -201.464111) (xy 9.902279 -201.559378) (xy 9.85587 -201.651311) (xy 9.802447 -201.739353)
			(xy 9.742333 -201.822969) (xy 9.675893 -201.901653) (xy 9.640062 -201.938636) (xy 9.632696 -201.945748)
			(xy 9.62533 -201.964036) (xy 9.62533 -202.055984) (xy 9.632696 -202.074272) (xy 9.640062 -202.081384)
			(xy 9.677476 -202.120059) (xy 9.746598 -202.202541) (xy 9.808777 -202.290376) (xy 9.836658 -202.3364)
			(xy 9.84377 -202.348084) (xy 9.86663 -202.361292) (xy 9.880854 -202.361292) (xy 9.921949 -202.361778)
			(xy 10.003786 -202.369384) (xy 10.084573 -202.384506) (xy 10.16362 -202.407017) (xy 10.240254 -202.436725)
			(xy 10.31382 -202.473375) (xy 10.383691 -202.516655) (xy 10.449272 -202.566197) (xy 10.510003 -202.621577)
			(xy 10.556824 -202.67295) (xy 14.350492 -202.67295) (xy 14.350919 -202.631847) (xy 14.358508 -202.549991)
			(xy 14.373618 -202.469185) (xy 14.396118 -202.390117) (xy 14.425818 -202.313463) (xy 14.462464 -202.239876)
			(xy 14.505742 -202.169984) (xy 14.555285 -202.104384) (xy 14.610669 -202.043634) (xy 14.671422 -201.988253)
			(xy 14.737026 -201.938714) (xy 14.80692 -201.895439) (xy 14.880509 -201.858798) (xy 14.957165 -201.829102)
			(xy 15.036234 -201.806606) (xy 15.117041 -201.791501) (xy 15.198897 -201.783917) (xy 15.24 -201.783442)
			(xy 15.2824 -201.783877) (xy 15.366813 -201.791965) (xy 15.450073 -201.808049) (xy 15.531425 -201.831983)
			(xy 15.61013 -201.863549) (xy 15.685474 -201.902462) (xy 15.756774 -201.948367) (xy 15.823382 -202.000849)
			(xy 15.884693 -202.059431) (xy 15.940152 -202.123581) (xy 15.989255 -202.192718) (xy 16.031557 -202.266213)
			(xy 16.066673 -202.3434) (xy 16.094284 -202.423578) (xy 16.114141 -202.50602) (xy 16.126063 -202.589977)
			(xy 16.128492 -202.63231) (xy 16.129256 -202.64136) (xy 16.136417 -202.658042) (xy 16.148942 -202.671182)
			(xy 16.15694 -202.67549) (xy 16.195683 -202.69522) (xy 16.269494 -202.741177) (xy 16.338467 -202.794119)
			(xy 16.401943 -202.85354) (xy 16.459318 -202.918871) (xy 16.485108 -202.953874) (xy 16.492474 -202.964288)
			(xy 16.514572 -202.975464) (xy 16.623538 -202.973178) (xy 16.645382 -202.96124) (xy 16.65224 -202.950826)
			(xy 16.676883 -202.914513) (xy 16.732281 -202.846442) (xy 16.794112 -202.784156) (xy 16.861776 -202.728262)
			(xy 16.934615 -202.679302) (xy 17.011921 -202.637752) (xy 17.092942 -202.604017) (xy 17.176892 -202.578423)
			(xy 17.262954 -202.561221) (xy 17.350292 -202.552576) (xy 17.394174 -202.552046) (xy 17.435277 -202.552513)
			(xy 17.517131 -202.560098) (xy 17.597937 -202.575204) (xy 17.677004 -202.597701) (xy 17.701906 -202.607348)
			(xy 29.26359 -202.607348) (xy 29.26359 -202.522652) (xy 29.271641 -202.438338) (xy 29.28767 -202.355172)
			(xy 29.311531 -202.273905) (xy 29.34301 -202.195275) (xy 29.381821 -202.119994) (xy 29.427611 -202.048742)
			(xy 29.479967 -201.982166) (xy 29.538415 -201.920868) (xy 29.602425 -201.865403) (xy 29.671417 -201.816274)
			(xy 29.744767 -201.773925) (xy 29.82181 -201.738741) (xy 29.901849 -201.711039) (xy 29.984158 -201.691071)
			(xy 30.067993 -201.679018) (xy 30.152594 -201.674988) (xy 30.237195 -201.679018) (xy 30.32103 -201.691071)
			(xy 30.403339 -201.711039) (xy 30.483378 -201.738741) (xy 30.560421 -201.773925) (xy 30.633771 -201.816274)
			(xy 30.702763 -201.865403) (xy 30.766773 -201.920868) (xy 30.825221 -201.982166) (xy 30.877577 -202.048742)
			(xy 30.923367 -202.119994) (xy 30.962178 -202.195275) (xy 30.993657 -202.273905) (xy 31.017518 -202.355172)
			(xy 31.033547 -202.438338) (xy 31.041598 -202.522652) (xy 31.042102 -202.565) (xy 31.041598 -202.607348)
			(xy 31.033547 -202.691662) (xy 31.017518 -202.774828) (xy 30.993657 -202.856095) (xy 30.962178 -202.934725)
			(xy 30.923367 -203.010006) (xy 30.877577 -203.081258) (xy 30.825221 -203.147834) (xy 30.766773 -203.209132)
			(xy 30.702763 -203.264597) (xy 30.633771 -203.313726) (xy 30.560421 -203.356075) (xy 30.483378 -203.391259)
			(xy 30.403339 -203.418961) (xy 30.32103 -203.438929) (xy 30.237195 -203.450982) (xy 30.152594 -203.455013)
			(xy 30.067993 -203.450982) (xy 29.984158 -203.438929) (xy 29.901849 -203.418961) (xy 29.82181 -203.391259)
			(xy 29.744767 -203.356075) (xy 29.671417 -203.313726) (xy 29.602425 -203.264597) (xy 29.538415 -203.209132)
			(xy 29.479967 -203.147834) (xy 29.427611 -203.081258) (xy 29.381821 -203.010006) (xy 29.34301 -202.934725)
			(xy 29.311531 -202.856095) (xy 29.28767 -202.774828) (xy 29.271641 -202.691662) (xy 29.26359 -202.607348)
			(xy 17.701906 -202.607348) (xy 17.753658 -202.627397) (xy 17.827245 -202.664039) (xy 17.897137 -202.707315)
			(xy 17.962738 -202.756855) (xy 18.023489 -202.812237) (xy 18.07887 -202.872988) (xy 18.128409 -202.938589)
			(xy 18.171685 -203.008482) (xy 18.208326 -203.082069) (xy 18.238022 -203.158724) (xy 18.260518 -203.237791)
			(xy 18.275623 -203.318597) (xy 18.283208 -203.400451) (xy 18.283682 -203.441554) (xy 18.283217 -203.483593)
			(xy 18.275329 -203.5673) (xy 18.267934 -203.608686) (xy 18.265902 -203.618592) (xy 18.269966 -203.637896)
			(xy 18.320258 -203.713842) (xy 18.336514 -203.725018) (xy 18.34642 -203.72705) (xy 18.388606 -203.73655)
			(xy 18.471035 -203.7627) (xy 18.550538 -203.796726) (xy 18.626364 -203.838307) (xy 18.697796 -203.88705)
			(xy 18.764161 -203.942496) (xy 18.824832 -204.00412) (xy 18.879235 -204.071341) (xy 18.926859 -204.143525)
			(xy 18.967252 -204.21999) (xy 19.000034 -204.300014) (xy 19.024895 -204.382841) (xy 19.041601 -204.467691)
			(xy 19.049994 -204.553761) (xy 19.050508 -204.597) (xy 19.050033 -204.638102) (xy 19.042448 -204.719957)
			(xy 19.027343 -204.800762) (xy 19.004847 -204.879829) (xy 18.975151 -204.956483) (xy 18.938509 -205.03007)
			(xy 18.895234 -205.099962) (xy 18.845694 -205.165563) (xy 18.790313 -205.226313) (xy 18.729563 -205.281694)
			(xy 18.663962 -205.331234) (xy 18.59407 -205.374509) (xy 18.520483 -205.411151) (xy 18.443829 -205.440847)
			(xy 18.364762 -205.463343) (xy 18.283957 -205.478448) (xy 18.202102 -205.486033) (xy 18.161 -205.486508)
			(xy 18.118753 -205.486046) (xy 18.034639 -205.478033) (xy 17.951664 -205.462079) (xy 17.870577 -205.438328)
			(xy 17.792107 -205.406994) (xy 17.716963 -205.368359) (xy 17.645821 -205.322772) (xy 17.579323 -205.270644)
			(xy 17.548352 -205.241906) (xy 17.541872 -205.236155) (xy 17.526058 -205.229103) (xy 17.508792 -205.227778)
			(xy 17.500346 -205.229714) (xy 17.463035 -205.239186) (xy 17.387193 -205.252407) (xy 17.310493 -205.259034)
			(xy 17.272 -205.259432) (xy 17.230898 -205.258933) (xy 17.149045 -205.251349) (xy 17.068241 -205.236244)
			(xy 16.989176 -205.213748) (xy 16.912523 -205.184054) (xy 16.838937 -205.147413) (xy 16.769046 -205.104139)
			(xy 16.703445 -205.054601) (xy 16.642695 -204.999222) (xy 16.587314 -204.938473) (xy 16.537775 -204.872874)
			(xy 16.494499 -204.802984) (xy 16.457856 -204.729399) (xy 16.428159 -204.652747) (xy 16.405661 -204.573682)
			(xy 16.390555 -204.492878) (xy 16.382968 -204.411026) (xy 16.382492 -204.369924) (xy 16.383762 -204.322426)
			(xy 16.384524 -204.308202) (xy 16.371316 -204.28331) (xy 16.269462 -204.222858) (xy 16.241268 -204.223112)
			(xy 16.229076 -204.230478) (xy 16.193988 -204.251528) (xy 16.120664 -204.287856) (xy 16.044312 -204.317296)
			(xy 15.96558 -204.339596) (xy 15.885131 -204.35457) (xy 15.803647 -204.36209) (xy 15.762732 -204.362558)
			(xy 15.720333 -204.362093) (xy 15.635921 -204.354007) (xy 15.552661 -204.337926) (xy 15.47131 -204.313995)
			(xy 15.392605 -204.282431) (xy 15.31726 -204.243521) (xy 15.245961 -204.197618) (xy 15.179353 -204.145138)
			(xy 15.118041 -204.086559) (xy 15.062581 -204.02241) (xy 15.013478 -203.953275) (xy 14.971176 -203.879782)
			(xy 14.93606 -203.802596) (xy 14.908448 -203.722419) (xy 14.888591 -203.639978) (xy 14.876669 -203.556022)
			(xy 14.87424 -203.51369) (xy 14.873459 -203.504643) (xy 14.866304 -203.487963) (xy 14.853786 -203.474821)
			(xy 14.845792 -203.47051) (xy 14.809055 -203.451822) (xy 14.738866 -203.408599) (xy 14.672976 -203.359069)
			(xy 14.61195 -203.303658) (xy 14.556309 -203.24284) (xy 14.506533 -203.177137) (xy 14.463046 -203.107112)
			(xy 14.426222 -203.033365) (xy 14.396376 -202.956528) (xy 14.373765 -202.87726) (xy 14.358582 -202.796241)
			(xy 14.350957 -202.714165) (xy 14.350492 -202.67295) (xy 10.556824 -202.67295) (xy 10.565366 -202.682323)
			(xy 10.614889 -202.747918) (xy 10.658149 -202.817802) (xy 10.694778 -202.891379) (xy 10.724463 -202.968021)
			(xy 10.746952 -203.047074) (xy 10.762052 -203.127865) (xy 10.769634 -203.209705) (xy 10.770108 -203.2508)
			(xy 10.769565 -203.293991) (xy 10.761172 -203.379964) (xy 10.744486 -203.464719) (xy 10.719663 -203.547457)
			(xy 10.686937 -203.6274) (xy 10.646616 -203.703794) (xy 10.59908 -203.77592) (xy 10.544777 -203.843098)
			(xy 10.484218 -203.904697) (xy 10.417973 -203.960136) (xy 10.346667 -204.008892) (xy 10.27097 -204.050507)
			(xy 10.191596 -204.084589) (xy 10.109292 -204.110817) (xy 10.024833 -204.128943) (xy 9.939016 -204.138797)
			(xy 9.89584 -204.140054) (xy 9.882124 -204.140308) (xy 9.858502 -204.154786) (xy 9.803638 -204.257402)
			(xy 9.804654 -204.285088) (xy 9.812274 -204.296518) (xy 9.840877 -204.342135) (xy 9.891434 -204.437209)
			(xy 9.934084 -204.536082) (xy 9.968544 -204.638099) (xy 9.994586 -204.742583) (xy 10.012036 -204.848839)
			(xy 10.02078 -204.956164) (xy 10.021316 -205.010004) (xy 10.020808 -205.061495) (xy 10.012793 -205.164164)
			(xy 9.99681 -205.265899) (xy 9.972958 -205.36608) (xy 9.941381 -205.464101) (xy 9.90227 -205.559367)
			(xy 9.855863 -205.6513) (xy 9.802441 -205.739342) (xy 9.742329 -205.822959) (xy 9.675891 -205.901644)
			(xy 9.640062 -205.938628) (xy 9.632696 -205.94574) (xy 9.62533 -205.964028) (xy 9.62533 -206.055976)
			(xy 9.632696 -206.074264) (xy 9.640062 -206.081376) (xy 9.675893 -206.118359) (xy 9.742333 -206.197043)
			(xy 9.802447 -206.280659) (xy 9.85587 -206.368701) (xy 9.902278 -206.460634) (xy 9.94139 -206.5559)
			(xy 9.972969 -206.653922) (xy 9.977118 -206.671348) (xy 12.522196 -206.671348) (xy 12.522196 -206.586652)
			(xy 12.530247 -206.502338) (xy 12.546276 -206.419172) (xy 12.570137 -206.337905) (xy 12.601616 -206.259275)
			(xy 12.640427 -206.183994) (xy 12.686217 -206.112742) (xy 12.738573 -206.046166) (xy 12.797021 -205.984868)
			(xy 12.861031 -205.929403) (xy 12.930023 -205.880274) (xy 13.003373 -205.837925) (xy 13.080416 -205.802741)
			(xy 13.160455 -205.775039) (xy 13.242764 -205.755071) (xy 13.326599 -205.743018) (xy 13.4112 -205.738988)
			(xy 13.495801 -205.743018) (xy 13.579636 -205.755071) (xy 13.661945 -205.775039) (xy 13.683063 -205.782348)
			(xy 14.604996 -205.782348) (xy 14.604996 -205.697652) (xy 14.613047 -205.613338) (xy 14.629076 -205.530172)
			(xy 14.652937 -205.448905) (xy 14.684416 -205.370275) (xy 14.723227 -205.294994) (xy 14.769017 -205.223742)
			(xy 14.821373 -205.157166) (xy 14.879821 -205.095868) (xy 14.943831 -205.040403) (xy 15.012823 -204.991274)
			(xy 15.086173 -204.948925) (xy 15.163216 -204.913741) (xy 15.243255 -204.886039) (xy 15.325564 -204.866071)
			(xy 15.409399 -204.854018) (xy 15.494 -204.849988) (xy 15.578601 -204.854018) (xy 15.662436 -204.866071)
			(xy 15.744745 -204.886039) (xy 15.824784 -204.913741) (xy 15.901827 -204.948925) (xy 15.975177 -204.991274)
			(xy 16.044169 -205.040403) (xy 16.108179 -205.095868) (xy 16.166627 -205.157166) (xy 16.218983 -205.223742)
			(xy 16.264773 -205.294994) (xy 16.303584 -205.370275) (xy 16.335063 -205.448905) (xy 16.358924 -205.530172)
			(xy 16.374953 -205.613338) (xy 16.383004 -205.697652) (xy 16.383508 -205.74) (xy 20.192492 -205.74)
			(xy 20.193013 -205.696655) (xy 20.201459 -205.610377) (xy 20.218259 -205.52533) (xy 20.243255 -205.442322)
			(xy 20.27621 -205.362139) (xy 20.316811 -205.285544) (xy 20.364672 -205.213263) (xy 20.41934 -205.145983)
			(xy 20.480294 -205.084341) (xy 20.513294 -205.056232) (xy 20.52193 -205.048866) (xy 20.531582 -205.028546)
			(xy 20.531582 -204.927454) (xy 20.52193 -204.907134) (xy 20.513294 -204.899768) (xy 20.480288 -204.871669)
			(xy 20.419349 -204.810014) (xy 20.364695 -204.742726) (xy 20.316844 -204.670441) (xy 20.276248 -204.593846)
			(xy 20.243295 -204.513666) (xy 20.218295 -204.430661) (xy 20.201485 -204.345618) (xy 20.193026 -204.259344)
			(xy 20.192492 -204.216) (xy 20.192996 -204.173652) (xy 20.201047 -204.089338) (xy 20.217076 -204.006172)
			(xy 20.240937 -203.924905) (xy 20.272416 -203.846275) (xy 20.311227 -203.770994) (xy 20.357017 -203.699742)
			(xy 20.409373 -203.633166) (xy 20.467821 -203.571868) (xy 20.531831 -203.516403) (xy 20.600823 -203.467274)
			(xy 20.674173 -203.424925) (xy 20.751216 -203.389741) (xy 20.831255 -203.362039) (xy 20.913564 -203.342071)
			(xy 20.997399 -203.330018) (xy 21.082 -203.325988) (xy 21.166601 -203.330018) (xy 21.250436 -203.342071)
			(xy 21.332745 -203.362039) (xy 21.412784 -203.389741) (xy 21.489827 -203.424925) (xy 21.563177 -203.467274)
			(xy 21.632169 -203.516403) (xy 21.696179 -203.571868) (xy 21.754627 -203.633166) (xy 21.806983 -203.699742)
			(xy 21.852773 -203.770994) (xy 21.891584 -203.846275) (xy 21.923063 -203.924905) (xy 21.946924 -204.006172)
			(xy 21.962953 -204.089338) (xy 21.971004 -204.173652) (xy 21.971508 -204.216) (xy 21.970987 -204.259345)
			(xy 21.962541 -204.345623) (xy 21.945741 -204.43067) (xy 21.920745 -204.513678) (xy 21.88779 -204.593861)
			(xy 21.847189 -204.670456) (xy 21.799328 -204.742737) (xy 21.74466 -204.810017) (xy 21.683706 -204.871659)
			(xy 21.650706 -204.899768) (xy 21.64207 -204.907134) (xy 21.632418 -204.927454) (xy 21.632418 -205.028546)
			(xy 21.64207 -205.048866) (xy 21.650706 -205.056232) (xy 21.683712 -205.084331) (xy 21.744651 -205.145986)
			(xy 21.799305 -205.213274) (xy 21.847156 -205.285559) (xy 21.887752 -205.362154) (xy 21.920705 -205.442334)
			(xy 21.945705 -205.525339) (xy 21.962515 -205.610382) (xy 21.970974 -205.696656) (xy 21.971508 -205.74)
			(xy 21.971004 -205.782348) (xy 21.962953 -205.866662) (xy 21.946924 -205.949828) (xy 21.923063 -206.031095)
			(xy 21.907408 -206.0702) (xy 32.954976 -206.0702) (xy 32.955467 -206.029098) (xy 32.963051 -205.947245)
			(xy 32.978156 -205.86644) (xy 33.000652 -205.787374) (xy 33.030347 -205.710721) (xy 33.066988 -205.637135)
			(xy 33.110263 -205.567243) (xy 33.159801 -205.501643) (xy 33.215181 -205.440893) (xy 33.27593 -205.385512)
			(xy 33.34153 -205.335972) (xy 33.411421 -205.292696) (xy 33.485006 -205.256054) (xy 33.561659 -205.226357)
			(xy 33.640725 -205.20386) (xy 33.721529 -205.188754) (xy 33.803382 -205.181167) (xy 33.844484 -205.180692)
			(xy 33.883782 -205.181103) (xy 33.962075 -205.188012) (xy 34.039451 -205.201804) (xy 34.115309 -205.222371)
			(xy 34.152332 -205.235556) (xy 34.165286 -205.240382) (xy 34.19221 -205.23581) (xy 34.280856 -205.160372)
			(xy 34.289746 -205.134718) (xy 34.287206 -205.121256) (xy 34.279721 -205.079686) (xy 34.271703 -204.995597)
			(xy 34.271204 -204.953362) (xy 34.271752 -204.910596) (xy 34.279949 -204.825457) (xy 34.296281 -204.741498)
			(xy 34.320598 -204.659495) (xy 34.352676 -204.580206) (xy 34.392218 -204.504363) (xy 34.438859 -204.432666)
			(xy 34.492168 -204.365778) (xy 34.551652 -204.304318) (xy 34.583878 -204.276198) (xy 34.590699 -204.26983)
			(xy 34.599584 -204.253437) (xy 34.602022 -204.234952) (xy 34.59769 -204.216816) (xy 34.592768 -204.208888)
			(xy 34.567833 -204.171715) (xy 34.524671 -204.093293) (xy 34.489605 -204.010931) (xy 34.46299 -203.925464)
			(xy 34.445094 -203.837756) (xy 34.436098 -203.748694) (xy 34.435542 -203.703936) (xy 34.435999 -203.661712)
			(xy 34.444017 -203.577644) (xy 34.459967 -203.494715) (xy 34.483704 -203.41367) (xy 34.515014 -203.33524)
			(xy 34.553616 -203.260129) (xy 34.599162 -203.189015) (xy 34.651243 -203.122538) (xy 34.709389 -203.061295)
			(xy 34.773078 -203.005839) (xy 34.841735 -202.956667) (xy 34.914743 -202.914223) (xy 34.991445 -202.87889)
			(xy 35.07115 -202.850984) (xy 35.153142 -202.830757) (xy 35.23668 -202.818391) (xy 35.278822 -202.815698)
			(xy 35.290899 -202.814403) (xy 35.311856 -202.802188) (xy 35.318954 -202.79233) (xy 35.34125 -202.758717)
			(xy 35.390974 -202.695201) (xy 35.446244 -202.636446) (xy 35.506605 -202.582937) (xy 35.571563 -202.535111)
			(xy 35.640584 -202.493362) (xy 35.7131 -202.458033) (xy 35.788517 -202.429414) (xy 35.866215 -202.407739)
			(xy 35.945557 -202.393188) (xy 36.02589 -202.385878) (xy 36.066222 -202.385422) (xy 36.107326 -202.385831)
			(xy 36.189184 -202.393419) (xy 36.269993 -202.408526) (xy 36.349063 -202.431026) (xy 36.42572 -202.460725)
			(xy 36.499309 -202.497371) (xy 36.569203 -202.54065) (xy 36.634806 -202.590194) (xy 36.695557 -202.64558)
			(xy 36.750939 -202.706334) (xy 36.800479 -202.77194) (xy 36.843754 -202.841836) (xy 36.880396 -202.915428)
			(xy 36.91009 -202.992086) (xy 36.932585 -203.071158) (xy 36.947689 -203.151967) (xy 36.955271 -203.233826)
			(xy 36.95573 -203.27493) (xy 36.955232 -203.317265) (xy 36.947183 -203.401552) (xy 36.931162 -203.484693)
			(xy 36.907313 -203.565935) (xy 36.875851 -203.644544) (xy 36.837063 -203.719807) (xy 36.791298 -203.791044)
			(xy 36.738971 -203.85761) (xy 36.680556 -203.918902) (xy 36.648898 -203.947014) (xy 36.640893 -203.954736)
			(xy 36.631816 -203.975009) (xy 36.632131 -203.997219) (xy 36.636452 -204.007466) (xy 36.653628 -204.043844)
			(xy 36.682104 -204.119088) (xy 36.703668 -204.196597) (xy 36.718143 -204.275736) (xy 36.725411 -204.35586)
			(xy 36.72586 -204.396086) (xy 36.725306 -204.439472) (xy 36.716873 -204.525833) (xy 36.700068 -204.610962)
			(xy 36.675049 -204.694049) (xy 36.642056 -204.774303) (xy 36.601401 -204.850961) (xy 36.553471 -204.923295)
			(xy 36.498723 -204.990615) (xy 36.437677 -205.052281) (xy 36.370914 -205.107707) (xy 36.299069 -205.156365)
			(xy 36.222825 -205.197793) (xy 36.142909 -205.231597) (xy 36.060079 -205.257454) (xy 36.017708 -205.266798)
			(xy 36.005657 -205.269935) (xy 35.986482 -205.285779) (xy 35.981132 -205.297024) (xy 35.963815 -205.336959)
			(xy 35.922504 -205.41358) (xy 35.873906 -205.485799) (xy 35.818485 -205.552926) (xy 35.756771 -205.614317)
			(xy 35.689355 -205.669386) (xy 35.616882 -205.717605) (xy 35.540046 -205.758514) (xy 35.45958 -205.791721)
			(xy 35.376255 -205.816909) (xy 35.290868 -205.833836) (xy 35.204236 -205.842341) (xy 35.160712 -205.84287)
			(xy 35.121414 -205.842463) (xy 35.043121 -205.835553) (xy 34.965744 -205.82176) (xy 34.889887 -205.801192)
			(xy 34.852864 -205.788006) (xy 34.83991 -205.78318) (xy 34.812986 -205.787752) (xy 34.72434 -205.86319)
			(xy 34.71545 -205.888844) (xy 34.71799 -205.902306) (xy 34.725484 -205.943874) (xy 34.733496 -206.027964)
			(xy 34.733992 -206.0702) (xy 34.733594 -206.107384) (xy 34.727346 -206.18149) (xy 34.714928 -206.254814)
			(xy 34.706052 -206.290926) (xy 34.704107 -206.300513) (xy 34.706746 -206.319877) (xy 34.716437 -206.336847)
			(xy 34.723832 -206.34325) (xy 34.758187 -206.371353) (xy 34.821726 -206.433336) (xy 34.878779 -206.501336)
			(xy 34.928779 -206.574678) (xy 34.971229 -206.652633) (xy 35.005708 -206.734427) (xy 35.031872 -206.819248)
			(xy 35.049462 -206.906251) (xy 35.058303 -206.994574) (xy 35.058858 -207.038956) (xy 35.058354 -207.081304)
			(xy 35.050303 -207.165618) (xy 35.034274 -207.248784) (xy 35.010413 -207.330051) (xy 34.978934 -207.408681)
			(xy 34.940123 -207.483962) (xy 34.894333 -207.555214) (xy 34.841977 -207.62179) (xy 34.783529 -207.683088)
			(xy 34.719519 -207.738553) (xy 34.650527 -207.787682) (xy 34.577177 -207.830031) (xy 34.500134 -207.865215)
			(xy 34.420095 -207.892917) (xy 34.337786 -207.912885) (xy 34.253951 -207.924938) (xy 34.16935 -207.928969)
			(xy 34.084749 -207.924938) (xy 34.000914 -207.912885) (xy 33.918605 -207.892917) (xy 33.838566 -207.865215)
			(xy 33.761523 -207.830031) (xy 33.688173 -207.787682) (xy 33.619181 -207.738553) (xy 33.555171 -207.683088)
			(xy 33.496723 -207.62179) (xy 33.444367 -207.555214) (xy 33.398577 -207.483962) (xy 33.359766 -207.408681)
			(xy 33.328287 -207.330051) (xy 33.304426 -207.248784) (xy 33.288397 -207.165618) (xy 33.280346 -207.081304)
			(xy 33.279842 -207.038956) (xy 33.280251 -207.001772) (xy 33.286494 -206.927666) (xy 33.298908 -206.854342)
			(xy 33.307782 -206.81823) (xy 33.309751 -206.808647) (xy 33.307099 -206.78928) (xy 33.297399 -206.772309)
			(xy 33.290002 -206.765906) (xy 33.255633 -206.737819) (xy 33.192093 -206.675835) (xy 33.13504 -206.607834)
			(xy 33.085041 -206.534489) (xy 33.042592 -206.456532) (xy 33.008115 -206.374735) (xy 32.981953 -206.289913)
			(xy 32.964366 -206.202907) (xy 32.955529 -206.114583) (xy 32.954976 -206.0702) (xy 21.907408 -206.0702)
			(xy 21.891584 -206.109725) (xy 21.852773 -206.185006) (xy 21.806983 -206.256258) (xy 21.754627 -206.322834)
			(xy 21.696179 -206.384132) (xy 21.632169 -206.439597) (xy 21.563177 -206.488726) (xy 21.489827 -206.531075)
			(xy 21.412784 -206.566259) (xy 21.332745 -206.593961) (xy 21.250436 -206.613929) (xy 21.166601 -206.625982)
			(xy 21.082 -206.630013) (xy 20.997399 -206.625982) (xy 20.913564 -206.613929) (xy 20.831255 -206.593961)
			(xy 20.751216 -206.566259) (xy 20.674173 -206.531075) (xy 20.600823 -206.488726) (xy 20.531831 -206.439597)
			(xy 20.467821 -206.384132) (xy 20.409373 -206.322834) (xy 20.357017 -206.256258) (xy 20.311227 -206.185006)
			(xy 20.272416 -206.109725) (xy 20.240937 -206.031095) (xy 20.217076 -205.949828) (xy 20.201047 -205.866662)
			(xy 20.192996 -205.782348) (xy 20.192492 -205.74) (xy 16.383508 -205.74) (xy 16.383004 -205.782348)
			(xy 16.374953 -205.866662) (xy 16.358924 -205.949828) (xy 16.335063 -206.031095) (xy 16.303584 -206.109725)
			(xy 16.264773 -206.185006) (xy 16.218983 -206.256258) (xy 16.166627 -206.322834) (xy 16.108179 -206.384132)
			(xy 16.044169 -206.439597) (xy 15.975177 -206.488726) (xy 15.901827 -206.531075) (xy 15.824784 -206.566259)
			(xy 15.744745 -206.593961) (xy 15.662436 -206.613929) (xy 15.578601 -206.625982) (xy 15.494 -206.630013)
			(xy 15.409399 -206.625982) (xy 15.325564 -206.613929) (xy 15.243255 -206.593961) (xy 15.163216 -206.566259)
			(xy 15.086173 -206.531075) (xy 15.012823 -206.488726) (xy 14.943831 -206.439597) (xy 14.879821 -206.384132)
			(xy 14.821373 -206.322834) (xy 14.769017 -206.256258) (xy 14.723227 -206.185006) (xy 14.684416 -206.109725)
			(xy 14.652937 -206.031095) (xy 14.629076 -205.949828) (xy 14.613047 -205.866662) (xy 14.604996 -205.782348)
			(xy 13.683063 -205.782348) (xy 13.741984 -205.802741) (xy 13.819027 -205.837925) (xy 13.892377 -205.880274)
			(xy 13.961369 -205.929403) (xy 14.025379 -205.984868) (xy 14.083827 -206.046166) (xy 14.136183 -206.112742)
			(xy 14.181973 -206.183994) (xy 14.220784 -206.259275) (xy 14.252263 -206.337905) (xy 14.276124 -206.419172)
			(xy 14.292153 -206.502338) (xy 14.300204 -206.586652) (xy 14.300708 -206.629) (xy 14.300204 -206.671348)
			(xy 14.292153 -206.755662) (xy 14.276124 -206.838828) (xy 14.252263 -206.920095) (xy 14.220784 -206.998725)
			(xy 14.181973 -207.074006) (xy 14.136183 -207.145258) (xy 14.083827 -207.211834) (xy 14.025379 -207.273132)
			(xy 13.961369 -207.328597) (xy 13.892377 -207.377726) (xy 13.819027 -207.420075) (xy 13.741984 -207.455259)
			(xy 13.661945 -207.482961) (xy 13.579636 -207.502929) (xy 13.495801 -207.514982) (xy 13.4112 -207.519013)
			(xy 13.326599 -207.514982) (xy 13.242764 -207.502929) (xy 13.160455 -207.482961) (xy 13.080416 -207.455259)
			(xy 13.003373 -207.420075) (xy 12.930023 -207.377726) (xy 12.861031 -207.328597) (xy 12.797021 -207.273132)
			(xy 12.738573 -207.211834) (xy 12.686217 -207.145258) (xy 12.640427 -207.074006) (xy 12.601616 -206.998725)
			(xy 12.570137 -206.920095) (xy 12.546276 -206.838828) (xy 12.530247 -206.755662) (xy 12.522196 -206.671348)
			(xy 9.977118 -206.671348) (xy 9.996822 -206.754104) (xy 10.012804 -206.855839) (xy 10.02082 -206.958509)
			(xy 10.02082 -207.061491) (xy 10.012804 -207.164161) (xy 9.996822 -207.265896) (xy 9.972969 -207.366078)
			(xy 9.94139 -207.4641) (xy 9.902278 -207.559366) (xy 9.85587 -207.651299) (xy 9.802447 -207.739341)
			(xy 9.742333 -207.822957) (xy 9.675893 -207.901641) (xy 9.640062 -207.938624) (xy 9.632696 -207.945736)
			(xy 9.62533 -207.964024) (xy 9.62533 -208.055972) (xy 9.632696 -208.07426) (xy 9.640062 -208.081372)
			(xy 9.675889 -208.118359) (xy 9.742329 -208.197043) (xy 9.802443 -208.280659) (xy 9.855866 -208.3687)
			(xy 9.88982 -208.43596) (xy 14.546308 -208.43596) (xy 14.550338 -208.351357) (xy 14.562392 -208.26752)
			(xy 14.582361 -208.185209) (xy 14.610063 -208.105168) (xy 14.645248 -208.028123) (xy 14.687598 -207.954772)
			(xy 14.736728 -207.885778) (xy 14.792194 -207.821767) (xy 14.853494 -207.763318) (xy 14.920072 -207.710961)
			(xy 14.991325 -207.665169) (xy 15.066609 -207.626358) (xy 15.145241 -207.594879) (xy 15.226509 -207.571016)
			(xy 15.309677 -207.554987) (xy 15.393993 -207.546936) (xy 15.436342 -207.546448) (xy 15.47338 -207.546818)
			(xy 15.547203 -207.55294) (xy 15.620259 -207.565188) (xy 15.692042 -207.583476) (xy 15.727172 -207.595216)
			(xy 15.736172 -207.597938) (xy 15.754949 -207.597243) (xy 15.772212 -207.58982) (xy 15.785633 -207.576668)
			(xy 15.78991 -207.568292) (xy 15.807981 -207.530005) (xy 15.85034 -207.456694) (xy 15.899473 -207.38774)
			(xy 15.954937 -207.323767) (xy 16.016229 -207.265353) (xy 16.082794 -207.213029) (xy 16.15403 -207.167266)
			(xy 16.229292 -207.12848) (xy 16.3079 -207.097022) (xy 16.389141 -207.073175) (xy 16.47228 -207.057157)
			(xy 16.556566 -207.049111) (xy 16.5989 -207.048608) (xy 16.64026 -207.049077) (xy 16.722622 -207.056746)
			(xy 16.803917 -207.07203) (xy 16.883442 -207.094795) (xy 16.960509 -207.124846) (xy 17.034453 -207.161924)
			(xy 17.104635 -207.205706) (xy 17.170449 -207.255816) (xy 17.231325 -207.31182) (xy 17.286739 -207.373235)
			(xy 17.336211 -207.439529) (xy 17.379314 -207.51013) (xy 17.415676 -207.584429) (xy 17.444981 -207.661783)
			(xy 17.466978 -207.741523) (xy 17.474692 -207.78216) (xy 17.476978 -207.795368) (xy 17.49425 -207.816196)
			(xy 17.601692 -207.856074) (xy 17.628108 -207.851756) (xy 17.638776 -207.843374) (xy 17.672719 -207.816465)
			(xy 17.744964 -207.768668) (xy 17.821513 -207.728122) (xy 17.901642 -207.69521) (xy 17.984592 -207.670244)
			(xy 18.069575 -207.653461) (xy 18.155788 -207.64502) (xy 18.1991 -207.644492) (xy 18.240317 -207.644935)
			(xy 18.322397 -207.652561) (xy 18.40342 -207.667747) (xy 18.48269 -207.690364) (xy 18.559529 -207.720217)
			(xy 18.59661 -207.738218) (xy 18.606262 -207.743044) (xy 18.62709 -207.74406) (xy 18.716752 -207.710532)
			(xy 18.731992 -207.696054) (xy 18.736056 -207.686148) (xy 18.753186 -207.645946) (xy 18.794328 -207.568841)
			(xy 18.842835 -207.496144) (xy 18.898239 -207.428556) (xy 18.960005 -207.366729) (xy 19.027539 -207.311258)
			(xy 19.100188 -207.26268) (xy 19.177251 -207.221462) (xy 19.257987 -207.188002) (xy 19.341615 -207.162623)
			(xy 19.427329 -207.14557) (xy 19.514303 -207.137007) (xy 19.558 -207.136492) (xy 19.599102 -207.136967)
			(xy 19.680957 -207.144552) (xy 19.761762 -207.159657) (xy 19.840829 -207.182153) (xy 19.917483 -207.211849)
			(xy 19.99107 -207.248491) (xy 20.060962 -207.291766) (xy 20.126563 -207.341306) (xy 20.187313 -207.396687)
			(xy 20.242694 -207.457437) (xy 20.292234 -207.523038) (xy 20.335509 -207.59293) (xy 20.372151 -207.666517)
			(xy 20.401847 -207.743171) (xy 20.424343 -207.822238) (xy 20.439448 -207.903043) (xy 20.447033 -207.984898)
			(xy 20.447508 -208.026) (xy 20.44701 -208.067505) (xy 20.439274 -208.150154) (xy 20.42387 -208.231723)
			(xy 20.400931 -208.311501) (xy 20.370657 -208.388794) (xy 20.333312 -208.462929) (xy 20.289221 -208.533262)
			(xy 20.264374 -208.566512) (xy 20.258035 -208.575712) (xy 20.253209 -208.5975) (xy 20.258035 -208.619288)
			(xy 20.264374 -208.628488) (xy 20.289221 -208.661738) (xy 20.321724 -208.713578) (xy 22.719792 -208.713578)
			(xy 22.720349 -208.669668) (xy 22.728994 -208.582275) (xy 22.746207 -208.496159) (xy 22.771822 -208.412158)
			(xy 22.805588 -208.33109) (xy 22.847178 -208.253743) (xy 22.896186 -208.18087) (xy 22.952136 -208.11318)
			(xy 22.982936 -208.08188) (xy 22.99104 -208.072901) (xy 22.998615 -208.049972) (xy 22.997414 -208.037938)
			(xy 22.992302 -208.003431) (xy 22.986833 -207.933882) (xy 22.986492 -207.899) (xy 22.986996 -207.856652)
			(xy 22.995047 -207.772338) (xy 23.011076 -207.689172) (xy 23.034937 -207.607905) (xy 23.066416 -207.529275)
			(xy 23.105227 -207.453994) (xy 23.151017 -207.382742) (xy 23.203373 -207.316166) (xy 23.261821 -207.254868)
			(xy 23.325831 -207.199403) (xy 23.394823 -207.150274) (xy 23.468173 -207.107925) (xy 23.545216 -207.072741)
			(xy 23.625255 -207.045039) (xy 23.707564 -207.025071) (xy 23.791399 -207.013018) (xy 23.876 -207.008988)
			(xy 23.897245 -207.01) (xy 30.91815 -207.01) (xy 30.918654 -206.967652) (xy 30.926705 -206.883338)
			(xy 30.942734 -206.800172) (xy 30.966595 -206.718905) (xy 30.998074 -206.640275) (xy 31.036885 -206.564994)
			(xy 31.082675 -206.493742) (xy 31.135031 -206.427166) (xy 31.193479 -206.365868) (xy 31.257489 -206.310403)
			(xy 31.326481 -206.261274) (xy 31.399831 -206.218925) (xy 31.476874 -206.183741) (xy 31.556913 -206.156039)
			(xy 31.639222 -206.136071) (xy 31.723057 -206.124018) (xy 31.807658 -206.119988) (xy 31.892259 -206.124018)
			(xy 31.976094 -206.136071) (xy 32.058403 -206.156039) (xy 32.138442 -206.183741) (xy 32.215485 -206.218925)
			(xy 32.288835 -206.261274) (xy 32.357827 -206.310403) (xy 32.421837 -206.365868) (xy 32.480285 -206.427166)
			(xy 32.532641 -206.493742) (xy 32.578431 -206.564994) (xy 32.617242 -206.640275) (xy 32.648721 -206.718905)
			(xy 32.672582 -206.800172) (xy 32.688611 -206.883338) (xy 32.696662 -206.967652) (xy 32.697166 -207.01)
			(xy 32.696634 -207.053754) (xy 32.688039 -207.14084) (xy 32.67093 -207.22666) (xy 32.645475 -207.310385)
			(xy 32.611919 -207.391204) (xy 32.570587 -207.468336) (xy 32.521878 -207.541036) (xy 32.494474 -207.57515)
			(xy 32.488764 -207.582714) (xy 32.482901 -207.600725) (xy 32.483044 -207.610202) (xy 32.484568 -207.640174)
			(xy 32.485463 -207.649658) (xy 32.493286 -207.667013) (xy 32.499808 -207.673956) (xy 32.530974 -207.705317)
			(xy 32.587657 -207.773178) (xy 32.637325 -207.84633) (xy 32.679488 -207.92405) (xy 32.713731 -208.00557)
			(xy 32.739714 -208.090086) (xy 32.757181 -208.176763) (xy 32.76596 -208.264746) (xy 32.766508 -208.308956)
			(xy 32.766004 -208.351304) (xy 32.757953 -208.435618) (xy 32.741924 -208.518784) (xy 32.718063 -208.600051)
			(xy 32.686584 -208.678681) (xy 32.647773 -208.753962) (xy 32.601983 -208.825214) (xy 32.549627 -208.89179)
			(xy 32.491179 -208.953088) (xy 32.427169 -209.008553) (xy 32.387075 -209.037104) (xy 35.008054 -209.037104)
			(xy 35.008054 -208.952408) (xy 35.016105 -208.868094) (xy 35.032134 -208.784928) (xy 35.055995 -208.703661)
			(xy 35.087474 -208.625031) (xy 35.126285 -208.54975) (xy 35.172075 -208.478498) (xy 35.224431 -208.411922)
			(xy 35.282879 -208.350624) (xy 35.346889 -208.295159) (xy 35.415881 -208.24603) (xy 35.489231 -208.203681)
			(xy 35.566274 -208.168497) (xy 35.646313 -208.140795) (xy 35.728622 -208.120827) (xy 35.812457 -208.108774)
			(xy 35.897058 -208.104744) (xy 35.981659 -208.108774) (xy 36.065494 -208.120827) (xy 36.147803 -208.140795)
			(xy 36.227842 -208.168497) (xy 36.304885 -208.203681) (xy 36.378235 -208.24603) (xy 36.447227 -208.295159)
			(xy 36.511237 -208.350624) (xy 36.569685 -208.411922) (xy 36.622041 -208.478498) (xy 36.667831 -208.54975)
			(xy 36.706642 -208.625031) (xy 36.738121 -208.703661) (xy 36.761982 -208.784928) (xy 36.778011 -208.868094)
			(xy 36.786062 -208.952408) (xy 36.786566 -208.994756) (xy 36.786062 -209.037104) (xy 36.778011 -209.121418)
			(xy 36.761982 -209.204584) (xy 36.738121 -209.285851) (xy 36.706642 -209.364481) (xy 36.667831 -209.439762)
			(xy 36.622041 -209.511014) (xy 36.569685 -209.57759) (xy 36.511237 -209.638888) (xy 36.447227 -209.694353)
			(xy 36.378235 -209.743482) (xy 36.304885 -209.785831) (xy 36.227842 -209.821015) (xy 36.147803 -209.848717)
			(xy 36.065494 -209.868685) (xy 35.981659 -209.880738) (xy 35.897058 -209.884769) (xy 35.812457 -209.880738)
			(xy 35.728622 -209.868685) (xy 35.646313 -209.848717) (xy 35.566274 -209.821015) (xy 35.489231 -209.785831)
			(xy 35.415881 -209.743482) (xy 35.346889 -209.694353) (xy 35.282879 -209.638888) (xy 35.224431 -209.57759)
			(xy 35.172075 -209.511014) (xy 35.126285 -209.439762) (xy 35.087474 -209.364481) (xy 35.055995 -209.285851)
			(xy 35.032134 -209.204584) (xy 35.016105 -209.121418) (xy 35.008054 -209.037104) (xy 32.387075 -209.037104)
			(xy 32.358177 -209.057682) (xy 32.284827 -209.100031) (xy 32.207784 -209.135215) (xy 32.127745 -209.162917)
			(xy 32.045436 -209.182885) (xy 31.961601 -209.194938) (xy 31.877 -209.198969) (xy 31.792399 -209.194938)
			(xy 31.708564 -209.182885) (xy 31.626255 -209.162917) (xy 31.546216 -209.135215) (xy 31.469173 -209.100031)
			(xy 31.395823 -209.057682) (xy 31.326831 -209.008553) (xy 31.262821 -208.953088) (xy 31.204373 -208.89179)
			(xy 31.152017 -208.825214) (xy 31.106227 -208.753962) (xy 31.067416 -208.678681) (xy 31.035937 -208.600051)
			(xy 31.012076 -208.518784) (xy 30.996047 -208.435618) (xy 30.987996 -208.351304) (xy 30.987492 -208.308956)
			(xy 30.988007 -208.265201) (xy 30.996607 -208.178115) (xy 31.013719 -208.092295) (xy 31.039177 -208.008571)
			(xy 31.072735 -207.927752) (xy 31.11407 -207.850619) (xy 31.16278 -207.77792) (xy 31.190184 -207.743806)
			(xy 31.195864 -207.736222) (xy 31.201746 -207.718227) (xy 31.201614 -207.708754) (xy 31.20009 -207.678782)
			(xy 31.199227 -207.669292) (xy 31.191383 -207.651939) (xy 31.18485 -207.645) (xy 31.153654 -207.613667)
			(xy 31.096975 -207.545801) (xy 31.04731 -207.472644) (xy 31.005151 -207.39492) (xy 30.970912 -207.313396)
			(xy 30.944933 -207.228877) (xy 30.92747 -207.142196) (xy 30.918695 -207.054211) (xy 30.91815 -207.01)
			(xy 23.897245 -207.01) (xy 23.960601 -207.013018) (xy 24.044436 -207.025071) (xy 24.126745 -207.045039)
			(xy 24.206784 -207.072741) (xy 24.283827 -207.107925) (xy 24.357177 -207.150274) (xy 24.426169 -207.199403)
			(xy 24.490179 -207.254868) (xy 24.548627 -207.316166) (xy 24.600983 -207.382742) (xy 24.646773 -207.453994)
			(xy 24.685584 -207.529275) (xy 24.717063 -207.607905) (xy 24.740924 -207.689172) (xy 24.756953 -207.772338)
			(xy 24.765004 -207.856652) (xy 24.765508 -207.899) (xy 24.765003 -207.942911) (xy 24.75635 -208.030306)
			(xy 24.739129 -208.116423) (xy 24.713507 -208.200424) (xy 24.679734 -208.281493) (xy 24.638137 -208.358839)
			(xy 24.589123 -208.431711) (xy 24.533167 -208.499399) (xy 24.502364 -208.530698) (xy 24.494217 -208.539645)
			(xy 24.486666 -208.5626) (xy 24.487886 -208.57464) (xy 24.492995 -208.609147) (xy 24.498466 -208.678696)
			(xy 24.498808 -208.713578) (xy 24.498402 -208.751729) (xy 24.491869 -208.82775) (xy 24.47885 -208.902933)
			(xy 24.45944 -208.976725) (xy 24.446992 -209.01279) (xy 24.443925 -209.022517) (xy 24.445061 -209.042866)
			(xy 24.454058 -209.061153) (xy 24.46147 -209.068162) (xy 24.492845 -209.096293) (xy 24.550753 -209.157517)
			(xy 24.602612 -209.223943) (xy 24.647959 -209.294974) (xy 24.686387 -209.369974) (xy 24.701197 -209.407182)
			(xy 24.891996 -209.407182) (xy 24.891996 -209.322486) (xy 24.900047 -209.238172) (xy 24.916076 -209.155006)
			(xy 24.939937 -209.073739) (xy 24.971416 -208.995109) (xy 25.010227 -208.919828) (xy 25.056017 -208.848576)
			(xy 25.108373 -208.782) (xy 25.166821 -208.720702) (xy 25.230831 -208.665237) (xy 25.299823 -208.616108)
			(xy 25.373173 -208.573759) (xy 25.450216 -208.538575) (xy 25.530255 -208.510873) (xy 25.612564 -208.490905)
			(xy 25.696399 -208.478852) (xy 25.781 -208.474822) (xy 25.865601 -208.478852) (xy 25.949436 -208.490905)
			(xy 26.031745 -208.510873) (xy 26.111784 -208.538575) (xy 26.188827 -208.573759) (xy 26.262177 -208.616108)
			(xy 26.331169 -208.665237) (xy 26.395179 -208.720702) (xy 26.453627 -208.782) (xy 26.505983 -208.848576)
			(xy 26.551773 -208.919828) (xy 26.590584 -208.995109) (xy 26.622063 -209.073739) (xy 26.645924 -209.155006)
			(xy 26.661953 -209.238172) (xy 26.670004 -209.322486) (xy 26.670508 -209.364834) (xy 26.670004 -209.407182)
			(xy 26.661953 -209.491496) (xy 26.645924 -209.574662) (xy 26.622063 -209.655929) (xy 26.590584 -209.734559)
			(xy 26.551773 -209.80984) (xy 26.505983 -209.881092) (xy 26.453627 -209.947668) (xy 26.395179 -210.008966)
			(xy 26.331169 -210.064431) (xy 26.262177 -210.11356) (xy 26.188827 -210.155909) (xy 26.111784 -210.191093)
			(xy 26.031745 -210.218795) (xy 25.949436 -210.238763) (xy 25.865601 -210.250816) (xy 25.781 -210.254847)
			(xy 25.696399 -210.250816) (xy 25.612564 -210.238763) (xy 25.530255 -210.218795) (xy 25.450216 -210.191093)
			(xy 25.373173 -210.155909) (xy 25.299823 -210.11356) (xy 25.230831 -210.064431) (xy 25.166821 -210.008966)
			(xy 25.108373 -209.947668) (xy 25.056017 -209.881092) (xy 25.010227 -209.80984) (xy 24.971416 -209.734559)
			(xy 24.939937 -209.655929) (xy 24.916076 -209.574662) (xy 24.900047 -209.491496) (xy 24.891996 -209.407182)
			(xy 24.701197 -209.407182) (xy 24.717552 -209.448272) (xy 24.741174 -209.529165) (xy 24.757041 -209.61193)
			(xy 24.765013 -209.695824) (xy 24.765508 -209.73796) (xy 24.765004 -209.780308) (xy 24.756953 -209.864622)
			(xy 24.740924 -209.947788) (xy 24.717063 -210.029055) (xy 24.685584 -210.107685) (xy 24.646773 -210.182966)
			(xy 24.600983 -210.254218) (xy 24.548627 -210.320794) (xy 24.490179 -210.382092) (xy 24.426169 -210.437557)
			(xy 24.357177 -210.486686) (xy 24.283827 -210.529035) (xy 24.206784 -210.564219) (xy 24.126745 -210.591921)
			(xy 24.114235 -210.594956) (xy 30.352492 -210.594956) (xy 30.352996 -210.552608) (xy 30.361047 -210.468294)
			(xy 30.377076 -210.385128) (xy 30.400937 -210.303861) (xy 30.432416 -210.225231) (xy 30.471227 -210.14995)
			(xy 30.517017 -210.078698) (xy 30.569373 -210.012122) (xy 30.627821 -209.950824) (xy 30.691831 -209.895359)
			(xy 30.760823 -209.84623) (xy 30.834173 -209.803881) (xy 30.911216 -209.768697) (xy 30.991255 -209.740995)
			(xy 31.073564 -209.721027) (xy 31.157399 -209.708974) (xy 31.242 -209.704944) (xy 31.326601 -209.708974)
			(xy 31.410436 -209.721027) (xy 31.492745 -209.740995) (xy 31.572784 -209.768697) (xy 31.649827 -209.803881)
			(xy 31.723177 -209.84623) (xy 31.792169 -209.895359) (xy 31.856179 -209.950824) (xy 31.905265 -210.002304)
			(xy 33.350196 -210.002304) (xy 33.350196 -209.917608) (xy 33.358247 -209.833294) (xy 33.374276 -209.750128)
			(xy 33.398137 -209.668861) (xy 33.429616 -209.590231) (xy 33.468427 -209.51495) (xy 33.514217 -209.443698)
			(xy 33.566573 -209.377122) (xy 33.625021 -209.315824) (xy 33.689031 -209.260359) (xy 33.758023 -209.21123)
			(xy 33.831373 -209.168881) (xy 33.908416 -209.133697) (xy 33.988455 -209.105995) (xy 34.070764 -209.086027)
			(xy 34.154599 -209.073974) (xy 34.2392 -209.069944) (xy 34.323801 -209.073974) (xy 34.407636 -209.086027)
			(xy 34.489945 -209.105995) (xy 34.569984 -209.133697) (xy 34.647027 -209.168881) (xy 34.720377 -209.21123)
			(xy 34.789369 -209.260359) (xy 34.853379 -209.315824) (xy 34.911827 -209.377122) (xy 34.964183 -209.443698)
			(xy 35.009973 -209.51495) (xy 35.048784 -209.590231) (xy 35.080263 -209.668861) (xy 35.104124 -209.750128)
			(xy 35.120153 -209.833294) (xy 35.128204 -209.917608) (xy 35.128708 -209.959956) (xy 35.128204 -210.002304)
			(xy 35.120153 -210.086618) (xy 35.104124 -210.169784) (xy 35.080263 -210.251051) (xy 35.048784 -210.329681)
			(xy 35.009973 -210.404962) (xy 34.964183 -210.476214) (xy 34.911827 -210.54279) (xy 34.853379 -210.604088)
			(xy 34.789369 -210.659553) (xy 34.720377 -210.708682) (xy 34.647027 -210.751031) (xy 34.569984 -210.786215)
			(xy 34.489945 -210.813917) (xy 34.407636 -210.833885) (xy 34.323801 -210.845938) (xy 34.2392 -210.849969)
			(xy 34.154599 -210.845938) (xy 34.070764 -210.833885) (xy 33.988455 -210.813917) (xy 33.908416 -210.786215)
			(xy 33.831373 -210.751031) (xy 33.758023 -210.708682) (xy 33.689031 -210.659553) (xy 33.625021 -210.604088)
			(xy 33.566573 -210.54279) (xy 33.514217 -210.476214) (xy 33.468427 -210.404962) (xy 33.429616 -210.329681)
			(xy 33.398137 -210.251051) (xy 33.374276 -210.169784) (xy 33.358247 -210.086618) (xy 33.350196 -210.002304)
			(xy 31.905265 -210.002304) (xy 31.914627 -210.012122) (xy 31.966983 -210.078698) (xy 32.012773 -210.14995)
			(xy 32.051584 -210.225231) (xy 32.083063 -210.303861) (xy 32.106924 -210.385128) (xy 32.122953 -210.468294)
			(xy 32.131004 -210.552608) (xy 32.131508 -210.594956) (xy 32.130965 -210.639727) (xy 32.121968 -210.728816)
			(xy 32.104061 -210.816549) (xy 32.077424 -210.902037) (xy 32.060388 -210.943444) (xy 32.055816 -210.954366)
			(xy 32.056832 -210.977734) (xy 32.074853 -211.009992) (xy 41.678606 -211.009992) (xy 41.679105 -210.958501)
			(xy 41.687121 -210.855831) (xy 41.703104 -210.754096) (xy 41.726957 -210.653915) (xy 41.758535 -210.555893)
			(xy 41.797647 -210.460627) (xy 41.844055 -210.368694) (xy 41.897477 -210.280652) (xy 41.957591 -210.197036)
			(xy 42.02403 -210.118352) (xy 42.05986 -210.081368) (xy 42.067226 -210.074256) (xy 42.074592 -210.055968)
			(xy 42.074592 -209.96402) (xy 42.067226 -209.945732) (xy 42.05986 -209.93862) (xy 42.024026 -209.90164)
			(xy 41.957587 -209.822956) (xy 41.897475 -209.739338) (xy 41.844053 -209.651296) (xy 41.797645 -209.559363)
			(xy 41.758534 -209.464096) (xy 41.726957 -209.366075) (xy 41.703105 -209.265893) (xy 41.687122 -209.164158)
			(xy 41.679107 -209.061488) (xy 41.679107 -208.958506) (xy 41.687123 -208.855836) (xy 41.703106 -208.754102)
			(xy 41.726958 -208.65392) (xy 41.758536 -208.555898) (xy 41.797648 -208.460632) (xy 41.844055 -208.368699)
			(xy 41.897478 -208.280657) (xy 41.957591 -208.19704) (xy 42.02403 -208.118356) (xy 42.05986 -208.081372)
			(xy 42.067226 -208.07426) (xy 42.074592 -208.055972) (xy 42.074592 -207.964024) (xy 42.067226 -207.945736)
			(xy 42.05986 -207.938624) (xy 42.02403 -207.90164) (xy 41.957591 -207.822956) (xy 41.897479 -207.739339)
			(xy 41.844056 -207.651297) (xy 41.797649 -207.559364) (xy 41.758538 -207.464098) (xy 41.72696 -207.366077)
			(xy 41.703108 -207.265895) (xy 41.687126 -207.164161) (xy 41.67911 -207.061491) (xy 41.67911 -206.958509)
			(xy 41.687126 -206.855839) (xy 41.703108 -206.754105) (xy 41.72696 -206.653923) (xy 41.758538 -206.555902)
			(xy 41.797649 -206.460636) (xy 41.844056 -206.368703) (xy 41.897479 -206.280661) (xy 41.957591 -206.197044)
			(xy 42.02403 -206.11836) (xy 42.05986 -206.081376) (xy 42.067226 -206.074264) (xy 42.074592 -206.055976)
			(xy 42.074592 -205.964028) (xy 42.067226 -205.94574) (xy 42.05986 -205.938628) (xy 42.024034 -205.901641)
			(xy 41.957595 -205.822957) (xy 41.897483 -205.73934) (xy 41.84406 -205.651298) (xy 41.797653 -205.559366)
			(xy 41.758541 -205.4641) (xy 41.726964 -205.366079) (xy 41.703111 -205.265897) (xy 41.687129 -205.164163)
			(xy 41.679113 -205.061494) (xy 41.679113 -204.958512) (xy 41.687128 -204.855842) (xy 41.70311 -204.754108)
			(xy 41.726962 -204.653927) (xy 41.758539 -204.555905) (xy 41.79765 -204.460639) (xy 41.844058 -204.368707)
			(xy 41.897479 -204.280665) (xy 41.957592 -204.197048) (xy 42.02403 -204.118364) (xy 42.05986 -204.08138)
			(xy 42.067226 -204.074268) (xy 42.074592 -204.05598) (xy 42.074592 -203.964032) (xy 42.067226 -203.945744)
			(xy 42.05986 -203.938632) (xy 42.024038 -203.901641) (xy 41.957599 -203.822957) (xy 41.897486 -203.739341)
			(xy 41.844064 -203.6513) (xy 41.797656 -203.559367) (xy 41.758545 -203.464102) (xy 41.726967 -203.366081)
			(xy 41.703115 -203.2659) (xy 41.687132 -203.164166) (xy 41.679116 -203.061497) (xy 41.679115 -202.958515)
			(xy 41.68713 -202.855846) (xy 41.703112 -202.754112) (xy 41.726964 -202.65393) (xy 41.758541 -202.555909)
			(xy 41.797652 -202.460643) (xy 41.844059 -202.36871) (xy 41.89748 -202.280669) (xy 41.957592 -202.197052)
			(xy 42.02403 -202.118368) (xy 42.05986 -202.081384) (xy 42.067226 -202.074272) (xy 42.074592 -202.055984)
			(xy 42.074592 -201.964036) (xy 42.067226 -201.945748) (xy 42.05986 -201.938636) (xy 42.024042 -201.901641)
			(xy 41.957603 -201.822958) (xy 41.89749 -201.739342) (xy 41.844068 -201.651301) (xy 41.79766 -201.559369)
			(xy 41.758549 -201.464103) (xy 41.726971 -201.366083) (xy 41.703118 -201.265902) (xy 41.687135 -201.164168)
			(xy 41.679119 -201.061499) (xy 41.679118 -200.958518) (xy 41.687133 -200.855849) (xy 41.703115 -200.754115)
			(xy 41.726966 -200.653934) (xy 41.758543 -200.555913) (xy 41.797653 -200.460647) (xy 41.84406 -200.368714)
			(xy 41.897481 -200.280673) (xy 41.957593 -200.197056) (xy 42.024031 -200.118372) (xy 42.05986 -200.081388)
			(xy 42.067226 -200.074276) (xy 42.074592 -200.055988) (xy 42.074592 -199.96404) (xy 42.067226 -199.945752)
			(xy 42.05986 -199.93864) (xy 42.024046 -199.901641) (xy 41.957607 -199.822958) (xy 41.897494 -199.739343)
			(xy 41.844072 -199.651302) (xy 41.797664 -199.55937) (xy 41.758552 -199.464105) (xy 41.726974 -199.366085)
			(xy 41.703121 -199.265904) (xy 41.687138 -199.164171) (xy 41.679122 -199.061502) (xy 41.679121 -198.958521)
			(xy 41.687135 -198.855852) (xy 41.703117 -198.754118) (xy 41.726968 -198.653937) (xy 41.758544 -198.555916)
			(xy 41.797654 -198.460651) (xy 41.844061 -198.368718) (xy 41.897482 -198.280676) (xy 41.957593 -198.19706)
			(xy 42.024031 -198.118376) (xy 42.05986 -198.081392) (xy 42.067226 -198.07428) (xy 42.074592 -198.055992)
			(xy 42.074592 -197.964044) (xy 42.067226 -197.945756) (xy 42.05986 -197.938644) (xy 42.024032 -197.901658)
			(xy 41.957592 -197.822975) (xy 41.897478 -197.739358) (xy 41.844055 -197.651317) (xy 41.797646 -197.559384)
			(xy 41.758534 -197.464118) (xy 41.726955 -197.366097) (xy 41.703101 -197.265915) (xy 41.687117 -197.164181)
			(xy 41.6791 -197.061511) (xy 41.678606 -197.01002) (xy 41.679108 -196.958125) (xy 41.68725 -196.854655)
			(xy 41.703485 -196.752143) (xy 41.727713 -196.651221) (xy 41.759785 -196.55251) (xy 41.799502 -196.456621)
			(xy 41.846621 -196.364143) (xy 41.900851 -196.275647) (xy 41.961856 -196.191679) (xy 42.029262 -196.112757)
			(xy 42.102652 -196.039366) (xy 42.181575 -195.97196) (xy 42.265542 -195.910954) (xy 42.354038 -195.856724)
			(xy 42.446515 -195.809605) (xy 42.542405 -195.769887) (xy 42.641115 -195.737814) (xy 42.742037 -195.713586)
			(xy 42.844549 -195.69735) (xy 42.948019 -195.689208) (xy 42.999914 -195.688712) (xy 43.061128 -195.690236)
			(xy 43.070487 -195.690319) (xy 43.088232 -195.684402) (xy 43.102677 -195.672516) (xy 43.111902 -195.656243)
			(xy 43.113706 -195.647056) (xy 43.120703 -195.605613) (xy 43.141351 -195.524138) (xy 43.169593 -195.444973)
			(xy 43.205175 -195.368825) (xy 43.247781 -195.296373) (xy 43.297031 -195.228262) (xy 43.352486 -195.165101)
			(xy 43.413651 -195.107451) (xy 43.479981 -195.055828) (xy 43.550885 -195.010692) (xy 43.62573 -194.972445)
			(xy 43.703849 -194.941427) (xy 43.784545 -194.917917) (xy 43.867099 -194.902122) (xy 43.950774 -194.894185)
			(xy 43.9928 -194.893692) (xy 44.034849 -194.894223) (xy 44.118571 -194.902169) (xy 44.201169 -194.917982)
			(xy 44.281906 -194.941519) (xy 44.360061 -194.972571) (xy 44.434937 -195.010861) (xy 44.505864 -195.056046)
			(xy 44.572211 -195.107724) (xy 44.633384 -195.165433) (xy 44.688838 -195.228658) (xy 44.738077 -195.296834)
			(xy 44.780661 -195.369353) (xy 44.816212 -195.445568) (xy 44.844411 -195.524797) (xy 44.865006 -195.606334)
			(xy 44.871894 -195.647818) (xy 44.873775 -195.657018) (xy 44.883153 -195.673266) (xy 44.89774 -195.685063)
			(xy 44.915591 -195.690834) (xy 44.92498 -195.690744) (xy 44.943697 -195.689767) (xy 44.981168 -195.688752)
			(xy 44.99991 -195.688712) (xy 45.051805 -195.689179) (xy 45.155276 -195.697323) (xy 45.257789 -195.71356)
			(xy 45.358712 -195.737791) (xy 45.457423 -195.769865) (xy 45.553313 -195.809585) (xy 45.645791 -195.856706)
			(xy 45.734287 -195.910937) (xy 45.818255 -195.971945) (xy 45.897177 -196.039353) (xy 45.970568 -196.112745)
			(xy 46.037973 -196.191669) (xy 46.098979 -196.275638) (xy 46.153209 -196.364135) (xy 46.200328 -196.456614)
			(xy 46.240045 -196.552505) (xy 46.272117 -196.651217) (xy 46.296345 -196.75214) (xy 46.31258 -196.854653)
			(xy 46.320722 -196.958125) (xy 46.321218 -197.01002) (xy 46.32072 -197.061511) (xy 46.312703 -197.164181)
			(xy 46.29672 -197.265915) (xy 46.272866 -197.366097) (xy 46.241288 -197.464118) (xy 46.202176 -197.559384)
			(xy 46.155768 -197.651317) (xy 46.102346 -197.739359) (xy 46.042233 -197.822976) (xy 45.975794 -197.90166)
			(xy 45.939964 -197.938644) (xy 45.932598 -197.945756) (xy 45.925232 -197.964044) (xy 45.925232 -198.055992)
			(xy 45.932598 -198.07428) (xy 45.939964 -198.081392) (xy 45.975812 -198.118359) (xy 46.042254 -198.197043)
			(xy 46.10237 -198.28066) (xy 46.155795 -198.368703) (xy 46.202205 -198.460637) (xy 46.241318 -198.555905)
			(xy 46.272896 -198.653928) (xy 46.29675 -198.754111) (xy 46.312732 -198.855848) (xy 46.320748 -198.958519)
			(xy 46.320747 -199.061503) (xy 46.31273 -199.164175) (xy 46.296745 -199.265911) (xy 46.27289 -199.366094)
			(xy 46.24131 -199.464117) (xy 46.202195 -199.559384) (xy 46.155784 -199.651317) (xy 46.102357 -199.739359)
			(xy 46.04224 -199.822974) (xy 45.975796 -199.901657) (xy 45.939964 -199.93864) (xy 45.932598 -199.945752)
			(xy 45.925232 -199.96404) (xy 45.925232 -200.055988) (xy 45.932598 -200.074276) (xy 45.939964 -200.081388)
			(xy 45.975808 -200.118359) (xy 46.04225 -200.197043) (xy 46.102366 -200.28066) (xy 46.155791 -200.368702)
			(xy 46.202201 -200.460636) (xy 46.241314 -200.555903) (xy 46.272893 -200.653926) (xy 46.296746 -200.754109)
			(xy 46.312729 -200.855845) (xy 46.320745 -200.958517) (xy 46.320744 -201.0615) (xy 46.312727 -201.164172)
			(xy 46.296743 -201.265908) (xy 46.272888 -201.366091) (xy 46.241308 -201.464113) (xy 46.202194 -201.55938)
			(xy 46.155783 -201.651313) (xy 46.102356 -201.739355) (xy 46.042239 -201.822971) (xy 45.975796 -201.901653)
			(xy 45.939964 -201.938636) (xy 45.932598 -201.945748) (xy 45.925232 -201.964036) (xy 45.925232 -202.055984)
			(xy 45.932598 -202.074272) (xy 45.939964 -202.081384) (xy 45.975804 -202.118359) (xy 46.042246 -202.197042)
			(xy 46.102362 -202.280659) (xy 46.155787 -202.368701) (xy 46.202197 -202.460634) (xy 46.24131 -202.555901)
			(xy 46.27289 -202.653924) (xy 46.296743 -202.754107) (xy 46.312726 -202.855843) (xy 46.320742 -202.958514)
			(xy 46.320741 -203.061498) (xy 46.312725 -203.164169) (xy 46.296741 -203.265904) (xy 46.272886 -203.366087)
			(xy 46.241306 -203.464109) (xy 46.202192 -203.559376) (xy 46.155782 -203.651309) (xy 46.102356 -203.739351)
			(xy 46.042239 -203.822967) (xy 45.975796 -203.901649) (xy 45.939964 -203.938632) (xy 45.932598 -203.945744)
			(xy 45.925232 -203.964032) (xy 45.925232 -204.05598) (xy 45.932598 -204.074268) (xy 45.939964 -204.08138)
			(xy 45.9758 -204.118359) (xy 46.042242 -204.197042) (xy 46.102358 -204.280658) (xy 46.155783 -204.3687)
			(xy 46.202193 -204.460633) (xy 46.241307 -204.5559) (xy 46.272886 -204.653922) (xy 46.29674 -204.754104)
			(xy 46.312723 -204.85584) (xy 46.320739 -204.958511) (xy 46.320739 -205.061495) (xy 46.312722 -205.164166)
			(xy 46.296739 -205.265901) (xy 46.272885 -205.366084) (xy 46.241305 -205.464106) (xy 46.202191 -205.559372)
			(xy 46.155781 -205.651305) (xy 46.102355 -205.739347) (xy 46.042238 -205.822963) (xy 45.975796 -205.901645)
			(xy 45.939964 -205.938628) (xy 45.932598 -205.94574) (xy 45.925232 -205.964028) (xy 45.925232 -206.055976)
			(xy 45.932598 -206.074264) (xy 45.939964 -206.081376) (xy 45.975796 -206.118359) (xy 46.042238 -206.197041)
			(xy 46.102354 -206.280657) (xy 46.155779 -206.368699) (xy 46.20219 -206.460631) (xy 46.241303 -206.555898)
			(xy 46.272883 -206.65392) (xy 46.296736 -206.754102) (xy 46.31272 -206.855838) (xy 46.320736 -206.958508)
			(xy 46.320736 -207.061492) (xy 46.31272 -207.164162) (xy 46.296736 -207.265898) (xy 46.272883 -207.36608)
			(xy 46.241303 -207.464102) (xy 46.20219 -207.559369) (xy 46.155779 -207.651301) (xy 46.102354 -207.739343)
			(xy 46.042238 -207.822959) (xy 45.975796 -207.901641) (xy 45.939964 -207.938624) (xy 45.932598 -207.945736)
			(xy 45.925232 -207.964024) (xy 45.925232 -208.055972) (xy 45.932598 -208.07426) (xy 45.939964 -208.081372)
			(xy 45.975792 -208.118358) (xy 46.042234 -208.197041) (xy 46.10235 -208.280656) (xy 46.155776 -208.368697)
			(xy 46.202186 -208.46063) (xy 46.2413 -208.555896) (xy 46.272879 -208.653918) (xy 46.296733 -208.7541)
			(xy 46.312717 -208.855835) (xy 46.320733 -208.958506) (xy 46.320733 -209.061489) (xy 46.312717 -209.164159)
			(xy 46.296734 -209.265894) (xy 46.272881 -209.366077) (xy 46.241301 -209.464099) (xy 46.202188 -209.559365)
			(xy 46.155778 -209.651298) (xy 46.102353 -209.739339) (xy 46.042238 -209.822955) (xy 45.975796 -209.901637)
			(xy 45.939964 -209.93862) (xy 45.932598 -209.945732) (xy 45.925232 -209.96402) (xy 45.925232 -210.055968)
			(xy 45.932598 -210.074256) (xy 45.939964 -210.081368) (xy 45.975784 -210.118362) (xy 46.042226 -210.197043)
			(xy 46.102342 -210.280658) (xy 46.155767 -210.368698) (xy 46.202177 -210.46063) (xy 46.24129 -210.555895)
			(xy 46.27287 -210.653916) (xy 46.296724 -210.754097) (xy 46.312708 -210.855831) (xy 46.320725 -210.958501)
			(xy 46.321218 -211.009992) (xy 46.320747 -211.060811) (xy 46.312938 -211.162149) (xy 46.297366 -211.262588)
			(xy 46.274123 -211.361533) (xy 46.243346 -211.458399) (xy 46.205217 -211.552615) (xy 46.159962 -211.643622)
			(xy 46.107847 -211.730883) (xy 46.049182 -211.813882) (xy 45.984314 -211.892128) (xy 45.913625 -211.965158)
			(xy 45.837533 -212.032541) (xy 45.756489 -212.093878) (xy 45.670972 -212.148807) (xy 45.581487 -212.197003)
			(xy 45.488564 -212.23818) (xy 45.392751 -212.272096) (xy 45.294616 -212.29855) (xy 45.244766 -212.30844)
			(xy 45.233336 -212.310472) (xy 45.215048 -212.32368) (xy 45.16628 -212.41258) (xy 45.164756 -212.435186)
			(xy 45.169074 -212.445854) (xy 45.187081 -212.492535) (xy 45.21649 -212.588178) (xy 45.238206 -212.685855)
			(xy 45.252093 -212.784949) (xy 45.258064 -212.884833) (xy 45.256079 -212.984876) (xy 45.246151 -213.084444)
			(xy 45.228345 -213.182909) (xy 45.202771 -213.279648) (xy 45.169592 -213.37405) (xy 45.129017 -213.465516)
			(xy 45.081303 -213.55347) (xy 45.026752 -213.637355) (xy 44.965709 -213.71664) (xy 44.898559 -213.790825)
			(xy 44.825728 -213.85944) (xy 44.747674 -213.922051) (xy 44.664894 -213.978263) (xy 44.577908 -214.02772)
			(xy 44.487268 -214.070109) (xy 44.393547 -214.105163) (xy 44.297337 -214.13266) (xy 44.199246 -214.152426)
			(xy 44.099895 -214.164335) (xy 43.999912 -214.168313) (xy 43.899929 -214.164335) (xy 43.800578 -214.152426)
			(xy 43.702487 -214.13266) (xy 43.606277 -214.105163) (xy 43.512556 -214.070109) (xy 43.421916 -214.02772)
			(xy 43.33493 -213.978263) (xy 43.25215 -213.922051) (xy 43.174096 -213.85944) (xy 43.101265 -213.790825)
			(xy 43.034115 -213.71664) (xy 42.973072 -213.637355) (xy 42.918521 -213.55347) (xy 42.870807 -213.465516)
			(xy 42.830232 -213.37405) (xy 42.797053 -213.279648) (xy 42.771479 -213.182909) (xy 42.753673 -213.084444)
			(xy 42.743745 -212.984876) (xy 42.74176 -212.884833) (xy 42.747731 -212.784949) (xy 42.761618 -212.685855)
			(xy 42.783334 -212.588178) (xy 42.812743 -212.492535) (xy 42.83075 -212.445854) (xy 42.835068 -212.435186)
			(xy 42.833544 -212.41258) (xy 42.784776 -212.32368) (xy 42.766488 -212.310472) (xy 42.755058 -212.30844)
			(xy 42.705198 -212.298599) (xy 42.607063 -212.27214) (xy 42.511252 -212.238219) (xy 42.418329 -212.197036)
			(xy 42.328846 -212.148836) (xy 42.24333 -212.093903) (xy 42.162287 -212.032562) (xy 42.086198 -211.965176)
			(xy 42.01551 -211.892143) (xy 41.950643 -211.813894) (xy 41.89198 -211.730893) (xy 41.839867 -211.64363)
			(xy 41.794613 -211.552621) (xy 41.756485 -211.458404) (xy 41.725709 -211.361536) (xy 41.702466 -211.26259)
			(xy 41.686895 -211.162151) (xy 41.679086 -211.060812) (xy 41.678606 -211.009992) (xy 32.074853 -211.009992)
			(xy 32.107632 -211.068666) (xy 32.126682 -211.081874) (xy 32.138366 -211.083652) (xy 32.179902 -211.090461)
			(xy 32.261538 -211.110989) (xy 32.340869 -211.139136) (xy 32.417186 -211.174651) (xy 32.489808 -211.217216)
			(xy 32.558084 -211.266451) (xy 32.621404 -211.321915) (xy 32.679201 -211.383113) (xy 32.730959 -211.449497)
			(xy 32.776215 -211.520473) (xy 32.814564 -211.595407) (xy 32.845663 -211.673628) (xy 32.869233 -211.754437)
			(xy 32.885065 -211.837112) (xy 32.893017 -211.920912) (xy 32.893508 -211.963) (xy 32.893004 -212.005348)
			(xy 32.884953 -212.089662) (xy 32.868924 -212.172828) (xy 32.845063 -212.254095) (xy 32.813584 -212.332725)
			(xy 32.774773 -212.408006) (xy 32.728983 -212.479258) (xy 32.676627 -212.545834) (xy 32.618179 -212.607132)
			(xy 32.554169 -212.662597) (xy 32.485177 -212.711726) (xy 32.411827 -212.754075) (xy 32.334784 -212.789259)
			(xy 32.254745 -212.816961) (xy 32.172436 -212.836929) (xy 32.088601 -212.848982) (xy 32.004 -212.853013)
			(xy 31.919399 -212.848982) (xy 31.835564 -212.836929) (xy 31.753255 -212.816961) (xy 31.673216 -212.789259)
			(xy 31.596173 -212.754075) (xy 31.522823 -212.711726) (xy 31.453831 -212.662597) (xy 31.389821 -212.607132)
			(xy 31.331373 -212.545834) (xy 31.279017 -212.479258) (xy 31.233227 -212.408006) (xy 31.194416 -212.332725)
			(xy 31.162937 -212.254095) (xy 31.139076 -212.172828) (xy 31.123047 -212.089662) (xy 31.114996 -212.005348)
			(xy 31.114492 -211.963) (xy 31.115055 -211.91823) (xy 31.124046 -211.829141) (xy 31.141948 -211.741408)
			(xy 31.168579 -211.655919) (xy 31.185612 -211.614512) (xy 31.190184 -211.60359) (xy 31.189168 -211.580222)
			(xy 31.138368 -211.48929) (xy 31.119318 -211.476082) (xy 31.107634 -211.474304) (xy 31.066108 -211.467441)
			(xy 30.984475 -211.446915) (xy 30.905146 -211.41877) (xy 30.828831 -211.383258) (xy 30.756211 -211.340696)
			(xy 30.687936 -211.291465) (xy 30.624617 -211.236005) (xy 30.56682 -211.174811) (xy 30.515061 -211.108432)
			(xy 30.469804 -211.03746) (xy 30.431454 -210.962531) (xy 30.400352 -210.884314) (xy 30.376778 -210.80351)
			(xy 30.360942 -210.720839) (xy 30.352986 -210.637043) (xy 30.352492 -210.594956) (xy 24.114235 -210.594956)
			(xy 24.044436 -210.611889) (xy 23.960601 -210.623942) (xy 23.876 -210.627973) (xy 23.791399 -210.623942)
			(xy 23.707564 -210.611889) (xy 23.625255 -210.591921) (xy 23.545216 -210.564219) (xy 23.468173 -210.529035)
			(xy 23.394823 -210.486686) (xy 23.325831 -210.437557) (xy 23.261821 -210.382092) (xy 23.203373 -210.320794)
			(xy 23.151017 -210.254218) (xy 23.105227 -210.182966) (xy 23.066416 -210.107685) (xy 23.034937 -210.029055)
			(xy 23.011076 -209.947788) (xy 22.995047 -209.864622) (xy 22.986996 -209.780308) (xy 22.986492 -209.73796)
			(xy 22.986909 -209.699809) (xy 22.993439 -209.623788) (xy 23.006455 -209.548605) (xy 23.025862 -209.474814)
			(xy 23.038308 -209.438748) (xy 23.041342 -209.429013) (xy 23.040219 -209.408671) (xy 23.031236 -209.390385)
			(xy 23.02383 -209.383376) (xy 22.992425 -209.355278) (xy 22.934518 -209.294049) (xy 22.882661 -209.227619)
			(xy 22.837316 -209.156584) (xy 22.798892 -209.081579) (xy 22.767731 -209.003277) (xy 22.744113 -208.92238)
			(xy 22.72825 -208.839612) (xy 22.720284 -208.755715) (xy 22.719792 -208.713578) (xy 20.321724 -208.713578)
			(xy 20.333317 -208.732069) (xy 20.370667 -208.806204) (xy 20.400944 -208.883496) (xy 20.423885 -208.963275)
			(xy 20.439292 -209.044844) (xy 20.447028 -209.127494) (xy 20.447508 -209.169) (xy 20.446922 -209.213977)
			(xy 20.437827 -209.30347) (xy 20.419759 -209.39159) (xy 20.406868 -209.434684) (xy 20.403566 -209.445352)
			(xy 20.406106 -209.466434) (xy 20.456652 -209.550762) (xy 20.474178 -209.562954) (xy 20.4851 -209.564986)
			(xy 20.525337 -209.573108) (xy 20.604255 -209.595704) (xy 20.680755 -209.625477) (xy 20.754187 -209.662173)
			(xy 20.823924 -209.705479) (xy 20.889374 -209.755027) (xy 20.94998 -209.810396) (xy 21.005225 -209.871114)
			(xy 21.054641 -209.936664) (xy 21.097806 -210.006489) (xy 21.134352 -210.079994) (xy 21.16397 -210.156555)
			(xy 21.186407 -210.235519) (xy 21.201471 -210.316215) (xy 21.209036 -210.397955) (xy 21.209508 -210.439)
			(xy 21.208935 -210.483324) (xy 21.200075 -210.571529) (xy 21.182492 -210.658416) (xy 21.156362 -210.743126)
			(xy 21.139658 -210.784186) (xy 21.135848 -210.793584) (xy 21.135594 -210.813142) (xy 21.169122 -210.897978)
			(xy 21.182584 -210.912202) (xy 21.191728 -210.916266) (xy 21.230401 -210.934173) (xy 21.304486 -210.976306)
			(xy 21.374202 -211.025333) (xy 21.43891 -211.080802) (xy 21.498016 -211.142205) (xy 21.550978 -211.20898)
			(xy 21.597312 -211.280513) (xy 21.636591 -211.356151) (xy 21.668457 -211.435198) (xy 21.692617 -211.51693)
			(xy 21.708849 -211.600599) (xy 21.717005 -211.685436) (xy 21.717508 -211.72805) (xy 21.717081 -211.769153)
			(xy 21.709492 -211.851009) (xy 21.694382 -211.931815) (xy 21.673457 -212.005348) (xy 25.653996 -212.005348)
			(xy 25.653996 -211.920652) (xy 25.662047 -211.836338) (xy 25.678076 -211.753172) (xy 25.701937 -211.671905)
			(xy 25.733416 -211.593275) (xy 25.772227 -211.517994) (xy 25.818017 -211.446742) (xy 25.870373 -211.380166)
			(xy 25.928821 -211.318868) (xy 25.992831 -211.263403) (xy 26.061823 -211.214274) (xy 26.135173 -211.171925)
			(xy 26.212216 -211.136741) (xy 26.292255 -211.109039) (xy 26.374564 -211.089071) (xy 26.458399 -211.077018)
			(xy 26.543 -211.072988) (xy 26.627601 -211.077018) (xy 26.711436 -211.089071) (xy 26.793745 -211.109039)
			(xy 26.873784 -211.136741) (xy 26.950827 -211.171925) (xy 27.024177 -211.214274) (xy 27.093169 -211.263403)
			(xy 27.157179 -211.318868) (xy 27.215627 -211.380166) (xy 27.267983 -211.446742) (xy 27.313773 -211.517994)
			(xy 27.352584 -211.593275) (xy 27.384063 -211.671905) (xy 27.407924 -211.753172) (xy 27.423953 -211.836338)
			(xy 27.432004 -211.920652) (xy 27.432508 -211.963) (xy 27.432004 -212.005348) (xy 27.423953 -212.089662)
			(xy 27.407924 -212.172828) (xy 27.384063 -212.254095) (xy 27.352584 -212.332725) (xy 27.313773 -212.408006)
			(xy 27.267983 -212.479258) (xy 27.215627 -212.545834) (xy 27.157179 -212.607132) (xy 27.093169 -212.662597)
			(xy 27.024177 -212.711726) (xy 26.950827 -212.754075) (xy 26.873784 -212.789259) (xy 26.793745 -212.816961)
			(xy 26.711436 -212.836929) (xy 26.627601 -212.848982) (xy 26.543 -212.853013) (xy 26.458399 -212.848982)
			(xy 26.374564 -212.836929) (xy 26.292255 -212.816961) (xy 26.212216 -212.789259) (xy 26.135173 -212.754075)
			(xy 26.061823 -212.711726) (xy 25.992831 -212.662597) (xy 25.928821 -212.607132) (xy 25.870373 -212.545834)
			(xy 25.818017 -212.479258) (xy 25.772227 -212.408006) (xy 25.733416 -212.332725) (xy 25.701937 -212.254095)
			(xy 25.678076 -212.172828) (xy 25.662047 -212.089662) (xy 25.653996 -212.005348) (xy 21.673457 -212.005348)
			(xy 21.671882 -212.010883) (xy 21.642182 -212.087537) (xy 21.605536 -212.161124) (xy 21.562258 -212.231016)
			(xy 21.512715 -212.296616) (xy 21.457331 -212.357366) (xy 21.396578 -212.412747) (xy 21.330974 -212.462286)
			(xy 21.26108 -212.505561) (xy 21.187491 -212.542202) (xy 21.110835 -212.571898) (xy 21.031766 -212.594394)
			(xy 20.950959 -212.609499) (xy 20.869103 -212.617083) (xy 20.828 -212.617558) (xy 20.784883 -212.617053)
			(xy 20.699055 -212.608707) (xy 20.614436 -212.592095) (xy 20.572984 -212.58022) (xy 20.562316 -212.576918)
			(xy 20.540472 -212.58022) (xy 20.456652 -212.63356) (xy 20.444714 -212.652356) (xy 20.44319 -212.663278)
			(xy 20.436759 -212.705185) (xy 20.416891 -212.787615) (xy 20.389269 -212.867781) (xy 20.354144 -212.944953)
			(xy 20.311834 -213.018433) (xy 20.262723 -213.087553) (xy 20.207258 -213.151686) (xy 20.145941 -213.21025)
			(xy 20.079329 -213.262712) (xy 20.008027 -213.308598) (xy 19.932682 -213.347489) (xy 19.853978 -213.379034)
			(xy 19.772629 -213.402947) (xy 19.689373 -213.419009) (xy 19.604967 -213.427075) (xy 19.562572 -213.427564)
			(xy 19.520223 -213.427084) (xy 19.435907 -213.419033) (xy 19.352739 -213.403004) (xy 19.271471 -213.379141)
			(xy 19.192839 -213.347662) (xy 19.117555 -213.308851) (xy 19.046302 -213.263059) (xy 18.979724 -213.210702)
			(xy 18.918424 -213.152253) (xy 18.862958 -213.088242) (xy 18.813828 -213.019248) (xy 18.771478 -212.945897)
			(xy 18.736293 -212.868852) (xy 18.708591 -212.788811) (xy 18.688622 -212.7065) (xy 18.676568 -212.622663)
			(xy 18.672538 -212.53806) (xy 18.676568 -212.453457) (xy 18.688622 -212.36962) (xy 18.708591 -212.287309)
			(xy 18.736293 -212.207268) (xy 18.771478 -212.130223) (xy 18.813828 -212.056872) (xy 18.862958 -211.987878)
			(xy 18.918424 -211.923867) (xy 18.979724 -211.865418) (xy 19.046302 -211.813061) (xy 19.117555 -211.767269)
			(xy 19.192839 -211.728458) (xy 19.271471 -211.696979) (xy 19.352739 -211.673116) (xy 19.435907 -211.657087)
			(xy 19.520223 -211.649036) (xy 19.562572 -211.648548) (xy 19.605689 -211.64906) (xy 19.691517 -211.657402)
			(xy 19.776135 -211.674012) (xy 19.817588 -211.685886) (xy 19.828256 -211.689188) (xy 19.8501 -211.685886)
			(xy 19.93392 -211.632546) (xy 19.945858 -211.61375) (xy 19.947382 -211.602828) (xy 19.953188 -211.565117)
			(xy 19.9704 -211.490778) (xy 19.993903 -211.418182) (xy 20.008342 -211.382864) (xy 20.012152 -211.373466)
			(xy 20.012406 -211.353908) (xy 19.978878 -211.269072) (xy 19.965416 -211.254848) (xy 19.956272 -211.250784)
			(xy 19.91758 -211.232918) (xy 19.843493 -211.190781) (xy 19.773777 -211.141751) (xy 19.709069 -211.086278)
			(xy 19.649964 -211.024871) (xy 19.597002 -210.958093) (xy 19.55067 -210.886555) (xy 19.511392 -210.810914)
			(xy 19.479529 -210.731863) (xy 19.455373 -210.650127) (xy 19.439144 -210.566456) (xy 19.430993 -210.481615)
			(xy 19.430492 -210.439) (xy 19.431078 -210.394023) (xy 19.440173 -210.30453) (xy 19.458241 -210.21641)
			(xy 19.471132 -210.173316) (xy 19.474434 -210.162648) (xy 19.471894 -210.141566) (xy 19.421348 -210.057238)
			(xy 19.403822 -210.045046) (xy 19.3929 -210.043014) (xy 19.3526 -210.034927) (xy 19.27358 -210.012281)
			(xy 19.196987 -209.982442) (xy 19.123473 -209.945662) (xy 19.053666 -209.902257) (xy 18.988162 -209.852596)
			(xy 18.92752 -209.797103) (xy 18.872256 -209.736251) (xy 18.822843 -209.67056) (xy 18.779702 -209.60059)
			(xy 18.7432 -209.526937) (xy 18.71365 -209.450232) (xy 18.70202 -209.410808) (xy 18.698972 -209.399886)
			(xy 18.685002 -209.383376) (xy 18.594832 -209.341466) (xy 18.572988 -209.341212) (xy 18.562828 -209.345784)
			(xy 18.519823 -209.364379) (xy 18.430757 -209.393473) (xy 18.339128 -209.413053) (xy 18.245949 -209.422902)
			(xy 18.1991 -209.423508) (xy 18.157739 -209.423086) (xy 18.075374 -209.415415) (xy 17.994078 -209.400129)
			(xy 17.914551 -209.37736) (xy 17.837483 -209.347306) (xy 17.763537 -209.310226) (xy 17.693355 -209.26644)
			(xy 17.627541 -209.216326) (xy 17.566664 -209.160319) (xy 17.511251 -209.0989) (xy 17.46178 -209.032602)
			(xy 17.418678 -208.961997) (xy 17.382318 -208.887695) (xy 17.353015 -208.810338) (xy 17.33102 -208.730594)
			(xy 17.323308 -208.689956) (xy 17.321022 -208.676748) (xy 17.30375 -208.65592) (xy 17.196308 -208.616042)
			(xy 17.169892 -208.62036) (xy 17.159224 -208.628742) (xy 17.125283 -208.655654) (xy 17.053038 -208.70345)
			(xy 16.976488 -208.743995) (xy 16.896358 -208.776907) (xy 16.813409 -208.801872) (xy 16.728425 -208.818655)
			(xy 16.642212 -208.827096) (xy 16.5989 -208.827624) (xy 16.561861 -208.827272) (xy 16.488038 -208.821145)
			(xy 16.414982 -208.808892) (xy 16.3432 -208.790599) (xy 16.30807 -208.778856) (xy 16.299056 -208.776194)
			(xy 16.280291 -208.776875) (xy 16.263035 -208.784281) (xy 16.249613 -208.797413) (xy 16.245332 -208.80578)
			(xy 16.227262 -208.844067) (xy 16.184901 -208.917376) (xy 16.135765 -208.986328) (xy 16.0803 -209.050299)
			(xy 16.019008 -209.10871) (xy 15.952442 -209.161034) (xy 15.881207 -209.206796) (xy 15.805945 -209.245582)
			(xy 15.727339 -209.277041) (xy 15.646099 -209.300889) (xy 15.56296 -209.31691) (xy 15.478676 -209.324959)
			(xy 15.436342 -209.325464) (xy 15.393993 -209.324984) (xy 15.309677 -209.316933) (xy 15.226509 -209.300904)
			(xy 15.145241 -209.277041) (xy 15.066609 -209.245562) (xy 14.991325 -209.206751) (xy 14.920072 -209.160959)
			(xy 14.853494 -209.108602) (xy 14.792194 -209.050153) (xy 14.736728 -208.986142) (xy 14.687598 -208.917148)
			(xy 14.645248 -208.843797) (xy 14.610063 -208.766752) (xy 14.582361 -208.686711) (xy 14.562392 -208.6044)
			(xy 14.550338 -208.520563) (xy 14.546308 -208.43596) (xy 9.88982 -208.43596) (xy 9.902275 -208.460633)
			(xy 9.941387 -208.555899) (xy 9.972965 -208.65392) (xy 9.996818 -208.754102) (xy 10.012801 -208.855836)
			(xy 10.020817 -208.958506) (xy 10.020817 -209.061488) (xy 10.012802 -209.164158) (xy 9.996819 -209.265893)
			(xy 9.972967 -209.366075) (xy 9.941389 -209.464096) (xy 9.902277 -209.559362) (xy 9.855869 -209.651295)
			(xy 9.802446 -209.739337) (xy 9.742332 -209.822953) (xy 9.675892 -209.901637) (xy 9.640062 -209.93862)
			(xy 9.632696 -209.945732) (xy 9.62533 -209.96402) (xy 9.62533 -210.055968) (xy 9.632696 -210.074256)
			(xy 9.640062 -210.081368) (xy 9.675881 -210.118362) (xy 9.742323 -210.197044) (xy 9.802439 -210.280658)
			(xy 9.855864 -210.368698) (xy 9.902275 -210.46063) (xy 9.941388 -210.555895) (xy 9.972968 -210.653916)
			(xy 9.996822 -210.754097) (xy 10.012806 -210.855831) (xy 10.020823 -210.958501) (xy 10.021316 -211.009992)
			(xy 10.020791 -211.061886) (xy 10.012648 -211.165354) (xy 9.996413 -211.267864) (xy 9.972185 -211.368785)
			(xy 9.940113 -211.467493) (xy 9.900396 -211.563381) (xy 9.867649 -211.62765) (xy 11.255498 -211.62765)
			(xy 11.255498 -211.542954) (xy 11.263549 -211.45864) (xy 11.279578 -211.375474) (xy 11.303439 -211.294207)
			(xy 11.334918 -211.215577) (xy 11.373729 -211.140296) (xy 11.419519 -211.069044) (xy 11.471875 -211.002468)
			(xy 11.530323 -210.94117) (xy 11.594333 -210.885705) (xy 11.663325 -210.836576) (xy 11.736675 -210.794227)
			(xy 11.813718 -210.759043) (xy 11.893757 -210.731341) (xy 11.976066 -210.711373) (xy 12.059901 -210.69932)
			(xy 12.144502 -210.69529) (xy 12.229103 -210.69932) (xy 12.312938 -210.711373) (xy 12.395247 -210.731341)
			(xy 12.475286 -210.759043) (xy 12.552329 -210.794227) (xy 12.625679 -210.836576) (xy 12.694671 -210.885705)
			(xy 12.758681 -210.94117) (xy 12.817129 -211.002468) (xy 12.848414 -211.04225) (xy 14.912832 -211.04225)
			(xy 14.916862 -210.957647) (xy 14.928916 -210.873811) (xy 14.948885 -210.791499) (xy 14.976587 -210.711459)
			(xy 15.011772 -210.634414) (xy 15.054122 -210.561063) (xy 15.103252 -210.49207) (xy 15.158718 -210.428059)
			(xy 15.220017 -210.36961) (xy 15.286595 -210.317253) (xy 15.357848 -210.271462) (xy 15.433132 -210.232651)
			(xy 15.511763 -210.201172) (xy 15.593031 -210.17731) (xy 15.676199 -210.161281) (xy 15.760515 -210.15323)
			(xy 15.802864 -210.152742) (xy 15.847786 -210.153288) (xy 15.937172 -210.162351) (xy 16.025188 -210.180378)
			(xy 16.11094 -210.207186) (xy 16.193552 -210.242501) (xy 16.23314 -210.26374) (xy 16.246107 -210.270296)
			(xy 16.274449 -210.276629) (xy 16.303427 -210.27472) (xy 16.330693 -210.264725) (xy 16.354039 -210.247453)
			(xy 16.371573 -210.224303) (xy 16.381875 -210.197151) (xy 16.383508 -210.182714) (xy 16.387249 -210.141379)
			(xy 16.401387 -210.059592) (xy 16.423085 -209.979478) (xy 16.452153 -209.901734) (xy 16.488338 -209.827036)
			(xy 16.531325 -209.756035) (xy 16.580741 -209.689348) (xy 16.636156 -209.627555) (xy 16.697087 -209.571195)
			(xy 16.763004 -209.520757) (xy 16.833334 -209.47668) (xy 16.907465 -209.439348) (xy 16.984752 -209.409085)
			(xy 17.064522 -209.386155) (xy 17.146082 -209.370757) (xy 17.228722 -209.363026) (xy 17.270222 -209.362548)
			(xy 17.31257 -209.36306) (xy 17.396883 -209.371111) (xy 17.480049 -209.38714) (xy 17.561315 -209.411002)
			(xy 17.639944 -209.44248) (xy 17.715225 -209.481291) (xy 17.786477 -209.527081) (xy 17.853052 -209.579437)
			(xy 17.91435 -209.637885) (xy 17.969814 -209.701894) (xy 18.018943 -209.770886) (xy 18.061291 -209.844235)
			(xy 18.096476 -209.921278) (xy 18.124177 -210.001316) (xy 18.144145 -210.083625) (xy 18.156198 -210.167459)
			(xy 18.160229 -210.25206) (xy 18.156198 -210.336661) (xy 18.144145 -210.420495) (xy 18.124177 -210.502804)
			(xy 18.096476 -210.582842) (xy 18.061291 -210.659885) (xy 18.018943 -210.733234) (xy 17.969814 -210.802226)
			(xy 17.91435 -210.866235) (xy 17.853052 -210.924683) (xy 17.786477 -210.977039) (xy 17.715225 -211.022829)
			(xy 17.639944 -211.06164) (xy 17.561315 -211.093118) (xy 17.480049 -211.11698) (xy 17.396883 -211.133009)
			(xy 17.31257 -211.14106) (xy 17.270222 -211.141564) (xy 17.225301 -211.14098) (xy 17.135917 -211.131925)
			(xy 17.0479 -211.113907) (xy 16.962148 -211.087108) (xy 16.879535 -211.051801) (xy 16.839946 -211.030566)
			(xy 16.826989 -211.023988) (xy 16.798643 -211.017657) (xy 16.769662 -211.019569) (xy 16.742393 -211.029567)
			(xy 16.719046 -211.046843) (xy 16.701511 -211.069997) (xy 16.69121 -211.097153) (xy 16.689578 -211.111592)
			(xy 16.685856 -211.152929) (xy 16.671717 -211.234717) (xy 16.650018 -211.314832) (xy 16.620949 -211.392577)
			(xy 16.584763 -211.467275) (xy 16.541774 -211.538276) (xy 16.492357 -211.604963) (xy 16.436941 -211.666756)
			(xy 16.376009 -211.723117) (xy 16.31009 -211.773554) (xy 16.239759 -211.817631) (xy 16.165626 -211.854963)
			(xy 16.088338 -211.885225) (xy 16.008567 -211.908154) (xy 15.927006 -211.923551) (xy 15.844365 -211.931281)
			(xy 15.802864 -211.931758) (xy 15.760515 -211.93127) (xy 15.676199 -211.923219) (xy 15.593031 -211.90719)
			(xy 15.511763 -211.883328) (xy 15.433132 -211.851849) (xy 15.357848 -211.813038) (xy 15.286595 -211.767247)
			(xy 15.220017 -211.71489) (xy 15.158718 -211.656441) (xy 15.103252 -211.59243) (xy 15.054122 -211.523437)
			(xy 15.011772 -211.450086) (xy 14.976587 -211.373041) (xy 14.948885 -211.293001) (xy 14.928916 -211.210689)
			(xy 14.916862 -211.126853) (xy 14.912832 -211.04225) (xy 12.848414 -211.04225) (xy 12.869485 -211.069044)
			(xy 12.915275 -211.140296) (xy 12.954086 -211.215577) (xy 12.985565 -211.294207) (xy 13.009426 -211.375474)
			(xy 13.025455 -211.45864) (xy 13.033506 -211.542954) (xy 13.03401 -211.585302) (xy 13.033506 -211.62765)
			(xy 13.025455 -211.711964) (xy 13.009426 -211.79513) (xy 12.985565 -211.876397) (xy 12.954086 -211.955027)
			(xy 12.915275 -212.030308) (xy 12.869485 -212.10156) (xy 12.817129 -212.168136) (xy 12.758681 -212.229434)
			(xy 12.694671 -212.284899) (xy 12.625679 -212.334028) (xy 12.552329 -212.376377) (xy 12.475286 -212.411561)
			(xy 12.395247 -212.439263) (xy 12.312938 -212.459231) (xy 12.229103 -212.471284) (xy 12.144502 -212.475315)
			(xy 12.059901 -212.471284) (xy 11.976066 -212.459231) (xy 11.893757 -212.439263) (xy 11.813718 -212.411561)
			(xy 11.736675 -212.376377) (xy 11.663325 -212.334028) (xy 11.594333 -212.284899) (xy 11.530323 -212.229434)
			(xy 11.471875 -212.168136) (xy 11.419519 -212.10156) (xy 11.373729 -212.030308) (xy 11.334918 -211.955027)
			(xy 11.303439 -211.876397) (xy 11.279578 -211.79513) (xy 11.263549 -211.711964) (xy 11.255498 -211.62765)
			(xy 9.867649 -211.62765) (xy 9.853277 -211.655857) (xy 9.799049 -211.744351) (xy 9.738044 -211.828318)
			(xy 9.67064 -211.907239) (xy 9.597251 -211.980629) (xy 9.518331 -212.048034) (xy 9.434365 -212.10904)
			(xy 9.345871 -212.16327) (xy 9.253396 -212.210389) (xy 9.157508 -212.250107) (xy 9.0588 -212.28218)
			(xy 8.95788 -212.30641) (xy 8.85537 -212.322646) (xy 8.751902 -212.33079) (xy 8.700008 -212.3313)
			(xy 8.648517 -212.330789) (xy 8.545848 -212.322774) (xy 8.444113 -212.306792) (xy 8.343932 -212.282941)
			(xy 8.245911 -212.251364) (xy 8.150644 -212.212254) (xy 8.058711 -212.165847) (xy 7.970669 -212.112425)
			(xy 7.887052 -212.052313) (xy 7.808368 -211.985876) (xy 7.771384 -211.950046) (xy 7.764272 -211.94268)
			(xy 7.745984 -211.935314) (xy 7.654036 -211.935314) (xy 7.635748 -211.94268) (xy 7.628636 -211.950046)
			(xy 7.591637 -211.98586) (xy 7.512956 -212.052303) (xy 7.429343 -212.11242) (xy 7.341303 -212.165845)
			(xy 7.249372 -212.212256) (xy 7.154107 -212.25137) (xy 7.056087 -212.282951) (xy 6.955906 -212.306805)
			(xy 6.854172 -212.322789) (xy 6.751503 -212.330806) (xy 6.700012 -212.3313) (xy 6.648118 -212.330787)
			(xy 6.544649 -212.322644) (xy 6.442139 -212.306408) (xy 6.341218 -212.282179) (xy 6.242509 -212.250107)
			(xy 6.146621 -212.210389) (xy 6.054145 -212.16327) (xy 5.96565 -212.109041) (xy 5.881684 -212.048035)
			(xy 5.802762 -211.98063) (xy 5.729372 -211.907241) (xy 5.661967 -211.82832) (xy 5.600962 -211.744353)
			(xy 5.546732 -211.655859) (xy 5.499613 -211.563383) (xy 5.459895 -211.467495) (xy 5.427822 -211.368786)
			(xy 5.403593 -211.267865) (xy 5.387357 -211.165355) (xy 5.379214 -211.061886) (xy 5.378704 -211.009992)
			(xy 1.652219 -211.009992) (xy 1.651254 -211.041996) (xy 1.651254 -215.02498) (xy 17.248237 -215.02498)
			(xy 17.250871 -214.94117) (xy 17.26138 -214.857981) (xy 17.279672 -214.77615) (xy 17.305583 -214.696403)
			(xy 17.338884 -214.619449) (xy 17.37928 -214.54597) (xy 17.426411 -214.476618) (xy 17.479859 -214.41201)
			(xy 17.53915 -214.352719) (xy 17.603758 -214.299271) (xy 17.67311 -214.25214) (xy 17.746589 -214.211744)
			(xy 17.823543 -214.178443) (xy 17.90329 -214.152532) (xy 17.985121 -214.13424) (xy 18.06831 -214.123731)
			(xy 18.15212 -214.121097) (xy 18.235805 -214.126362) (xy 18.318623 -214.139479) (xy 18.39984 -214.160332)
			(xy 18.478733 -214.188736) (xy 18.554603 -214.224438) (xy 18.626777 -214.267121) (xy 18.694614 -214.316407)
			(xy 18.757511 -214.371859) (xy 18.814911 -214.432983) (xy 18.866303 -214.499238) (xy 18.911233 -214.570036)
			(xy 18.9493 -214.644747) (xy 18.9552 -214.659648) (xy 20.446996 -214.659648) (xy 20.446996 -214.574952)
			(xy 20.455047 -214.490638) (xy 20.471076 -214.407472) (xy 20.494937 -214.326205) (xy 20.526416 -214.247575)
			(xy 20.565227 -214.172294) (xy 20.611017 -214.101042) (xy 20.663373 -214.034466) (xy 20.721821 -213.973168)
			(xy 20.785831 -213.917703) (xy 20.854823 -213.868574) (xy 20.928173 -213.826225) (xy 21.005216 -213.791041)
			(xy 21.085255 -213.763339) (xy 21.167564 -213.743371) (xy 21.251399 -213.731318) (xy 21.336 -213.727288)
			(xy 21.420601 -213.731318) (xy 21.504436 -213.743371) (xy 21.586745 -213.763339) (xy 21.666784 -213.791041)
			(xy 21.743827 -213.826225) (xy 21.817177 -213.868574) (xy 21.886169 -213.917703) (xy 21.950179 -213.973168)
			(xy 22.008627 -214.034466) (xy 22.060983 -214.101042) (xy 22.106773 -214.172294) (xy 22.145584 -214.247575)
			(xy 22.177063 -214.326205) (xy 22.200924 -214.407472) (xy 22.216953 -214.490638) (xy 22.225004 -214.574952)
			(xy 22.225508 -214.6173) (xy 22.225004 -214.659648) (xy 22.216953 -214.743962) (xy 22.200924 -214.827128)
			(xy 22.177063 -214.908395) (xy 22.145584 -214.987025) (xy 22.106773 -215.062306) (xy 22.060983 -215.133558)
			(xy 22.008627 -215.200134) (xy 21.950179 -215.261432) (xy 21.886169 -215.316897) (xy 21.817177 -215.366026)
			(xy 21.743827 -215.408375) (xy 21.666784 -215.443559) (xy 21.586745 -215.471261) (xy 21.504436 -215.491229)
			(xy 21.420601 -215.503282) (xy 21.336 -215.507313) (xy 21.251399 -215.503282) (xy 21.167564 -215.491229)
			(xy 21.085255 -215.471261) (xy 21.005216 -215.443559) (xy 20.928173 -215.408375) (xy 20.854823 -215.366026)
			(xy 20.785831 -215.316897) (xy 20.721821 -215.261432) (xy 20.663373 -215.200134) (xy 20.611017 -215.133558)
			(xy 20.565227 -215.062306) (xy 20.526416 -214.987025) (xy 20.494937 -214.908395) (xy 20.471076 -214.827128)
			(xy 20.455047 -214.743962) (xy 20.446996 -214.659648) (xy 18.9552 -214.659648) (xy 18.980168 -214.722709)
			(xy 19.003561 -214.803231) (xy 19.019273 -214.885596) (xy 19.027164 -214.969075) (xy 19.027648 -215.011)
			(xy 19.027101 -215.055297) (xy 19.018262 -215.14345) (xy 19.00071 -215.230288) (xy 18.974619 -215.314954)
			(xy 18.940247 -215.396609) (xy 18.897934 -215.474447) (xy 18.87347 -215.51138) (xy 18.866277 -215.522841)
			(xy 18.857493 -215.54842) (xy 18.855733 -215.575408) (xy 18.861121 -215.601912) (xy 18.873278 -215.62607)
			(xy 18.891351 -215.64619) (xy 18.914073 -215.660858) (xy 18.939849 -215.669046) (xy 18.966871 -215.670179)
			(xy 18.98015 -215.66759) (xy 19.028707 -215.657264) (xy 19.127363 -215.64619) (xy 19.177 -215.645492)
			(xy 19.218925 -215.645976) (xy 19.302404 -215.653867) (xy 19.384769 -215.669579) (xy 19.465291 -215.692972)
			(xy 19.543253 -215.72384) (xy 19.617964 -215.761907) (xy 19.688762 -215.806837) (xy 19.755017 -215.858229)
			(xy 19.816141 -215.915629) (xy 19.871593 -215.978526) (xy 19.920879 -216.046363) (xy 19.963562 -216.118537)
			(xy 19.999264 -216.194407) (xy 20.027668 -216.2733) (xy 20.048521 -216.354517) (xy 20.061638 -216.437335)
			(xy 20.066903 -216.52102) (xy 20.064269 -216.60483) (xy 20.057047 -216.662) (xy 24.256492 -216.662)
			(xy 24.256913 -216.621946) (xy 24.264124 -216.542165) (xy 24.278479 -216.463354) (xy 24.299862 -216.386153)
			(xy 24.328098 -216.311188) (xy 24.362961 -216.239064) (xy 24.404167 -216.170368) (xy 24.451382 -216.105654)
			(xy 24.477472 -216.07526) (xy 24.483157 -216.06814) (xy 24.489541 -216.051089) (xy 24.489918 -216.041986)
			(xy 24.489918 -216.012014) (xy 24.489534 -216.002912) (xy 24.483154 -215.985861) (xy 24.477472 -215.97874)
			(xy 24.451386 -215.948343) (xy 24.404168 -215.883632) (xy 24.362961 -215.814936) (xy 24.328099 -215.742813)
			(xy 24.299865 -215.667847) (xy 24.278486 -215.590646) (xy 24.264136 -215.511835) (xy 24.256932 -215.432053)
			(xy 24.256492 -215.392) (xy 24.256996 -215.349652) (xy 24.265047 -215.265338) (xy 24.281076 -215.182172)
			(xy 24.304937 -215.100905) (xy 24.336416 -215.022275) (xy 24.375227 -214.946994) (xy 24.421017 -214.875742)
			(xy 24.473373 -214.809166) (xy 24.531821 -214.747868) (xy 24.595831 -214.692403) (xy 24.664823 -214.643274)
			(xy 24.738173 -214.600925) (xy 24.815216 -214.565741) (xy 24.895255 -214.538039) (xy 24.977564 -214.518071)
			(xy 25.061399 -214.506018) (xy 25.146 -214.501988) (xy 25.230601 -214.506018) (xy 25.314436 -214.518071)
			(xy 25.396745 -214.538039) (xy 25.476784 -214.565741) (xy 25.553827 -214.600925) (xy 25.627177 -214.643274)
			(xy 25.668006 -214.672348) (xy 29.717996 -214.672348) (xy 29.717996 -214.587652) (xy 29.726047 -214.503338)
			(xy 29.742076 -214.420172) (xy 29.765937 -214.338905) (xy 29.797416 -214.260275) (xy 29.836227 -214.184994)
			(xy 29.882017 -214.113742) (xy 29.934373 -214.047166) (xy 29.992821 -213.985868) (xy 30.056831 -213.930403)
			(xy 30.125823 -213.881274) (xy 30.199173 -213.838925) (xy 30.276216 -213.803741) (xy 30.356255 -213.776039)
			(xy 30.438564 -213.756071) (xy 30.522399 -213.744018) (xy 30.607 -213.739988) (xy 30.691601 -213.744018)
			(xy 30.775436 -213.756071) (xy 30.857745 -213.776039) (xy 30.937784 -213.803741) (xy 31.014827 -213.838925)
			(xy 31.088177 -213.881274) (xy 31.157169 -213.930403) (xy 31.187748 -213.9569) (xy 35.432238 -213.9569)
			(xy 35.432723 -213.915997) (xy 35.440251 -213.834538) (xy 35.455227 -213.754114) (xy 35.477522 -213.675405)
			(xy 35.50695 -213.599075) (xy 35.543261 -213.525769) (xy 35.586148 -213.456106) (xy 35.63525 -213.390675)
			(xy 35.690152 -213.330028) (xy 35.750389 -213.274677) (xy 35.815454 -213.225091) (xy 35.884796 -213.181687)
			(xy 35.95783 -213.144832) (xy 36.033939 -213.114839) (xy 36.07308 -213.102952) (xy 36.081993 -213.099916)
			(xy 36.096907 -213.088445) (xy 36.106683 -213.072369) (xy 36.110007 -213.05385) (xy 36.10864 -213.044532)
			(xy 36.101247 -213.003145) (xy 36.093358 -212.919439) (xy 36.092892 -212.8774) (xy 36.093367 -212.836298)
			(xy 36.100952 -212.754443) (xy 36.116057 -212.673638) (xy 36.138553 -212.594571) (xy 36.168249 -212.517917)
			(xy 36.204891 -212.44433) (xy 36.248166 -212.374438) (xy 36.297706 -212.308837) (xy 36.353087 -212.248087)
			(xy 36.413837 -212.192706) (xy 36.479438 -212.143166) (xy 36.54933 -212.099891) (xy 36.622917 -212.063249)
			(xy 36.699571 -212.033553) (xy 36.778638 -212.011057) (xy 36.859443 -211.995952) (xy 36.941298 -211.988367)
			(xy 36.9824 -211.987892) (xy 37.025008 -211.988388) (xy 37.109834 -211.99653) (xy 37.193492 -212.012749)
			(xy 37.275216 -212.036896) (xy 37.354254 -212.06875) (xy 37.429883 -212.108018) (xy 37.501409 -212.15434)
			(xy 37.535104 -212.180424) (xy 37.54309 -212.186269) (xy 37.562051 -212.191881) (xy 37.571934 -212.191346)
			(xy 37.594728 -212.189105) (xy 37.640471 -212.18669) (xy 37.663374 -212.18652) (xy 37.705725 -212.186951)
			(xy 37.790045 -212.195) (xy 37.873217 -212.211028) (xy 37.954489 -212.23489) (xy 38.033125 -212.266369)
			(xy 38.108413 -212.30518) (xy 38.17967 -212.350973) (xy 38.246252 -212.403331) (xy 38.307555 -212.461782)
			(xy 38.363024 -212.525795) (xy 38.412158 -212.594791) (xy 38.45451 -212.668146) (xy 38.489697 -212.745194)
			(xy 38.517401 -212.825238) (xy 38.537371 -212.907553) (xy 38.549426 -212.991393) (xy 38.553456 -213.076)
			(xy 38.549426 -213.160607) (xy 38.537371 -213.244447) (xy 38.517401 -213.326762) (xy 38.489697 -213.406806)
			(xy 38.45451 -213.483854) (xy 38.412158 -213.557209) (xy 38.363024 -213.626205) (xy 38.307555 -213.690218)
			(xy 38.246252 -213.748669) (xy 38.17967 -213.801027) (xy 38.108413 -213.84682) (xy 38.033125 -213.885631)
			(xy 37.954489 -213.91711) (xy 37.873217 -213.940972) (xy 37.790045 -213.957) (xy 37.705725 -213.965049)
			(xy 37.663374 -213.965536) (xy 37.623054 -213.965079) (xy 37.542747 -213.957758) (xy 37.463432 -213.943196)
			(xy 37.385761 -213.921514) (xy 37.347906 -213.907624) (xy 37.336222 -213.903306) (xy 37.312346 -213.905846)
			(xy 37.222684 -213.964774) (xy 37.211 -213.985602) (xy 37.210238 -213.998048) (xy 37.207815 -214.040367)
			(xy 37.195862 -214.124292) (xy 37.175979 -214.206699) (xy 37.148345 -214.28684) (xy 37.113211 -214.363989)
			(xy 37.070896 -214.437444) (xy 37.021784 -214.50654) (xy 36.96632 -214.570649) (xy 36.905008 -214.629191)
			(xy 36.838404 -214.681633) (xy 36.767112 -214.727499) (xy 36.69178 -214.766374) (xy 36.61309 -214.797905)
			(xy 36.531757 -214.821806) (xy 36.44852 -214.83786) (xy 36.364132 -214.845921) (xy 36.321746 -214.846408)
			(xy 36.280644 -214.845904) (xy 36.198789 -214.838323) (xy 36.117983 -214.823222) (xy 36.038916 -214.800729)
			(xy 35.962261 -214.771036) (xy 35.888673 -214.734397) (xy 35.818779 -214.691124) (xy 35.753177 -214.641586)
			(xy 35.692426 -214.586207) (xy 35.637043 -214.525458) (xy 35.587502 -214.459859) (xy 35.544226 -214.389967)
			(xy 35.507583 -214.316381) (xy 35.477886 -214.239728) (xy 35.455389 -214.160661) (xy 35.440283 -214.079856)
			(xy 35.432698 -213.998002) (xy 35.432238 -213.9569) (xy 31.187748 -213.9569) (xy 31.221179 -213.985868)
			(xy 31.279627 -214.047166) (xy 31.331983 -214.113742) (xy 31.377773 -214.184994) (xy 31.416584 -214.260275)
			(xy 31.448063 -214.338905) (xy 31.471924 -214.420172) (xy 31.487953 -214.503338) (xy 31.496004 -214.587652)
			(xy 31.496508 -214.63) (xy 31.496004 -214.672348) (xy 31.487953 -214.756662) (xy 31.471924 -214.839828)
			(xy 31.448063 -214.921095) (xy 31.416584 -214.999725) (xy 31.377773 -215.075006) (xy 31.331983 -215.146258)
			(xy 31.279627 -215.212834) (xy 31.221179 -215.274132) (xy 31.157169 -215.329597) (xy 31.088177 -215.378726)
			(xy 31.014827 -215.421075) (xy 30.937784 -215.456259) (xy 30.857745 -215.483961) (xy 30.775436 -215.503929)
			(xy 30.691601 -215.515982) (xy 30.607 -215.520013) (xy 30.522399 -215.515982) (xy 30.438564 -215.503929)
			(xy 30.356255 -215.483961) (xy 30.276216 -215.456259) (xy 30.199173 -215.421075) (xy 30.125823 -215.378726)
			(xy 30.056831 -215.329597) (xy 29.992821 -215.274132) (xy 29.934373 -215.212834) (xy 29.882017 -215.146258)
			(xy 29.836227 -215.075006) (xy 29.797416 -214.999725) (xy 29.765937 -214.921095) (xy 29.742076 -214.839828)
			(xy 29.726047 -214.756662) (xy 29.717996 -214.672348) (xy 25.668006 -214.672348) (xy 25.696169 -214.692403)
			(xy 25.760179 -214.747868) (xy 25.818627 -214.809166) (xy 25.870983 -214.875742) (xy 25.916773 -214.946994)
			(xy 25.955584 -215.022275) (xy 25.987063 -215.100905) (xy 26.010924 -215.182172) (xy 26.026953 -215.265338)
			(xy 26.035004 -215.349652) (xy 26.035508 -215.392) (xy 26.035087 -215.432054) (xy 26.027876 -215.511835)
			(xy 26.013521 -215.590646) (xy 25.992138 -215.667847) (xy 25.963902 -215.742812) (xy 25.929039 -215.814936)
			(xy 25.887833 -215.883632) (xy 25.840618 -215.948346) (xy 25.814528 -215.97874) (xy 25.808843 -215.98586)
			(xy 25.802459 -216.002911) (xy 25.802082 -216.012014) (xy 25.802082 -216.041986) (xy 25.802466 -216.051088)
			(xy 25.808846 -216.068139) (xy 25.814528 -216.07526) (xy 25.840614 -216.105657) (xy 25.887832 -216.170368)
			(xy 25.929039 -216.239064) (xy 25.963901 -216.311187) (xy 25.992135 -216.386153) (xy 26.013514 -216.463354)
			(xy 26.027864 -216.542165) (xy 26.035068 -216.621947) (xy 26.035508 -216.662) (xy 26.035004 -216.704348)
			(xy 26.026953 -216.788662) (xy 26.010924 -216.871828) (xy 25.987063 -216.953095) (xy 25.955584 -217.031725)
			(xy 25.916773 -217.107006) (xy 25.870983 -217.178258) (xy 25.818627 -217.244834) (xy 25.760179 -217.306132)
			(xy 25.696169 -217.361597) (xy 25.627177 -217.410726) (xy 25.553827 -217.453075) (xy 25.476784 -217.488259)
			(xy 25.396745 -217.515961) (xy 25.314436 -217.535929) (xy 25.230601 -217.547982) (xy 25.146 -217.552013)
			(xy 25.061399 -217.547982) (xy 24.977564 -217.535929) (xy 24.895255 -217.515961) (xy 24.815216 -217.488259)
			(xy 24.738173 -217.453075) (xy 24.664823 -217.410726) (xy 24.595831 -217.361597) (xy 24.531821 -217.306132)
			(xy 24.473373 -217.244834) (xy 24.421017 -217.178258) (xy 24.375227 -217.107006) (xy 24.336416 -217.031725)
			(xy 24.304937 -216.953095) (xy 24.281076 -216.871828) (xy 24.265047 -216.788662) (xy 24.256996 -216.704348)
			(xy 24.256492 -216.662) (xy 20.057047 -216.662) (xy 20.05376 -216.688019) (xy 20.035468 -216.76985)
			(xy 20.009557 -216.849597) (xy 19.976256 -216.926551) (xy 19.93586 -217.00003) (xy 19.888729 -217.069382)
			(xy 19.835281 -217.13399) (xy 19.77599 -217.193281) (xy 19.711382 -217.246729) (xy 19.64203 -217.29386)
			(xy 19.568551 -217.334256) (xy 19.491597 -217.367557) (xy 19.41185 -217.393468) (xy 19.330019 -217.41176)
			(xy 19.24683 -217.422269) (xy 19.16302 -217.424903) (xy 19.079335 -217.419638) (xy 18.996517 -217.406521)
			(xy 18.9153 -217.385668) (xy 18.836407 -217.357264) (xy 18.760537 -217.321562) (xy 18.688363 -217.278879)
			(xy 18.620526 -217.229593) (xy 18.557629 -217.174141) (xy 18.500229 -217.113017) (xy 18.448837 -217.046762)
			(xy 18.403907 -216.975964) (xy 18.36584 -216.901253) (xy 18.334972 -216.823291) (xy 18.311579 -216.742769)
			(xy 18.295867 -216.660404) (xy 18.287976 -216.576925) (xy 18.287492 -216.535) (xy 18.288049 -216.490703)
			(xy 18.296888 -216.402551) (xy 18.314439 -216.315713) (xy 18.340528 -216.231048) (xy 18.374897 -216.149392)
			(xy 18.417207 -216.071554) (xy 18.44167 -216.03462) (xy 18.448923 -216.023191) (xy 18.457717 -215.9976)
			(xy 18.459481 -215.970599) (xy 18.454092 -215.944082) (xy 18.441927 -215.919912) (xy 18.42384 -215.899785)
			(xy 18.401103 -215.885115) (xy 18.37531 -215.876933) (xy 18.348274 -215.875812) (xy 18.33499 -215.87841)
			(xy 18.286432 -215.888729) (xy 18.187777 -215.899807) (xy 18.13814 -215.900508) (xy 18.096215 -215.900024)
			(xy 18.012736 -215.892133) (xy 17.930371 -215.876421) (xy 17.849849 -215.853028) (xy 17.771887 -215.82216)
			(xy 17.697176 -215.784093) (xy 17.626378 -215.739163) (xy 17.560123 -215.687771) (xy 17.498999 -215.630371)
			(xy 17.443547 -215.567474) (xy 17.394261 -215.499637) (xy 17.351578 -215.427463) (xy 17.315876 -215.351593)
			(xy 17.287472 -215.2727) (xy 17.266619 -215.191483) (xy 17.253502 -215.108665) (xy 17.248237 -215.02498)
			(xy 1.651254 -215.02498) (xy 1.651254 -216.020904) (xy 1.652778 -216.07145) (xy 1.651254 -216.121996)
			(xy 1.651254 -217.866398) (xy 28.955996 -217.866398) (xy 28.955996 -217.781702) (xy 28.964047 -217.697388)
			(xy 28.980076 -217.614222) (xy 29.003937 -217.532955) (xy 29.035416 -217.454325) (xy 29.074227 -217.379044)
			(xy 29.120017 -217.307792) (xy 29.172373 -217.241216) (xy 29.230821 -217.179918) (xy 29.294831 -217.124453)
			(xy 29.363823 -217.075324) (xy 29.437173 -217.032975) (xy 29.514216 -216.997791) (xy 29.594255 -216.970089)
			(xy 29.676564 -216.950121) (xy 29.760399 -216.938068) (xy 29.845 -216.934038) (xy 29.929601 -216.938068)
			(xy 30.013436 -216.950121) (xy 30.095745 -216.970089) (xy 30.175784 -216.997791) (xy 30.252827 -217.032975)
			(xy 30.270191 -217.043) (xy 36.194492 -217.043) (xy 36.195007 -216.999456) (xy 36.2035 -216.912784)
			(xy 36.220422 -216.827357) (xy 36.245614 -216.743993) (xy 36.278833 -216.663491) (xy 36.31976 -216.58662)
			(xy 36.368006 -216.514118) (xy 36.423106 -216.446679) (xy 36.484534 -216.384948) (xy 36.551702 -216.329516)
			(xy 36.623966 -216.280914) (xy 36.700634 -216.239609) (xy 36.780972 -216.205994) (xy 36.864211 -216.180393)
			(xy 36.949554 -216.16305) (xy 36.992814 -216.158064) (xy 37.002466 -216.157302) (xy 37.01923 -216.148412)
			(xy 37.077904 -216.08161) (xy 37.084254 -216.06383) (xy 37.084 -216.053924) (xy 37.083492 -216.027)
			(xy 37.083996 -215.984652) (xy 37.092047 -215.900338) (xy 37.108076 -215.817172) (xy 37.131937 -215.735905)
			(xy 37.163416 -215.657275) (xy 37.202227 -215.581994) (xy 37.248017 -215.510742) (xy 37.300373 -215.444166)
			(xy 37.358821 -215.382868) (xy 37.422831 -215.327403) (xy 37.491823 -215.278274) (xy 37.565173 -215.235925)
			(xy 37.642216 -215.200741) (xy 37.722255 -215.173039) (xy 37.804564 -215.153071) (xy 37.888399 -215.141018)
			(xy 37.973 -215.136988) (xy 38.057601 -215.141018) (xy 38.141436 -215.153071) (xy 38.223745 -215.173039)
			(xy 38.303784 -215.200741) (xy 38.380827 -215.235925) (xy 38.454177 -215.278274) (xy 38.523169 -215.327403)
			(xy 38.587179 -215.382868) (xy 38.645627 -215.444166) (xy 38.697983 -215.510742) (xy 38.743773 -215.581994)
			(xy 38.782584 -215.657275) (xy 38.814063 -215.735905) (xy 38.837924 -215.817172) (xy 38.853953 -215.900338)
			(xy 38.862004 -215.984652) (xy 38.862508 -216.027) (xy 38.861983 -216.071489) (xy 38.853094 -216.160022)
			(xy 38.835406 -216.247225) (xy 38.809095 -216.332224) (xy 38.774425 -216.41417) (xy 38.731742 -216.492242)
			(xy 38.681474 -216.56566) (xy 38.653212 -216.600024) (xy 38.647294 -216.607816) (xy 38.641213 -216.626391)
			(xy 38.642508 -216.645893) (xy 38.646354 -216.654888) (xy 38.663487 -216.691223) (xy 38.691882 -216.766377)
			(xy 38.713384 -216.843786) (xy 38.727817 -216.922818) (xy 38.735062 -217.00283) (xy 38.735508 -217.043)
			(xy 38.735033 -217.084102) (xy 38.727448 -217.165957) (xy 38.712343 -217.246762) (xy 38.689847 -217.325829)
			(xy 38.660151 -217.402483) (xy 38.623509 -217.47607) (xy 38.580234 -217.545962) (xy 38.530694 -217.611563)
			(xy 38.475313 -217.672313) (xy 38.414563 -217.727694) (xy 38.348962 -217.777234) (xy 38.27907 -217.820509)
			(xy 38.205483 -217.857151) (xy 38.128829 -217.886847) (xy 38.049762 -217.909343) (xy 37.968957 -217.924448)
			(xy 37.887102 -217.932033) (xy 37.846 -217.932508) (xy 37.799604 -217.931925) (xy 37.707316 -217.92228)
			(xy 37.616532 -217.903084) (xy 37.528239 -217.874546) (xy 37.485574 -217.856308) (xy 37.475634 -217.852488)
			(xy 37.454366 -217.852488) (xy 37.444426 -217.856308) (xy 37.401764 -217.874553) (xy 37.313471 -217.903097)
			(xy 37.222686 -217.92229) (xy 37.130396 -217.931923) (xy 37.084 -217.932508) (xy 37.042898 -217.932033)
			(xy 36.961043 -217.924448) (xy 36.880238 -217.909343) (xy 36.801171 -217.886847) (xy 36.724517 -217.857151)
			(xy 36.65093 -217.820509) (xy 36.581038 -217.777234) (xy 36.515437 -217.727694) (xy 36.454687 -217.672313)
			(xy 36.399306 -217.611563) (xy 36.349766 -217.545962) (xy 36.306491 -217.47607) (xy 36.269849 -217.402483)
			(xy 36.240153 -217.325829) (xy 36.217657 -217.246762) (xy 36.202552 -217.165957) (xy 36.194967 -217.084102)
			(xy 36.194492 -217.043) (xy 30.270191 -217.043) (xy 30.326177 -217.075324) (xy 30.395169 -217.124453)
			(xy 30.459179 -217.179918) (xy 30.517627 -217.241216) (xy 30.569983 -217.307792) (xy 30.615773 -217.379044)
			(xy 30.654584 -217.454325) (xy 30.686063 -217.532955) (xy 30.709924 -217.614222) (xy 30.725953 -217.697388)
			(xy 30.734004 -217.781702) (xy 30.734508 -217.82405) (xy 30.734004 -217.866398) (xy 30.725953 -217.950712)
			(xy 30.709924 -218.033878) (xy 30.686063 -218.115145) (xy 30.654584 -218.193775) (xy 30.615773 -218.269056)
			(xy 30.569983 -218.340308) (xy 30.517627 -218.406884) (xy 30.459179 -218.468182) (xy 30.395169 -218.523647)
			(xy 30.326177 -218.572776) (xy 30.252827 -218.615125) (xy 30.175784 -218.650309) (xy 30.095745 -218.678011)
			(xy 30.013436 -218.697979) (xy 29.929601 -218.710032) (xy 29.845 -218.714063) (xy 29.760399 -218.710032)
			(xy 29.676564 -218.697979) (xy 29.594255 -218.678011) (xy 29.514216 -218.650309) (xy 29.437173 -218.615125)
			(xy 29.363823 -218.572776) (xy 29.294831 -218.523647) (xy 29.230821 -218.468182) (xy 29.172373 -218.406884)
			(xy 29.120017 -218.340308) (xy 29.074227 -218.269056) (xy 29.035416 -218.193775) (xy 29.003937 -218.115145)
			(xy 28.980076 -218.033878) (xy 28.964047 -217.950712) (xy 28.955996 -217.866398) (xy 1.651254 -217.866398)
			(xy 1.651254 -219.117348) (xy 2.539996 -219.117348) (xy 2.539996 -219.032652) (xy 2.548047 -218.948338)
			(xy 2.564076 -218.865172) (xy 2.587937 -218.783905) (xy 2.619416 -218.705275) (xy 2.658227 -218.629994)
			(xy 2.704017 -218.558742) (xy 2.756373 -218.492166) (xy 2.814821 -218.430868) (xy 2.878831 -218.375403)
			(xy 2.947823 -218.326274) (xy 3.021173 -218.283925) (xy 3.098216 -218.248741) (xy 3.178255 -218.221039)
			(xy 3.260564 -218.201071) (xy 3.344399 -218.189018) (xy 3.429 -218.184988) (xy 3.513601 -218.189018)
			(xy 3.597436 -218.201071) (xy 3.679745 -218.221039) (xy 3.759784 -218.248741) (xy 3.836827 -218.283925)
			(xy 3.910177 -218.326274) (xy 3.979169 -218.375403) (xy 4.043179 -218.430868) (xy 4.101627 -218.492166)
			(xy 4.153983 -218.558742) (xy 4.199773 -218.629994) (xy 4.238584 -218.705275) (xy 4.270063 -218.783905)
			(xy 4.293924 -218.865172) (xy 4.309953 -218.948338) (xy 4.318004 -219.032652) (xy 4.318508 -219.075)
			(xy 4.318004 -219.117348) (xy 4.309953 -219.201662) (xy 4.293924 -219.284828) (xy 4.270063 -219.366095)
			(xy 4.238584 -219.444725) (xy 4.199773 -219.520006) (xy 4.153983 -219.591258) (xy 4.101627 -219.657834)
			(xy 4.043179 -219.719132) (xy 3.979169 -219.774597) (xy 3.910177 -219.823726) (xy 3.836827 -219.866075)
			(xy 3.759784 -219.901259) (xy 3.679745 -219.928961) (xy 3.597436 -219.948929) (xy 3.513601 -219.960982)
			(xy 3.429 -219.965013) (xy 3.344399 -219.960982) (xy 3.260564 -219.948929) (xy 3.178255 -219.928961)
			(xy 3.098216 -219.901259) (xy 3.021173 -219.866075) (xy 2.947823 -219.823726) (xy 2.878831 -219.774597)
			(xy 2.814821 -219.719132) (xy 2.756373 -219.657834) (xy 2.704017 -219.591258) (xy 2.658227 -219.520006)
			(xy 2.619416 -219.444725) (xy 2.587937 -219.366095) (xy 2.564076 -219.284828) (xy 2.548047 -219.201662)
			(xy 2.539996 -219.117348) (xy 1.651254 -219.117348) (xy 1.651254 -221.100904) (xy 1.652204 -221.1324)
			(xy 2.361692 -221.1324) (xy 2.362167 -221.091298) (xy 2.369752 -221.009443) (xy 2.384857 -220.928638)
			(xy 2.407353 -220.849571) (xy 2.437049 -220.772917) (xy 2.473691 -220.69933) (xy 2.516966 -220.629438)
			(xy 2.566506 -220.563837) (xy 2.621887 -220.503087) (xy 2.682637 -220.447706) (xy 2.748238 -220.398166)
			(xy 2.81813 -220.354891) (xy 2.891717 -220.318249) (xy 2.968371 -220.288553) (xy 3.047438 -220.266057)
			(xy 3.128243 -220.250952) (xy 3.210098 -220.243367) (xy 3.2512 -220.242892) (xy 3.294319 -220.243396)
			(xy 3.380151 -220.251745) (xy 3.464772 -220.268363) (xy 3.547387 -220.293096) (xy 3.587496 -220.308932)
			(xy 3.596865 -220.312269) (xy 3.616735 -220.312269) (xy 3.626104 -220.308932) (xy 3.666212 -220.293096)
			(xy 3.748828 -220.268365) (xy 3.833449 -220.251748) (xy 3.919281 -220.243401) (xy 3.9624 -220.242892)
			(xy 4.003502 -220.243367) (xy 4.085357 -220.250952) (xy 4.166162 -220.266057) (xy 4.245229 -220.288553)
			(xy 4.321883 -220.318249) (xy 4.39547 -220.354891) (xy 4.465362 -220.398166) (xy 4.530963 -220.447706)
			(xy 4.591713 -220.503087) (xy 4.647094 -220.563837) (xy 4.696634 -220.629438) (xy 4.739909 -220.69933)
			(xy 4.776551 -220.772917) (xy 4.806247 -220.849571) (xy 4.828743 -220.928638) (xy 4.843848 -221.009443)
			(xy 4.851433 -221.091298) (xy 4.851908 -221.1324) (xy 4.851478 -221.171533) (xy 4.84457 -221.249495)
			(xy 4.830841 -221.326549) (xy 4.810399 -221.4021) (xy 4.797298 -221.438978) (xy 4.794387 -221.448138)
			(xy 4.794901 -221.467332) (xy 4.798314 -221.476316) (xy 4.815064 -221.517427) (xy 4.841237 -221.602261)
			(xy 4.858821 -221.689281) (xy 4.867642 -221.77762) (xy 4.868164 -221.82201) (xy 4.867588 -221.868406)
			(xy 4.857942 -221.960695) (xy 4.838744 -222.051478) (xy 4.810203 -222.139772) (xy 4.791964 -222.182436)
			(xy 4.788139 -222.192374) (xy 4.788143 -222.213644) (xy 4.791964 -222.223584) (xy 4.810209 -222.266246)
			(xy 4.838754 -222.354538) (xy 4.857947 -222.445323) (xy 4.86758 -222.537614) (xy 4.868164 -222.58401)
			(xy 4.867588 -222.630406) (xy 4.857942 -222.722695) (xy 4.838744 -222.813478) (xy 4.810203 -222.901772)
			(xy 4.791964 -222.944436) (xy 4.788139 -222.954374) (xy 4.788143 -222.975644) (xy 4.791964 -222.985584)
			(xy 4.810209 -223.028246) (xy 4.838754 -223.116538) (xy 4.857947 -223.207323) (xy 4.86758 -223.299614)
			(xy 4.868164 -223.34601) (xy 4.867708 -223.387113) (xy 4.860123 -223.468969) (xy 4.845017 -223.549776)
			(xy 4.82252 -223.628844) (xy 4.792824 -223.7055) (xy 4.756181 -223.779088) (xy 4.712905 -223.848981)
			(xy 4.663364 -223.914583) (xy 4.607982 -223.975335) (xy 4.54723 -224.030717) (xy 4.481628 -224.080257)
			(xy 4.411734 -224.123533) (xy 4.338146 -224.160175) (xy 4.261491 -224.189872) (xy 4.182422 -224.212368)
			(xy 4.101615 -224.227473) (xy 4.019759 -224.235058) (xy 3.978656 -224.235518) (xy 3.935538 -224.234995)
			(xy 3.849706 -224.226652) (xy 3.765085 -224.210038) (xy 3.682469 -224.185311) (xy 3.64236 -224.169478)
			(xy 3.632991 -224.166141) (xy 3.613121 -224.166141) (xy 3.603752 -224.169478) (xy 3.563637 -224.185297)
			(xy 3.481024 -224.210032) (xy 3.396405 -224.226654) (xy 3.310574 -224.235007) (xy 3.267456 -224.235518)
			(xy 3.226353 -224.235047) (xy 3.144499 -224.227462) (xy 3.063694 -224.212356) (xy 2.984627 -224.18986)
			(xy 2.907973 -224.160163) (xy 2.834386 -224.123521) (xy 2.764494 -224.080246) (xy 2.698893 -224.030706)
			(xy 2.638143 -223.975324) (xy 2.582762 -223.914574) (xy 2.533222 -223.848973) (xy 2.489947 -223.779081)
			(xy 2.453305 -223.705493) (xy 2.423609 -223.628839) (xy 2.401113 -223.549772) (xy 2.386008 -223.468967)
			(xy 2.378423 -223.387113) (xy 2.377948 -223.34601) (xy 2.37853 -223.299614) (xy 2.388174 -223.207326)
			(xy 2.40737 -223.116542) (xy 2.43591 -223.028249) (xy 2.454148 -222.985584) (xy 2.457961 -222.975642)
			(xy 2.457964 -222.954376) (xy 2.454148 -222.944436) (xy 2.43591 -222.901771) (xy 2.407363 -222.81348)
			(xy 2.388168 -222.722696) (xy 2.378533 -222.630406) (xy 2.377948 -222.58401) (xy 2.37853 -222.537614)
			(xy 2.388174 -222.445326) (xy 2.40737 -222.354542) (xy 2.43591 -222.266249) (xy 2.454148 -222.223584)
			(xy 2.457961 -222.213642) (xy 2.457964 -222.192376) (xy 2.454148 -222.182436) (xy 2.43591 -222.139771)
			(xy 2.407363 -222.05148) (xy 2.388168 -221.960696) (xy 2.378533 -221.868406) (xy 2.377948 -221.82201)
			(xy 2.378383 -221.782877) (xy 2.385291 -221.704915) (xy 2.399018 -221.627861) (xy 2.419458 -221.55231)
			(xy 2.432558 -221.515432) (xy 2.435466 -221.506272) (xy 2.434955 -221.487077) (xy 2.431542 -221.478094)
			(xy 2.414787 -221.436984) (xy 2.388615 -221.352151) (xy 2.371032 -221.26513) (xy 2.362213 -221.17679)
			(xy 2.361692 -221.1324) (xy 1.652204 -221.1324) (xy 1.652778 -221.15145) (xy 1.651254 -221.201996)
			(xy 1.651254 -224.38741) (xy 11.380724 -224.38741) (xy 11.381308 -224.341014) (xy 11.390952 -224.248726)
			(xy 11.410148 -224.157942) (xy 11.438686 -224.069649) (xy 11.456924 -224.026984) (xy 11.460738 -224.017042)
			(xy 11.460741 -223.995776) (xy 11.456924 -223.985836) (xy 11.438684 -223.943172) (xy 11.410139 -223.85488)
			(xy 11.390944 -223.764096) (xy 11.381309 -223.671806) (xy 11.380724 -223.62541) (xy 11.381308 -223.579014)
			(xy 11.390952 -223.486726) (xy 11.410148 -223.395942) (xy 11.438686 -223.307649) (xy 11.456924 -223.264984)
			(xy 11.460738 -223.255042) (xy 11.460741 -223.233776) (xy 11.456924 -223.223836) (xy 11.438684 -223.181172)
			(xy 11.410139 -223.09288) (xy 11.390944 -223.002096) (xy 11.381309 -222.909806) (xy 11.380724 -222.86341)
			(xy 11.381162 -222.822306) (xy 11.388746 -222.740449) (xy 11.403851 -222.659641) (xy 11.426348 -222.580571)
			(xy 11.456045 -222.503914) (xy 11.492689 -222.430325) (xy 11.535966 -222.360431) (xy 11.585508 -222.294828)
			(xy 11.640892 -222.234076) (xy 11.701645 -222.178694) (xy 11.767249 -222.129154) (xy 11.837144 -222.085878)
			(xy 11.910734 -222.049236) (xy 11.987392 -222.019541) (xy 12.066462 -221.997046) (xy 12.147271 -221.981943)
			(xy 12.229128 -221.974361) (xy 12.270232 -221.973902) (xy 12.30852 -221.974338) (xy 12.38481 -221.980959)
			(xy 12.46025 -221.994106) (xy 12.534282 -222.013682) (xy 12.57046 -222.026226) (xy 12.578898 -222.028868)
			(xy 12.596566 -222.028868) (xy 12.605004 -222.026226) (xy 12.641176 -222.013661) (xy 12.715206 -221.994067)
			(xy 12.790648 -221.980918) (xy 12.866942 -221.974311) (xy 12.905232 -221.973902) (xy 12.946335 -221.974336)
			(xy 13.028191 -221.981924) (xy 13.108997 -221.997032) (xy 13.188065 -222.019532) (xy 13.26472 -222.04923)
			(xy 13.338307 -222.085875) (xy 13.408199 -222.129153) (xy 13.4738 -222.178695) (xy 13.53455 -222.234079)
			(xy 13.589931 -222.294832) (xy 13.639471 -222.360435) (xy 13.682745 -222.43033) (xy 13.719387 -222.503919)
			(xy 13.749082 -222.580575) (xy 13.771578 -222.659643) (xy 13.786682 -222.740451) (xy 13.794266 -222.822307)
			(xy 13.79474 -222.86341) (xy 13.794166 -222.909806) (xy 13.78452 -223.002095) (xy 13.765321 -223.092879)
			(xy 13.73678 -223.181172) (xy 13.71854 -223.223836) (xy 13.714716 -223.233774) (xy 13.71472 -223.255044)
			(xy 13.71854 -223.264984) (xy 13.73679 -223.307644) (xy 13.765332 -223.395937) (xy 13.784524 -223.486723)
			(xy 13.794156 -223.579014) (xy 13.79474 -223.62541) (xy 13.794166 -223.671806) (xy 13.78452 -223.764095)
			(xy 13.765321 -223.854879) (xy 13.73678 -223.943172) (xy 13.71854 -223.985836) (xy 13.714716 -223.995774)
			(xy 13.71472 -224.017044) (xy 13.71854 -224.026984) (xy 13.73679 -224.069644) (xy 13.765332 -224.157937)
			(xy 13.784524 -224.248723) (xy 13.794156 -224.341014) (xy 13.79474 -224.38741) (xy 13.794243 -224.428512)
			(xy 13.786657 -224.510364) (xy 13.771552 -224.591168) (xy 13.749056 -224.670233) (xy 13.719361 -224.746886)
			(xy 13.68272 -224.820471) (xy 13.639445 -224.890362) (xy 13.589907 -224.955963) (xy 13.534528 -225.016712)
			(xy 13.47378 -225.072093) (xy 13.408181 -225.121633) (xy 13.338291 -225.164909) (xy 13.264706 -225.201552)
			(xy 13.188054 -225.231249) (xy 13.10899 -225.253747) (xy 13.028186 -225.268854) (xy 12.946334 -225.276442)
			(xy 12.905232 -225.276918) (xy 12.866944 -225.276491) (xy 12.790653 -225.269867) (xy 12.715214 -225.256718)
			(xy 12.641181 -225.237139) (xy 12.605004 -225.224594) (xy 12.596566 -225.221952) (xy 12.578898 -225.221952)
			(xy 12.57046 -225.224594) (xy 12.534292 -225.23717) (xy 12.46026 -225.256761) (xy 12.384817 -225.269907)
			(xy 12.308522 -225.27651) (xy 12.270232 -225.276918) (xy 12.22913 -225.276417) (xy 12.147275 -225.268835)
			(xy 12.06647 -225.253733) (xy 11.987403 -225.231239) (xy 11.910748 -225.201546) (xy 11.837161 -225.164906)
			(xy 11.767268 -225.121633) (xy 11.701666 -225.072095) (xy 11.640914 -225.016715) (xy 11.585532 -224.955967)
			(xy 11.535991 -224.890367) (xy 11.492715 -224.820476) (xy 11.456071 -224.74689) (xy 11.426374 -224.670237)
			(xy 11.403877 -224.591171) (xy 11.388771 -224.510366) (xy 11.381185 -224.428512) (xy 11.380724 -224.38741)
			(xy 1.651254 -224.38741) (xy 1.651254 -226.180904) (xy 1.652778 -226.23145) (xy 1.651254 -226.281996)
			(xy 1.651254 -230.569262) (xy 2.082292 -230.569262) (xy 2.082897 -230.522867) (xy 2.092535 -230.430579)
			(xy 2.111725 -230.339795) (xy 2.140257 -230.251501) (xy 2.158492 -230.208836) (xy 2.16242 -230.198921)
			(xy 2.162405 -230.17761) (xy 2.158492 -230.167688) (xy 2.140248 -230.125025) (xy 2.111704 -230.036733)
			(xy 2.092511 -229.945948) (xy 2.082877 -229.853658) (xy 2.082292 -229.807262) (xy 2.082796 -229.764914)
			(xy 2.090847 -229.6806) (xy 2.106876 -229.597434) (xy 2.130737 -229.516167) (xy 2.162216 -229.437537)
			(xy 2.201027 -229.362256) (xy 2.246817 -229.291004) (xy 2.299173 -229.224428) (xy 2.357621 -229.16313)
			(xy 2.421631 -229.107665) (xy 2.490623 -229.058536) (xy 2.563973 -229.016187) (xy 2.641016 -228.981003)
			(xy 2.721055 -228.953301) (xy 2.803364 -228.933333) (xy 2.887199 -228.92128) (xy 2.9718 -228.91725)
			(xy 3.056401 -228.92128) (xy 3.140236 -228.933333) (xy 3.222545 -228.953301) (xy 3.302584 -228.981003)
			(xy 3.379627 -229.016187) (xy 3.452977 -229.058536) (xy 3.521969 -229.107665) (xy 3.585979 -229.16313)
			(xy 3.644427 -229.224428) (xy 3.696783 -229.291004) (xy 3.742573 -229.362256) (xy 3.781384 -229.437537)
			(xy 3.812863 -229.516167) (xy 3.836724 -229.597434) (xy 3.852753 -229.6806) (xy 3.860804 -229.764914)
			(xy 3.861308 -229.807262) (xy 3.860712 -229.853657) (xy 3.851071 -229.945945) (xy 3.831879 -230.036729)
			(xy 3.803344 -230.125023) (xy 3.785108 -230.167688) (xy 3.781226 -230.177617) (xy 3.781211 -230.198915)
			(xy 3.785108 -230.208836) (xy 3.803353 -230.251498) (xy 3.831897 -230.339791) (xy 3.85109 -230.430576)
			(xy 3.851992 -230.439214) (xy 7.371842 -230.439214) (xy 7.372426 -230.392818) (xy 7.38207 -230.30053)
			(xy 7.401265 -230.209746) (xy 7.429804 -230.121453) (xy 7.448042 -230.078788) (xy 7.451853 -230.068845)
			(xy 7.451858 -230.04758) (xy 7.448042 -230.03764) (xy 7.429805 -229.994975) (xy 7.401258 -229.906684)
			(xy 7.382063 -229.815899) (xy 7.372428 -229.72361) (xy 7.371842 -229.677214) (xy 7.372346 -229.634866)
			(xy 7.380397 -229.550552) (xy 7.396426 -229.467386) (xy 7.420287 -229.386119) (xy 7.451766 -229.307489)
			(xy 7.490577 -229.232208) (xy 7.536367 -229.160956) (xy 7.588723 -229.09438) (xy 7.647171 -229.033082)
			(xy 7.711181 -228.977617) (xy 7.780173 -228.928488) (xy 7.853523 -228.886139) (xy 7.930566 -228.850955)
			(xy 8.010605 -228.823253) (xy 8.092914 -228.803285) (xy 8.176749 -228.791232) (xy 8.26135 -228.787202)
			(xy 8.345951 -228.791232) (xy 8.429786 -228.803285) (xy 8.512095 -228.823253) (xy 8.592134 -228.850955)
			(xy 8.669177 -228.886139) (xy 8.742527 -228.928488) (xy 8.811519 -228.977617) (xy 8.875529 -229.033082)
			(xy 8.933977 -229.09438) (xy 8.986333 -229.160956) (xy 9.032123 -229.232208) (xy 9.070934 -229.307489)
			(xy 9.102413 -229.386119) (xy 9.126274 -229.467386) (xy 9.142303 -229.550552) (xy 9.150354 -229.634866)
			(xy 9.150858 -229.677214) (xy 9.150284 -229.72361) (xy 9.140637 -229.815899) (xy 9.121439 -229.906682)
			(xy 9.092897 -229.994976) (xy 9.074658 -230.03764) (xy 9.070831 -230.047577) (xy 9.070836 -230.068848)
			(xy 9.074658 -230.078788) (xy 9.092904 -230.12145) (xy 9.121449 -230.209742) (xy 9.140641 -230.300527)
			(xy 9.150274 -230.392818) (xy 9.150858 -230.439214) (xy 9.150354 -230.481562) (xy 9.142303 -230.565876)
			(xy 9.126274 -230.649042) (xy 9.102413 -230.730309) (xy 9.070934 -230.808939) (xy 9.032123 -230.88422)
			(xy 8.986333 -230.955472) (xy 8.933977 -231.022048) (xy 8.875529 -231.083346) (xy 8.811519 -231.138811)
			(xy 8.742527 -231.18794) (xy 8.669177 -231.230289) (xy 8.592134 -231.265473) (xy 8.512095 -231.293175)
			(xy 8.429786 -231.313143) (xy 8.345951 -231.325196) (xy 8.26135 -231.329227) (xy 8.176749 -231.325196)
			(xy 8.092914 -231.313143) (xy 8.010605 -231.293175) (xy 7.930566 -231.265473) (xy 7.853523 -231.230289)
			(xy 7.780173 -231.18794) (xy 7.711181 -231.138811) (xy 7.647171 -231.083346) (xy 7.588723 -231.022048)
			(xy 7.536367 -230.955472) (xy 7.490577 -230.88422) (xy 7.451766 -230.808939) (xy 7.420287 -230.730309)
			(xy 7.396426 -230.649042) (xy 7.380397 -230.565876) (xy 7.372346 -230.481562) (xy 7.371842 -230.439214)
			(xy 3.851992 -230.439214) (xy 3.860723 -230.522866) (xy 3.861308 -230.569262) (xy 3.860804 -230.61161)
			(xy 3.852753 -230.695924) (xy 3.836724 -230.77909) (xy 3.812863 -230.860357) (xy 3.781384 -230.938987)
			(xy 3.742573 -231.014268) (xy 3.696783 -231.08552) (xy 3.644427 -231.152096) (xy 3.585979 -231.213394)
			(xy 3.521969 -231.268859) (xy 3.452977 -231.317988) (xy 3.379627 -231.360337) (xy 3.302584 -231.395521)
			(xy 3.222545 -231.423223) (xy 3.140236 -231.443191) (xy 3.056401 -231.455244) (xy 2.9718 -231.459275)
			(xy 2.887199 -231.455244) (xy 2.803364 -231.443191) (xy 2.721055 -231.423223) (xy 2.641016 -231.395521)
			(xy 2.563973 -231.360337) (xy 2.490623 -231.317988) (xy 2.421631 -231.268859) (xy 2.357621 -231.213394)
			(xy 2.299173 -231.152096) (xy 2.246817 -231.08552) (xy 2.201027 -231.014268) (xy 2.162216 -230.938987)
			(xy 2.130737 -230.860357) (xy 2.106876 -230.77909) (xy 2.090847 -230.695924) (xy 2.082796 -230.61161)
			(xy 2.082292 -230.569262) (xy 1.651254 -230.569262) (xy 1.651254 -231.260904) (xy 1.652778 -231.31145)
			(xy 1.651254 -231.361996) (xy 1.651254 -235.903262) (xy 2.082292 -235.903262) (xy 2.082897 -235.856867)
			(xy 2.092535 -235.764579) (xy 2.111725 -235.673795) (xy 2.140257 -235.585501) (xy 2.158492 -235.542836)
			(xy 2.16242 -235.532921) (xy 2.162405 -235.51161) (xy 2.158492 -235.501688) (xy 2.140248 -235.459025)
			(xy 2.111704 -235.370733) (xy 2.092511 -235.279948) (xy 2.082877 -235.187658) (xy 2.082292 -235.141262)
			(xy 2.082766 -235.10001) (xy 2.09042 -235.01786) (xy 2.105648 -234.936773) (xy 2.128317 -234.857444)
			(xy 2.158235 -234.780554) (xy 2.195142 -234.706764) (xy 2.238723 -234.636709) (xy 2.288604 -234.57099)
			(xy 2.344354 -234.510171) (xy 2.405497 -234.454775) (xy 2.471505 -234.405278) (xy 2.541813 -234.362106)
			(xy 2.578608 -234.343448) (xy 2.586917 -234.338886) (xy 2.599674 -234.324883) (xy 2.606466 -234.307201)
			(xy 2.606802 -234.297728) (xy 2.606802 -234.206796) (xy 2.606428 -234.197328) (xy 2.599639 -234.179656)
			(xy 2.586909 -234.165642) (xy 2.578608 -234.161076) (xy 2.541809 -234.142422) (xy 2.471489 -234.099263)
			(xy 2.405468 -234.049775) (xy 2.344316 -233.994385) (xy 2.288557 -233.933568) (xy 2.238672 -233.867848)
			(xy 2.195089 -233.79779) (xy 2.158182 -233.723996) (xy 2.12827 -233.6471) (xy 2.105609 -233.567765)
			(xy 2.090395 -233.486671) (xy 2.082757 -233.404516) (xy 2.082292 -233.363262) (xy 2.082897 -233.316867)
			(xy 2.092535 -233.224579) (xy 2.111725 -233.133795) (xy 2.140257 -233.045501) (xy 2.158492 -233.002836)
			(xy 2.16242 -232.992921) (xy 2.162405 -232.97161) (xy 2.158492 -232.961688) (xy 2.140248 -232.919025)
			(xy 2.111704 -232.830733) (xy 2.092511 -232.739948) (xy 2.082877 -232.647658) (xy 2.082292 -232.601262)
			(xy 2.082796 -232.558914) (xy 2.090847 -232.4746) (xy 2.106876 -232.391434) (xy 2.130737 -232.310167)
			(xy 2.162216 -232.231537) (xy 2.201027 -232.156256) (xy 2.246817 -232.085004) (xy 2.299173 -232.018428)
			(xy 2.357621 -231.95713) (xy 2.421631 -231.901665) (xy 2.490623 -231.852536) (xy 2.563973 -231.810187)
			(xy 2.641016 -231.775003) (xy 2.721055 -231.747301) (xy 2.803364 -231.727333) (xy 2.887199 -231.71528)
			(xy 2.9718 -231.71125) (xy 3.056401 -231.71528) (xy 3.140236 -231.727333) (xy 3.222545 -231.747301)
			(xy 3.302584 -231.775003) (xy 3.379627 -231.810187) (xy 3.452977 -231.852536) (xy 3.521969 -231.901665)
			(xy 3.585979 -231.95713) (xy 3.644427 -232.018428) (xy 3.696783 -232.085004) (xy 3.742573 -232.156256)
			(xy 3.781384 -232.231537) (xy 3.812863 -232.310167) (xy 3.836724 -232.391434) (xy 3.852753 -232.4746)
			(xy 3.860804 -232.558914) (xy 3.861308 -232.601262) (xy 3.860712 -232.647657) (xy 3.851071 -232.739945)
			(xy 3.831879 -232.830729) (xy 3.803344 -232.919023) (xy 3.785108 -232.961688) (xy 3.781226 -232.971617)
			(xy 3.781211 -232.992915) (xy 3.785108 -233.002836) (xy 3.803353 -233.045498) (xy 3.831897 -233.133791)
			(xy 3.85109 -233.224576) (xy 3.860723 -233.316866) (xy 3.861308 -233.363262) (xy 3.860838 -233.404514)
			(xy 3.853183 -233.486664) (xy 3.837955 -233.567751) (xy 3.815285 -233.647081) (xy 3.785367 -233.72397)
			(xy 3.748459 -233.79776) (xy 3.704878 -233.867815) (xy 3.654997 -233.933535) (xy 3.599247 -233.994353)
			(xy 3.538104 -234.049749) (xy 3.472095 -234.099246) (xy 3.401787 -234.142418) (xy 3.364992 -234.161076)
			(xy 3.356672 -234.165622) (xy 3.343917 -234.179632) (xy 3.33713 -234.197321) (xy 3.336798 -234.206796)
			(xy 3.336798 -234.297728) (xy 3.337155 -234.307197) (xy 3.343952 -234.32487) (xy 3.356689 -234.338883)
			(xy 3.364992 -234.343448) (xy 3.401798 -234.362089) (xy 3.472118 -234.40525) (xy 3.538137 -234.454739)
			(xy 3.599289 -234.510131) (xy 3.655047 -234.570949) (xy 3.704932 -234.63667) (xy 3.748515 -234.70673)
			(xy 3.785421 -234.780525) (xy 3.815332 -234.857421) (xy 3.837992 -234.936758) (xy 3.853207 -235.017852)
			(xy 3.860843 -235.100007) (xy 3.861308 -235.141262) (xy 3.860712 -235.187657) (xy 3.851071 -235.279945)
			(xy 3.831879 -235.370729) (xy 3.803344 -235.459023) (xy 3.785108 -235.501688) (xy 3.781226 -235.511617)
			(xy 3.781211 -235.532915) (xy 3.785108 -235.542836) (xy 3.803353 -235.585498) (xy 3.831897 -235.673791)
			(xy 3.85109 -235.764576) (xy 3.851992 -235.773214) (xy 7.397242 -235.773214) (xy 7.397826 -235.726818)
			(xy 7.40747 -235.63453) (xy 7.426665 -235.543746) (xy 7.455204 -235.455453) (xy 7.473442 -235.412788)
			(xy 7.477253 -235.402845) (xy 7.477258 -235.38158) (xy 7.473442 -235.37164) (xy 7.455205 -235.328975)
			(xy 7.426658 -235.240684) (xy 7.407463 -235.149899) (xy 7.397828 -235.05761) (xy 7.397242 -235.011214)
			(xy 7.39779 -234.967554) (xy 7.406336 -234.880653) (xy 7.423357 -234.795007) (xy 7.448689 -234.711442)
			(xy 7.482088 -234.630762) (xy 7.523233 -234.553743) (xy 7.571727 -234.481127) (xy 7.627105 -234.413613)
			(xy 7.688832 -234.35185) (xy 7.756314 -234.296434) (xy 7.828902 -234.247897) (xy 7.905897 -234.206708)
			(xy 7.986558 -234.173262) (xy 8.028178 -234.16006) (xy 8.043926 -234.155234) (xy 8.063738 -234.129326)
			(xy 8.06704 -234.00004) (xy 8.048752 -233.973116) (xy 8.033258 -233.967528) (xy 7.994142 -233.952769)
			(xy 7.918612 -233.916911) (xy 7.846779 -233.874125) (xy 7.779278 -233.824789) (xy 7.716702 -233.769337)
			(xy 7.659605 -233.708259) (xy 7.60849 -233.642094) (xy 7.563808 -233.571425) (xy 7.525953 -233.496876)
			(xy 7.49526 -233.419104) (xy 7.471998 -233.338796) (xy 7.456373 -233.256659) (xy 7.448523 -233.173419)
			(xy 7.448042 -233.131614) (xy 7.448626 -233.085218) (xy 7.45827 -232.99293) (xy 7.477465 -232.902146)
			(xy 7.506004 -232.813853) (xy 7.524242 -232.771188) (xy 7.528053 -232.761245) (xy 7.528058 -232.73998)
			(xy 7.524242 -232.73004) (xy 7.506005 -232.687375) (xy 7.477458 -232.599084) (xy 7.458263 -232.508299)
			(xy 7.448628 -232.41601) (xy 7.448042 -232.369614) (xy 7.448546 -232.327266) (xy 7.456597 -232.242952)
			(xy 7.472626 -232.159786) (xy 7.496487 -232.078519) (xy 7.527966 -231.999889) (xy 7.566777 -231.924608)
			(xy 7.612567 -231.853356) (xy 7.664923 -231.78678) (xy 7.723371 -231.725482) (xy 7.787381 -231.670017)
			(xy 7.856373 -231.620888) (xy 7.929723 -231.578539) (xy 8.006766 -231.543355) (xy 8.086805 -231.515653)
			(xy 8.169114 -231.495685) (xy 8.252949 -231.483632) (xy 8.33755 -231.479602) (xy 8.422151 -231.483632)
			(xy 8.505986 -231.495685) (xy 8.588295 -231.515653) (xy 8.668334 -231.543355) (xy 8.745377 -231.578539)
			(xy 8.818727 -231.620888) (xy 8.887719 -231.670017) (xy 8.951729 -231.725482) (xy 9.010177 -231.78678)
			(xy 9.062533 -231.853356) (xy 9.108323 -231.924608) (xy 9.147134 -231.999889) (xy 9.178613 -232.078519)
			(xy 9.202474 -232.159786) (xy 9.218503 -232.242952) (xy 9.226554 -232.327266) (xy 9.227058 -232.369614)
			(xy 9.226484 -232.41601) (xy 9.216837 -232.508299) (xy 9.197639 -232.599082) (xy 9.169097 -232.687376)
			(xy 9.150858 -232.73004) (xy 9.147031 -232.739977) (xy 9.147036 -232.761248) (xy 9.150858 -232.771188)
			(xy 9.169104 -232.81385) (xy 9.197649 -232.902142) (xy 9.216841 -232.992927) (xy 9.226474 -233.085218)
			(xy 9.227058 -233.131614) (xy 9.226535 -233.175275) (xy 9.217987 -233.262177) (xy 9.200963 -233.347823)
			(xy 9.175629 -233.431388) (xy 9.142227 -233.512069) (xy 9.10108 -233.589088) (xy 9.052583 -233.661704)
			(xy 8.997204 -233.729218) (xy 8.935475 -233.79098) (xy 8.867991 -233.846396) (xy 8.795401 -233.894932)
			(xy 8.718405 -233.936121) (xy 8.637742 -233.969566) (xy 8.596122 -233.982768) (xy 8.580374 -233.987594)
			(xy 8.560562 -234.013502) (xy 8.55726 -234.142788) (xy 8.575548 -234.169712) (xy 8.591042 -234.1753)
			(xy 8.630161 -234.190052) (xy 8.705691 -234.22591) (xy 8.777524 -234.268697) (xy 8.845026 -234.318034)
			(xy 8.907601 -234.373486) (xy 8.964698 -234.434564) (xy 9.015813 -234.50073) (xy 9.060495 -234.5714)
			(xy 9.098349 -234.64595) (xy 9.129042 -234.723722) (xy 9.152304 -234.804031) (xy 9.167928 -234.886168)
			(xy 9.175778 -234.969409) (xy 9.176258 -235.011214) (xy 9.175684 -235.05761) (xy 9.166037 -235.149899)
			(xy 9.146839 -235.240682) (xy 9.118297 -235.328976) (xy 9.100058 -235.37164) (xy 9.096231 -235.381577)
			(xy 9.096236 -235.402848) (xy 9.100058 -235.412788) (xy 9.118304 -235.45545) (xy 9.146849 -235.543742)
			(xy 9.166041 -235.634527) (xy 9.175674 -235.726818) (xy 9.176258 -235.773214) (xy 9.175754 -235.815562)
			(xy 9.167703 -235.899876) (xy 9.151674 -235.983042) (xy 9.127813 -236.064309) (xy 9.096334 -236.142939)
			(xy 9.057523 -236.21822) (xy 9.011733 -236.289472) (xy 8.959377 -236.356048) (xy 8.900929 -236.417346)
			(xy 8.836919 -236.472811) (xy 8.767927 -236.52194) (xy 8.694577 -236.564289) (xy 8.617534 -236.599473)
			(xy 8.537495 -236.627175) (xy 8.455186 -236.647143) (xy 8.371351 -236.659196) (xy 8.28675 -236.663227)
			(xy 8.202149 -236.659196) (xy 8.118314 -236.647143) (xy 8.036005 -236.627175) (xy 7.955966 -236.599473)
			(xy 7.878923 -236.564289) (xy 7.805573 -236.52194) (xy 7.736581 -236.472811) (xy 7.672571 -236.417346)
			(xy 7.614123 -236.356048) (xy 7.561767 -236.289472) (xy 7.515977 -236.21822) (xy 7.477166 -236.142939)
			(xy 7.445687 -236.064309) (xy 7.421826 -235.983042) (xy 7.405797 -235.899876) (xy 7.397746 -235.815562)
			(xy 7.397242 -235.773214) (xy 3.851992 -235.773214) (xy 3.860723 -235.856866) (xy 3.861308 -235.903262)
			(xy 3.860876 -235.943463) (xy 3.853622 -236.023536) (xy 3.839171 -236.102629) (xy 3.81764 -236.180094)
			(xy 3.789205 -236.255299) (xy 3.754098 -236.327631) (xy 3.712606 -236.396499) (xy 3.665067 -236.461341)
			(xy 3.638804 -236.49178) (xy 3.6322 -236.4994) (xy 3.625596 -236.51845) (xy 3.631438 -236.610652)
			(xy 3.640328 -236.628686) (xy 3.647948 -236.63529) (xy 3.679243 -236.663388) (xy 3.736964 -236.724568)
			(xy 3.788651 -236.790924) (xy 3.833844 -236.861863) (xy 3.872138 -236.93675) (xy 3.903193 -237.014919)
			(xy 3.92673 -237.095669) (xy 3.942539 -237.178281) (xy 3.95048 -237.262017) (xy 3.95097 -237.304072)
			(xy 3.95038 -237.350467) (xy 3.940738 -237.442756) (xy 3.921544 -237.53354) (xy 3.893007 -237.621833)
			(xy 3.87477 -237.664498) (xy 3.870967 -237.674443) (xy 3.870957 -237.695706) (xy 3.87477 -237.705646)
			(xy 3.893015 -237.748308) (xy 3.921559 -237.8366) (xy 3.940752 -237.927386) (xy 3.950385 -238.019676)
			(xy 3.95097 -238.066072) (xy 3.950466 -238.10842) (xy 3.942415 -238.192734) (xy 3.940049 -238.20501)
			(xy 6.11759 -238.20501) (xy 6.118177 -238.158615) (xy 6.127821 -238.066326) (xy 6.147015 -237.975542)
			(xy 6.175553 -237.887249) (xy 6.19379 -237.844584) (xy 6.197689 -237.83466) (xy 6.197693 -237.813358)
			(xy 6.19379 -237.803436) (xy 6.175548 -237.760773) (xy 6.147004 -237.672481) (xy 6.12781 -237.581696)
			(xy 6.118175 -237.489406) (xy 6.11759 -237.44301) (xy 6.118094 -237.400662) (xy 6.126145 -237.316348)
			(xy 6.142174 -237.233182) (xy 6.166035 -237.151915) (xy 6.197514 -237.073285) (xy 6.236325 -236.998004)
			(xy 6.282115 -236.926752) (xy 6.334471 -236.860176) (xy 6.392919 -236.798878) (xy 6.456929 -236.743413)
			(xy 6.525921 -236.694284) (xy 6.599271 -236.651935) (xy 6.676314 -236.616751) (xy 6.756353 -236.589049)
			(xy 6.838662 -236.569081) (xy 6.922497 -236.557028) (xy 7.007098 -236.552998) (xy 7.091699 -236.557028)
			(xy 7.175534 -236.569081) (xy 7.257843 -236.589049) (xy 7.337882 -236.616751) (xy 7.414925 -236.651935)
			(xy 7.488275 -236.694284) (xy 7.557267 -236.743413) (xy 7.621277 -236.798878) (xy 7.679725 -236.860176)
			(xy 7.732081 -236.926752) (xy 7.777871 -236.998004) (xy 7.816682 -237.073285) (xy 7.848161 -237.151915)
			(xy 7.872022 -237.233182) (xy 7.888051 -237.316348) (xy 7.896102 -237.400662) (xy 7.896606 -237.44301)
			(xy 7.896027 -237.489406) (xy 7.886381 -237.581694) (xy 7.867184 -237.672478) (xy 7.838644 -237.760771)
			(xy 7.820406 -237.803436) (xy 7.816495 -237.813356) (xy 7.816499 -237.834662) (xy 7.820406 -237.844584)
			(xy 7.838654 -237.887245) (xy 7.867197 -237.975538) (xy 7.886389 -238.066323) (xy 7.896022 -238.158614)
			(xy 7.896606 -238.20501) (xy 7.896102 -238.247358) (xy 7.888051 -238.331672) (xy 7.872022 -238.414838)
			(xy 7.848161 -238.496105) (xy 7.816682 -238.574735) (xy 7.777871 -238.650016) (xy 7.732081 -238.721268)
			(xy 7.679725 -238.787844) (xy 7.621277 -238.849142) (xy 7.557267 -238.904607) (xy 7.488275 -238.953736)
			(xy 7.414925 -238.996085) (xy 7.337882 -239.031269) (xy 7.257843 -239.058971) (xy 7.175534 -239.078939)
			(xy 7.091699 -239.090992) (xy 7.007098 -239.095023) (xy 6.922497 -239.090992) (xy 6.838662 -239.078939)
			(xy 6.756353 -239.058971) (xy 6.676314 -239.031269) (xy 6.599271 -238.996085) (xy 6.525921 -238.953736)
			(xy 6.456929 -238.904607) (xy 6.392919 -238.849142) (xy 6.334471 -238.787844) (xy 6.282115 -238.721268)
			(xy 6.236325 -238.650016) (xy 6.197514 -238.574735) (xy 6.166035 -238.496105) (xy 6.142174 -238.414838)
			(xy 6.126145 -238.331672) (xy 6.118094 -238.247358) (xy 6.11759 -238.20501) (xy 3.940049 -238.20501)
			(xy 3.926386 -238.2759) (xy 3.902525 -238.357167) (xy 3.871046 -238.435797) (xy 3.832235 -238.511078)
			(xy 3.786445 -238.58233) (xy 3.734089 -238.648906) (xy 3.675641 -238.710204) (xy 3.611631 -238.765669)
			(xy 3.542639 -238.814798) (xy 3.469289 -238.857147) (xy 3.392246 -238.892331) (xy 3.312207 -238.920033)
			(xy 3.229898 -238.940001) (xy 3.146063 -238.952054) (xy 3.061462 -238.956085) (xy 2.976861 -238.952054)
			(xy 2.893026 -238.940001) (xy 2.810717 -238.920033) (xy 2.730678 -238.892331) (xy 2.653635 -238.857147)
			(xy 2.580285 -238.814798) (xy 2.511293 -238.765669) (xy 2.447283 -238.710204) (xy 2.388835 -238.648906)
			(xy 2.336479 -238.58233) (xy 2.290689 -238.511078) (xy 2.251878 -238.435797) (xy 2.220399 -238.357167)
			(xy 2.196538 -238.2759) (xy 2.180509 -238.192734) (xy 2.172458 -238.10842) (xy 2.171954 -238.066072)
			(xy 2.172557 -238.019677) (xy 2.182195 -237.927389) (xy 2.201385 -237.836605) (xy 2.229918 -237.748311)
			(xy 2.248154 -237.705646) (xy 2.251989 -237.695711) (xy 2.251978 -237.674438) (xy 2.248154 -237.664498)
			(xy 2.229911 -237.621835) (xy 2.201366 -237.533543) (xy 2.182173 -237.442758) (xy 2.172539 -237.350468)
			(xy 2.171954 -237.304072) (xy 2.172417 -237.263872) (xy 2.179667 -237.1838) (xy 2.194114 -237.104708)
			(xy 2.215641 -237.027244) (xy 2.244072 -236.952038) (xy 2.279175 -236.879706) (xy 2.320663 -236.810837)
			(xy 2.368197 -236.745994) (xy 2.394458 -236.715554) (xy 2.401062 -236.707934) (xy 2.407666 -236.688884)
			(xy 2.401824 -236.596682) (xy 2.392934 -236.578648) (xy 2.385314 -236.572044) (xy 2.354016 -236.543948)
			(xy 2.296296 -236.482768) (xy 2.244609 -236.416412) (xy 2.199416 -236.345473) (xy 2.161122 -236.270585)
			(xy 2.130067 -236.192416) (xy 2.106531 -236.111665) (xy 2.090722 -236.029053) (xy 2.082782 -235.945318)
			(xy 2.082292 -235.903262) (xy 1.651254 -235.903262) (xy 1.651254 -236.340904) (xy 1.652778 -236.39145)
			(xy 1.651254 -236.441996) (xy 1.651254 -241.420904) (xy 1.652778 -241.47145) (xy 1.651254 -241.521996)
			(xy 1.651254 -241.909854) (xy 21.349208 -241.909854) (xy 21.349208 -229.909624) (xy 21.349702 -229.81536)
			(xy 21.357596 -229.626996) (xy 21.373372 -229.439129) (xy 21.397001 -229.252087) (xy 21.428442 -229.066198)
			(xy 21.467639 -228.881789) (xy 21.514524 -228.699184) (xy 21.569015 -228.518702) (xy 21.631016 -228.34066)
			(xy 21.700418 -228.16537) (xy 21.777099 -227.993141) (xy 21.860926 -227.824273) (xy 21.95175 -227.659064)
			(xy 22.049413 -227.497804) (xy 22.153743 -227.340774) (xy 22.264558 -227.188251) (xy 22.381662 -227.040502)
			(xy 22.50485 -226.897787) (xy 22.633907 -226.760356) (xy 22.768606 -226.628449) (xy 22.90871 -226.502299)
			(xy 23.053974 -226.382126) (xy 23.204142 -226.268142) (xy 23.358953 -226.160546) (xy 23.518133 -226.059527)
			(xy 23.681403 -225.965263) (xy 23.848478 -225.877918) (xy 24.019064 -225.797647) (xy 24.192861 -225.724589)
			(xy 24.369566 -225.658873) (xy 24.548867 -225.600615) (xy 24.730451 -225.549915) (xy 24.913999 -225.506865)
			(xy 25.099188 -225.471538) (xy 25.285694 -225.443997) (xy 25.47319 -225.424291) (xy 25.661347 -225.412453)
			(xy 25.849834 -225.408505) (xy 26.038321 -225.412453) (xy 26.226478 -225.424291) (xy 26.413974 -225.443997)
			(xy 26.60048 -225.471538) (xy 26.785669 -225.506865) (xy 26.969217 -225.549915) (xy 27.150801 -225.600615)
			(xy 27.330102 -225.658873) (xy 27.506807 -225.724589) (xy 27.680604 -225.797647) (xy 27.85119 -225.877918)
			(xy 28.018265 -225.965263) (xy 28.181535 -226.059527) (xy 28.340715 -226.160546) (xy 28.495526 -226.268142)
			(xy 28.645694 -226.382126) (xy 28.790958 -226.502299) (xy 28.931062 -226.628449) (xy 29.065761 -226.760356)
			(xy 29.194818 -226.897787) (xy 29.318006 -227.040502) (xy 29.43511 -227.188251) (xy 29.545925 -227.340774)
			(xy 29.650255 -227.497804) (xy 29.720148 -227.61321) (xy 37.175948 -227.61321) (xy 37.17653 -227.566814)
			(xy 37.186174 -227.474526) (xy 37.20537 -227.383742) (xy 37.23391 -227.295449) (xy 37.252148 -227.252784)
			(xy 37.255961 -227.242842) (xy 37.255964 -227.221576) (xy 37.252148 -227.211636) (xy 37.23391 -227.168971)
			(xy 37.205363 -227.08068) (xy 37.186168 -226.989896) (xy 37.176533 -226.897606) (xy 37.175948 -226.85121)
			(xy 37.17653 -226.804814) (xy 37.186174 -226.712526) (xy 37.20537 -226.621742) (xy 37.23391 -226.533449)
			(xy 37.252148 -226.490784) (xy 37.255961 -226.480842) (xy 37.255964 -226.459576) (xy 37.252148 -226.449636)
			(xy 37.23391 -226.406971) (xy 37.205363 -226.31868) (xy 37.186168 -226.227896) (xy 37.176533 -226.135606)
			(xy 37.175948 -226.08921) (xy 37.176476 -226.048109) (xy 37.18406 -225.966257) (xy 37.199163 -225.885455)
			(xy 37.221657 -225.80639) (xy 37.25135 -225.729739) (xy 37.287989 -225.656154) (xy 37.331262 -225.586263)
			(xy 37.380798 -225.520663) (xy 37.436175 -225.459913) (xy 37.496921 -225.404532) (xy 37.562518 -225.354992)
			(xy 37.632406 -225.311716) (xy 37.705989 -225.275072) (xy 37.782639 -225.245374) (xy 37.861702 -225.222875)
			(xy 37.942504 -225.207767) (xy 38.024355 -225.200179) (xy 38.065456 -225.199702) (xy 38.103744 -225.200131)
			(xy 38.180035 -225.206754) (xy 38.255474 -225.219903) (xy 38.329506 -225.239481) (xy 38.365684 -225.252026)
			(xy 38.374122 -225.254668) (xy 38.39179 -225.254668) (xy 38.400228 -225.252026) (xy 38.436397 -225.239454)
			(xy 38.510429 -225.219862) (xy 38.585872 -225.206715) (xy 38.662166 -225.20011) (xy 38.700456 -225.199702)
			(xy 38.741559 -225.200194) (xy 38.823414 -225.207775) (xy 38.90422 -225.222877) (xy 38.983288 -225.245371)
			(xy 39.059944 -225.275064) (xy 39.133532 -225.311704) (xy 39.203426 -225.354977) (xy 39.269028 -225.404516)
			(xy 39.32978 -225.459896) (xy 39.385163 -225.520645) (xy 39.434703 -225.586246) (xy 39.47798 -225.656138)
			(xy 39.514622 -225.729725) (xy 39.544319 -225.806379) (xy 39.566815 -225.885447) (xy 39.58192 -225.966252)
			(xy 39.589504 -226.048107) (xy 39.589964 -226.08921) (xy 39.589388 -226.135606) (xy 39.579742 -226.227895)
			(xy 39.560544 -226.318678) (xy 39.532003 -226.406972) (xy 39.513764 -226.449636) (xy 39.509939 -226.459574)
			(xy 39.509943 -226.480844) (xy 39.513764 -226.490784) (xy 39.532009 -226.533446) (xy 39.560554 -226.621738)
			(xy 39.579747 -226.712523) (xy 39.58938 -226.804814) (xy 39.589964 -226.85121) (xy 39.589388 -226.897606)
			(xy 39.579742 -226.989895) (xy 39.560544 -227.080678) (xy 39.532003 -227.168972) (xy 39.513764 -227.211636)
			(xy 39.509939 -227.221574) (xy 39.509943 -227.242844) (xy 39.513764 -227.252784) (xy 39.532009 -227.295446)
			(xy 39.560554 -227.383738) (xy 39.579747 -227.474523) (xy 39.58938 -227.566814) (xy 39.589964 -227.61321)
			(xy 39.589557 -227.654315) (xy 39.581971 -227.736173) (xy 39.566864 -227.816982) (xy 39.544365 -227.896053)
			(xy 39.514666 -227.97271) (xy 39.47802 -228.0463) (xy 39.434741 -228.116195) (xy 39.385197 -228.181798)
			(xy 39.329811 -228.242549) (xy 39.269056 -228.297932) (xy 39.23399 -228.32441) (xy 44.897548 -228.32441)
			(xy 44.89813 -228.278014) (xy 44.907774 -228.185726) (xy 44.92697 -228.094942) (xy 44.95551 -228.006649)
			(xy 44.973748 -227.963984) (xy 44.977561 -227.954042) (xy 44.977564 -227.932776) (xy 44.973748 -227.922836)
			(xy 44.95551 -227.880171) (xy 44.926963 -227.79188) (xy 44.907768 -227.701096) (xy 44.898133 -227.608806)
			(xy 44.897548 -227.56241) (xy 44.89813 -227.516014) (xy 44.907774 -227.423726) (xy 44.92697 -227.332942)
			(xy 44.95551 -227.244649) (xy 44.973748 -227.201984) (xy 44.977561 -227.192042) (xy 44.977564 -227.170776)
			(xy 44.973748 -227.160836) (xy 44.95551 -227.118171) (xy 44.926963 -227.02988) (xy 44.907768 -226.939096)
			(xy 44.898133 -226.846806) (xy 44.897548 -226.80041) (xy 44.89813 -226.754014) (xy 44.907774 -226.661726)
			(xy 44.92697 -226.570942) (xy 44.95551 -226.482649) (xy 44.973748 -226.439984) (xy 44.977561 -226.430042)
			(xy 44.977564 -226.408776) (xy 44.973748 -226.398836) (xy 44.95551 -226.356171) (xy 44.926963 -226.26788)
			(xy 44.907768 -226.177096) (xy 44.898133 -226.084806) (xy 44.897548 -226.03841) (xy 44.898052 -225.996062)
			(xy 44.906103 -225.911748) (xy 44.922132 -225.828582) (xy 44.945993 -225.747315) (xy 44.977472 -225.668685)
			(xy 45.016283 -225.593404) (xy 45.062073 -225.522152) (xy 45.114429 -225.455576) (xy 45.172877 -225.394278)
			(xy 45.236887 -225.338813) (xy 45.305879 -225.289684) (xy 45.379229 -225.247335) (xy 45.456272 -225.212151)
			(xy 45.536311 -225.184449) (xy 45.61862 -225.164481) (xy 45.702455 -225.152428) (xy 45.787056 -225.148398)
			(xy 45.871657 -225.152428) (xy 45.955492 -225.164481) (xy 46.037801 -225.184449) (xy 46.11784 -225.212151)
			(xy 46.194883 -225.247335) (xy 46.268233 -225.289684) (xy 46.337225 -225.338813) (xy 46.401235 -225.394278)
			(xy 46.459683 -225.455576) (xy 46.512039 -225.522152) (xy 46.557829 -225.593404) (xy 46.59664 -225.668685)
			(xy 46.628119 -225.747315) (xy 46.65198 -225.828582) (xy 46.668009 -225.911748) (xy 46.67606 -225.996062)
			(xy 46.676564 -226.03841) (xy 46.675988 -226.084806) (xy 46.666342 -226.177095) (xy 46.647144 -226.267878)
			(xy 46.618603 -226.356172) (xy 46.600364 -226.398836) (xy 46.596539 -226.408774) (xy 46.596543 -226.430044)
			(xy 46.600364 -226.439984) (xy 46.618609 -226.482646) (xy 46.647154 -226.570938) (xy 46.666347 -226.661723)
			(xy 46.67598 -226.754014) (xy 46.676564 -226.80041) (xy 46.675988 -226.846806) (xy 46.666342 -226.939095)
			(xy 46.647144 -227.029878) (xy 46.618603 -227.118172) (xy 46.600364 -227.160836) (xy 46.596539 -227.170774)
			(xy 46.596543 -227.192044) (xy 46.600364 -227.201984) (xy 46.618609 -227.244646) (xy 46.647154 -227.332938)
			(xy 46.666347 -227.423723) (xy 46.67598 -227.516014) (xy 46.676564 -227.56241) (xy 46.675988 -227.608806)
			(xy 46.666342 -227.701095) (xy 46.647144 -227.791878) (xy 46.618603 -227.880172) (xy 46.600364 -227.922836)
			(xy 46.596539 -227.932774) (xy 46.596543 -227.954044) (xy 46.600364 -227.963984) (xy 46.618609 -228.006646)
			(xy 46.647154 -228.094938) (xy 46.666347 -228.185723) (xy 46.67598 -228.278014) (xy 46.676564 -228.32441)
			(xy 46.67606 -228.366758) (xy 46.668009 -228.451072) (xy 46.65198 -228.534238) (xy 46.628119 -228.615505)
			(xy 46.59664 -228.694135) (xy 46.557829 -228.769416) (xy 46.512039 -228.840668) (xy 46.459683 -228.907244)
			(xy 46.401235 -228.968542) (xy 46.337225 -229.024007) (xy 46.268233 -229.073136) (xy 46.194883 -229.115485)
			(xy 46.11784 -229.150669) (xy 46.037801 -229.178371) (xy 45.955492 -229.198339) (xy 45.871657 -229.210392)
			(xy 45.787056 -229.214423) (xy 45.702455 -229.210392) (xy 45.61862 -229.198339) (xy 45.536311 -229.178371)
			(xy 45.456272 -229.150669) (xy 45.379229 -229.115485) (xy 45.305879 -229.073136) (xy 45.236887 -229.024007)
			(xy 45.172877 -228.968542) (xy 45.114429 -228.907244) (xy 45.062073 -228.840668) (xy 45.016283 -228.769416)
			(xy 44.977472 -228.694135) (xy 44.945993 -228.615505) (xy 44.922132 -228.534238) (xy 44.906103 -228.451072)
			(xy 44.898052 -228.366758) (xy 44.897548 -228.32441) (xy 39.23399 -228.32441) (xy 39.20345 -228.347471)
			(xy 39.133553 -228.390747) (xy 39.059961 -228.427388) (xy 38.983302 -228.457082) (xy 38.90423 -228.479576)
			(xy 38.82342 -228.494678) (xy 38.741561 -228.50226) (xy 38.700456 -228.502718) (xy 38.662168 -228.502284)
			(xy 38.585878 -228.495662) (xy 38.510438 -228.482515) (xy 38.436406 -228.462938) (xy 38.400228 -228.450394)
			(xy 38.39179 -228.447752) (xy 38.374122 -228.447752) (xy 38.365684 -228.450394) (xy 38.329514 -228.462963)
			(xy 38.255483 -228.482556) (xy 38.18004 -228.495704) (xy 38.103746 -228.502309) (xy 38.065456 -228.502718)
			(xy 38.024353 -228.502275) (xy 37.942498 -228.494687) (xy 37.861693 -228.479578) (xy 37.782626 -228.457078)
			(xy 37.705972 -228.427379) (xy 37.632386 -228.390735) (xy 37.562494 -228.347457) (xy 37.496894 -228.297915)
			(xy 37.436144 -228.242532) (xy 37.380763 -228.18178) (xy 37.331224 -228.116178) (xy 37.287949 -228.046285)
			(xy 37.251307 -227.972697) (xy 37.221611 -227.896042) (xy 37.199114 -227.816974) (xy 37.184009 -227.736168)
			(xy 37.176423 -227.654313) (xy 37.175948 -227.61321) (xy 29.720148 -227.61321) (xy 29.747918 -227.659064)
			(xy 29.838742 -227.824273) (xy 29.922569 -227.993141) (xy 29.99925 -228.16537) (xy 30.068652 -228.34066)
			(xy 30.130653 -228.518702) (xy 30.185144 -228.699184) (xy 30.232029 -228.881789) (xy 30.271226 -229.066198)
			(xy 30.302667 -229.252087) (xy 30.326296 -229.439129) (xy 30.342072 -229.626996) (xy 30.349966 -229.81536)
			(xy 30.35046 -229.909624) (xy 30.35046 -232.029) (xy 40.48125 -232.029) (xy 40.481828 -231.982604)
			(xy 40.491474 -231.890316) (xy 40.510671 -231.799532) (xy 40.539211 -231.711238) (xy 40.55745 -231.668574)
			(xy 40.561268 -231.658634) (xy 40.561268 -231.637366) (xy 40.55745 -231.627426) (xy 40.539203 -231.584765)
			(xy 40.51066 -231.496472) (xy 40.491468 -231.405687) (xy 40.481835 -231.313396) (xy 40.48125 -231.267)
			(xy 40.481754 -231.224652) (xy 40.489805 -231.140338) (xy 40.505834 -231.057172) (xy 40.529695 -230.975905)
			(xy 40.561174 -230.897275) (xy 40.599985 -230.821994) (xy 40.645775 -230.750742) (xy 40.698131 -230.684166)
			(xy 40.756579 -230.622868) (xy 40.820589 -230.567403) (xy 40.889581 -230.518274) (xy 40.962931 -230.475925)
			(xy 41.039974 -230.440741) (xy 41.120013 -230.413039) (xy 41.202322 -230.393071) (xy 41.286157 -230.381018)
			(xy 41.370758 -230.376988) (xy 41.455359 -230.381018) (xy 41.539194 -230.393071) (xy 41.621503 -230.413039)
			(xy 41.701542 -230.440741) (xy 41.778585 -230.475925) (xy 41.851935 -230.518274) (xy 41.920927 -230.567403)
			(xy 41.984937 -230.622868) (xy 42.043385 -230.684166) (xy 42.095741 -230.750742) (xy 42.141531 -230.821994)
			(xy 42.180342 -230.897275) (xy 42.211821 -230.975905) (xy 42.235682 -231.057172) (xy 42.251711 -231.140338)
			(xy 42.259762 -231.224652) (xy 42.260266 -231.267) (xy 42.259687 -231.313396) (xy 42.250041 -231.405684)
			(xy 42.230844 -231.496468) (xy 42.202305 -231.584761) (xy 42.184066 -231.627426) (xy 42.180247 -231.637366)
			(xy 42.180247 -231.658634) (xy 42.184066 -231.668574) (xy 42.202308 -231.711237) (xy 42.230854 -231.799529)
			(xy 42.250047 -231.890314) (xy 42.259681 -231.982604) (xy 42.260266 -232.029) (xy 45.94225 -232.029)
			(xy 45.942828 -231.982604) (xy 45.952474 -231.890316) (xy 45.971671 -231.799532) (xy 46.000211 -231.711238)
			(xy 46.01845 -231.668574) (xy 46.022268 -231.658634) (xy 46.022268 -231.637366) (xy 46.01845 -231.627426)
			(xy 46.000203 -231.584765) (xy 45.97166 -231.496472) (xy 45.952468 -231.405687) (xy 45.942835 -231.313396)
			(xy 45.94225 -231.267) (xy 45.942754 -231.224652) (xy 45.950805 -231.140338) (xy 45.966834 -231.057172)
			(xy 45.990695 -230.975905) (xy 46.022174 -230.897275) (xy 46.060985 -230.821994) (xy 46.106775 -230.750742)
			(xy 46.159131 -230.684166) (xy 46.217579 -230.622868) (xy 46.281589 -230.567403) (xy 46.350581 -230.518274)
			(xy 46.423931 -230.475925) (xy 46.500974 -230.440741) (xy 46.581013 -230.413039) (xy 46.663322 -230.393071)
			(xy 46.747157 -230.381018) (xy 46.831758 -230.376988) (xy 46.916359 -230.381018) (xy 47.000194 -230.393071)
			(xy 47.082503 -230.413039) (xy 47.162542 -230.440741) (xy 47.239585 -230.475925) (xy 47.312935 -230.518274)
			(xy 47.381927 -230.567403) (xy 47.445937 -230.622868) (xy 47.504385 -230.684166) (xy 47.556741 -230.750742)
			(xy 47.602531 -230.821994) (xy 47.641342 -230.897275) (xy 47.672821 -230.975905) (xy 47.696682 -231.057172)
			(xy 47.712711 -231.140338) (xy 47.720762 -231.224652) (xy 47.721266 -231.267) (xy 47.720687 -231.313396)
			(xy 47.711041 -231.405684) (xy 47.691844 -231.496468) (xy 47.663305 -231.584761) (xy 47.645066 -231.627426)
			(xy 47.641247 -231.637366) (xy 47.641247 -231.658634) (xy 47.645066 -231.668574) (xy 47.663308 -231.711237)
			(xy 47.691854 -231.799529) (xy 47.711047 -231.890314) (xy 47.720681 -231.982604) (xy 47.721266 -232.029)
			(xy 47.720762 -232.071348) (xy 47.712711 -232.155662) (xy 47.696682 -232.238828) (xy 47.672821 -232.320095)
			(xy 47.641342 -232.398725) (xy 47.602531 -232.474006) (xy 47.556741 -232.545258) (xy 47.504385 -232.611834)
			(xy 47.445937 -232.673132) (xy 47.381927 -232.728597) (xy 47.312935 -232.777726) (xy 47.239585 -232.820075)
			(xy 47.162542 -232.855259) (xy 47.082503 -232.882961) (xy 47.000194 -232.902929) (xy 46.916359 -232.914982)
			(xy 46.831758 -232.919013) (xy 46.747157 -232.914982) (xy 46.663322 -232.902929) (xy 46.581013 -232.882961)
			(xy 46.500974 -232.855259) (xy 46.423931 -232.820075) (xy 46.350581 -232.777726) (xy 46.281589 -232.728597)
			(xy 46.217579 -232.673132) (xy 46.159131 -232.611834) (xy 46.106775 -232.545258) (xy 46.060985 -232.474006)
			(xy 46.022174 -232.398725) (xy 45.990695 -232.320095) (xy 45.966834 -232.238828) (xy 45.950805 -232.155662)
			(xy 45.942754 -232.071348) (xy 45.94225 -232.029) (xy 42.260266 -232.029) (xy 42.259762 -232.071348)
			(xy 42.251711 -232.155662) (xy 42.235682 -232.238828) (xy 42.211821 -232.320095) (xy 42.180342 -232.398725)
			(xy 42.141531 -232.474006) (xy 42.095741 -232.545258) (xy 42.043385 -232.611834) (xy 41.984937 -232.673132)
			(xy 41.920927 -232.728597) (xy 41.851935 -232.777726) (xy 41.778585 -232.820075) (xy 41.701542 -232.855259)
			(xy 41.621503 -232.882961) (xy 41.539194 -232.902929) (xy 41.455359 -232.914982) (xy 41.370758 -232.919013)
			(xy 41.286157 -232.914982) (xy 41.202322 -232.902929) (xy 41.120013 -232.882961) (xy 41.039974 -232.855259)
			(xy 40.962931 -232.820075) (xy 40.889581 -232.777726) (xy 40.820589 -232.728597) (xy 40.756579 -232.673132)
			(xy 40.698131 -232.611834) (xy 40.645775 -232.545258) (xy 40.599985 -232.474006) (xy 40.561174 -232.398725)
			(xy 40.529695 -232.320095) (xy 40.505834 -232.238828) (xy 40.489805 -232.155662) (xy 40.481754 -232.071348)
			(xy 40.48125 -232.029) (xy 30.35046 -232.029) (xy 30.35046 -237.363) (xy 40.48125 -237.363) (xy 40.481828 -237.316604)
			(xy 40.491474 -237.224316) (xy 40.510671 -237.133532) (xy 40.539211 -237.045238) (xy 40.55745 -237.002574)
			(xy 40.561268 -236.992634) (xy 40.561268 -236.971366) (xy 40.55745 -236.961426) (xy 40.539203 -236.918765)
			(xy 40.51066 -236.830472) (xy 40.491468 -236.739687) (xy 40.481835 -236.647396) (xy 40.48125 -236.601)
			(xy 40.481692 -236.559747) (xy 40.489349 -236.477597) (xy 40.50458 -236.396508) (xy 40.527253 -236.317178)
			(xy 40.557173 -236.240288) (xy 40.594084 -236.166498) (xy 40.637668 -236.096443) (xy 40.687551 -236.030724)
			(xy 40.743304 -235.969906) (xy 40.804449 -235.914511) (xy 40.87046 -235.865015) (xy 40.94077 -235.821843)
			(xy 40.977566 -235.803186) (xy 40.985871 -235.798618) (xy 40.998622 -235.784615) (xy 41.005418 -235.766937)
			(xy 41.00576 -235.757466) (xy 41.00576 -235.666534) (xy 41.005381 -235.657066) (xy 40.998598 -235.639391)
			(xy 40.985868 -235.625378) (xy 40.977566 -235.620814) (xy 40.940759 -235.602175) (xy 40.870437 -235.559016)
			(xy 40.804415 -235.509528) (xy 40.743262 -235.454137) (xy 40.687503 -235.393319) (xy 40.637617 -235.327598)
			(xy 40.594034 -235.257538) (xy 40.557129 -235.183742) (xy 40.527218 -235.106844) (xy 40.504559 -235.027507)
			(xy 40.489347 -234.946411) (xy 40.481713 -234.864255) (xy 40.48125 -234.823) (xy 40.481828 -234.776604)
			(xy 40.491474 -234.684316) (xy 40.510671 -234.593532) (xy 40.539211 -234.505238) (xy 40.55745 -234.462574)
			(xy 40.561268 -234.452634) (xy 40.561268 -234.431366) (xy 40.55745 -234.421426) (xy 40.539203 -234.378765)
			(xy 40.51066 -234.290472) (xy 40.491468 -234.199687) (xy 40.481835 -234.107396) (xy 40.48125 -234.061)
			(xy 40.481754 -234.018652) (xy 40.489805 -233.934338) (xy 40.505834 -233.851172) (xy 40.529695 -233.769905)
			(xy 40.561174 -233.691275) (xy 40.599985 -233.615994) (xy 40.645775 -233.544742) (xy 40.698131 -233.478166)
			(xy 40.756579 -233.416868) (xy 40.820589 -233.361403) (xy 40.889581 -233.312274) (xy 40.962931 -233.269925)
			(xy 41.039974 -233.234741) (xy 41.120013 -233.207039) (xy 41.202322 -233.187071) (xy 41.286157 -233.175018)
			(xy 41.370758 -233.170988) (xy 41.455359 -233.175018) (xy 41.539194 -233.187071) (xy 41.621503 -233.207039)
			(xy 41.701542 -233.234741) (xy 41.778585 -233.269925) (xy 41.851935 -233.312274) (xy 41.920927 -233.361403)
			(xy 41.984937 -233.416868) (xy 42.043385 -233.478166) (xy 42.095741 -233.544742) (xy 42.141531 -233.615994)
			(xy 42.180342 -233.691275) (xy 42.211821 -233.769905) (xy 42.235682 -233.851172) (xy 42.251711 -233.934338)
			(xy 42.259762 -234.018652) (xy 42.260266 -234.061) (xy 42.259687 -234.107396) (xy 42.250041 -234.199684)
			(xy 42.230844 -234.290468) (xy 42.202305 -234.378761) (xy 42.184066 -234.421426) (xy 42.180247 -234.431366)
			(xy 42.180247 -234.452634) (xy 42.184066 -234.462574) (xy 42.202308 -234.505237) (xy 42.230854 -234.593529)
			(xy 42.250047 -234.684314) (xy 42.259681 -234.776604) (xy 42.260266 -234.823) (xy 42.259815 -234.864253)
			(xy 42.252158 -234.946403) (xy 42.236928 -235.027491) (xy 42.214255 -235.10682) (xy 42.184336 -235.18371)
			(xy 42.147426 -235.257499) (xy 42.103843 -235.327554) (xy 42.053961 -235.393274) (xy 41.998208 -235.454092)
			(xy 41.937065 -235.509488) (xy 41.871055 -235.558984) (xy 41.800746 -235.602156) (xy 41.76395 -235.620814)
			(xy 41.755648 -235.625387) (xy 41.742895 -235.639387) (xy 41.736098 -235.657063) (xy 41.735756 -235.666534)
			(xy 41.735756 -235.757466) (xy 41.736127 -235.766935) (xy 41.742912 -235.784611) (xy 41.755646 -235.798623)
			(xy 41.76395 -235.803186) (xy 41.800761 -235.821818) (xy 41.871083 -235.864978) (xy 41.937104 -235.914467)
			(xy 41.998257 -235.969859) (xy 42.054015 -236.030677) (xy 42.1039 -236.096399) (xy 42.147483 -236.16646)
			(xy 42.184388 -236.240257) (xy 42.214299 -236.317155) (xy 42.236957 -236.396493) (xy 42.252169 -236.477589)
			(xy 42.259803 -236.559745) (xy 42.260266 -236.601) (xy 42.259687 -236.647396) (xy 42.250041 -236.739684)
			(xy 42.230844 -236.830468) (xy 42.202305 -236.918761) (xy 42.184066 -236.961426) (xy 42.180247 -236.971366)
			(xy 42.180247 -236.992634) (xy 42.184066 -237.002574) (xy 42.202308 -237.045237) (xy 42.230854 -237.133529)
			(xy 42.250047 -237.224314) (xy 42.259681 -237.316604) (xy 42.260266 -237.363) (xy 42.259762 -237.405348)
			(xy 42.251711 -237.489662) (xy 42.235682 -237.572828) (xy 42.211821 -237.654095) (xy 42.180342 -237.732725)
			(xy 42.141531 -237.808006) (xy 42.095741 -237.879258) (xy 42.043385 -237.945834) (xy 41.984937 -238.007132)
			(xy 41.920927 -238.062597) (xy 41.851935 -238.111726) (xy 41.778585 -238.154075) (xy 41.701542 -238.189259)
			(xy 41.621503 -238.216961) (xy 41.539194 -238.236929) (xy 41.455359 -238.248982) (xy 41.370758 -238.253013)
			(xy 41.286157 -238.248982) (xy 41.202322 -238.236929) (xy 41.120013 -238.216961) (xy 41.039974 -238.189259)
			(xy 40.962931 -238.154075) (xy 40.889581 -238.111726) (xy 40.820589 -238.062597) (xy 40.756579 -238.007132)
			(xy 40.698131 -237.945834) (xy 40.645775 -237.879258) (xy 40.599985 -237.808006) (xy 40.561174 -237.732725)
			(xy 40.529695 -237.654095) (xy 40.505834 -237.572828) (xy 40.489805 -237.489662) (xy 40.481754 -237.405348)
			(xy 40.48125 -237.363) (xy 30.35046 -237.363) (xy 30.35046 -239.5474) (xy 41.82745 -239.5474) (xy 41.828028 -239.501004)
			(xy 41.837674 -239.408716) (xy 41.856871 -239.317932) (xy 41.885411 -239.229638) (xy 41.90365 -239.186974)
			(xy 41.907468 -239.177034) (xy 41.907468 -239.155766) (xy 41.90365 -239.145826) (xy 41.885403 -239.103165)
			(xy 41.85686 -239.014872) (xy 41.837668 -238.924087) (xy 41.828035 -238.831796) (xy 41.82745 -238.7854)
			(xy 41.827954 -238.743052) (xy 41.836005 -238.658738) (xy 41.852034 -238.575572) (xy 41.875895 -238.494305)
			(xy 41.907374 -238.415675) (xy 41.946185 -238.340394) (xy 41.991975 -238.269142) (xy 42.044331 -238.202566)
			(xy 42.102779 -238.141268) (xy 42.166789 -238.085803) (xy 42.235781 -238.036674) (xy 42.309131 -237.994325)
			(xy 42.386174 -237.959141) (xy 42.466213 -237.931439) (xy 42.548522 -237.911471) (xy 42.632357 -237.899418)
			(xy 42.716958 -237.895388) (xy 42.801559 -237.899418) (xy 42.885394 -237.911471) (xy 42.967703 -237.931439)
			(xy 43.047742 -237.959141) (xy 43.124785 -237.994325) (xy 43.198135 -238.036674) (xy 43.267127 -238.085803)
			(xy 43.331137 -238.141268) (xy 43.389585 -238.202566) (xy 43.441941 -238.269142) (xy 43.487731 -238.340394)
			(xy 43.526542 -238.415675) (xy 43.558021 -238.494305) (xy 43.581882 -238.575572) (xy 43.597911 -238.658738)
			(xy 43.605962 -238.743052) (xy 43.606466 -238.7854) (xy 43.605887 -238.831796) (xy 43.596241 -238.924084)
			(xy 43.577044 -239.014868) (xy 43.548505 -239.103161) (xy 43.530266 -239.145826) (xy 43.526447 -239.155766)
			(xy 43.526447 -239.177034) (xy 43.530266 -239.186974) (xy 43.548508 -239.229637) (xy 43.577054 -239.317929)
			(xy 43.596247 -239.408714) (xy 43.605881 -239.501004) (xy 43.606466 -239.5474) (xy 45.63745 -239.5474)
			(xy 45.638028 -239.501004) (xy 45.647674 -239.408716) (xy 45.666871 -239.317932) (xy 45.695411 -239.229638)
			(xy 45.71365 -239.186974) (xy 45.717468 -239.177034) (xy 45.717468 -239.155766) (xy 45.71365 -239.145826)
			(xy 45.695403 -239.103165) (xy 45.66686 -239.014872) (xy 45.647668 -238.924087) (xy 45.638035 -238.831796)
			(xy 45.63745 -238.7854) (xy 45.637952 -238.743549) (xy 45.645824 -238.660218) (xy 45.661487 -238.577995)
			(xy 45.684805 -238.497607) (xy 45.71557 -238.419764) (xy 45.753511 -238.345155) (xy 45.798292 -238.27444)
			(xy 45.849517 -238.208243) (xy 45.906734 -238.147151) (xy 45.969435 -238.091703) (xy 46.037068 -238.04239)
			(xy 46.072806 -238.020606) (xy 46.082204 -238.015018) (xy 46.094396 -237.998) (xy 46.114462 -237.90402)
			(xy 46.110398 -237.883446) (xy 46.104048 -237.87481) (xy 46.078396 -237.837288) (xy 46.03398 -237.75798)
			(xy 45.997883 -237.674557) (xy 45.97048 -237.587887) (xy 45.952059 -237.498876) (xy 45.94281 -237.408449)
			(xy 45.94225 -237.363) (xy 45.942828 -237.316604) (xy 45.952474 -237.224316) (xy 45.971671 -237.133532)
			(xy 46.000211 -237.045238) (xy 46.01845 -237.002574) (xy 46.022268 -236.992634) (xy 46.022268 -236.971366)
			(xy 46.01845 -236.961426) (xy 46.000203 -236.918765) (xy 45.97166 -236.830472) (xy 45.952468 -236.739687)
			(xy 45.942835 -236.647396) (xy 45.94225 -236.601) (xy 45.942692 -236.559747) (xy 45.950349 -236.477597)
			(xy 45.96558 -236.396508) (xy 45.988253 -236.317178) (xy 46.018173 -236.240288) (xy 46.055084 -236.166498)
			(xy 46.098668 -236.096443) (xy 46.148551 -236.030724) (xy 46.204304 -235.969906) (xy 46.265449 -235.914511)
			(xy 46.33146 -235.865015) (xy 46.40177 -235.821843) (xy 46.438566 -235.803186) (xy 46.446871 -235.798618)
			(xy 46.459622 -235.784615) (xy 46.466418 -235.766937) (xy 46.46676 -235.757466) (xy 46.46676 -235.666534)
			(xy 46.466381 -235.657066) (xy 46.459598 -235.639391) (xy 46.446868 -235.625378) (xy 46.438566 -235.620814)
			(xy 46.401759 -235.602175) (xy 46.331437 -235.559016) (xy 46.265415 -235.509528) (xy 46.204262 -235.454137)
			(xy 46.148503 -235.393319) (xy 46.098617 -235.327598) (xy 46.055034 -235.257538) (xy 46.018129 -235.183742)
			(xy 45.988218 -235.106844) (xy 45.965559 -235.027507) (xy 45.950347 -234.946411) (xy 45.942713 -234.864255)
			(xy 45.94225 -234.823) (xy 45.942828 -234.776604) (xy 45.952474 -234.684316) (xy 45.971671 -234.593532)
			(xy 46.000211 -234.505238) (xy 46.01845 -234.462574) (xy 46.022268 -234.452634) (xy 46.022268 -234.431366)
			(xy 46.01845 -234.421426) (xy 46.000203 -234.378765) (xy 45.97166 -234.290472) (xy 45.952468 -234.199687)
			(xy 45.942835 -234.107396) (xy 45.94225 -234.061) (xy 45.942754 -234.018652) (xy 45.950805 -233.934338)
			(xy 45.966834 -233.851172) (xy 45.990695 -233.769905) (xy 46.022174 -233.691275) (xy 46.060985 -233.615994)
			(xy 46.106775 -233.544742) (xy 46.159131 -233.478166) (xy 46.217579 -233.416868) (xy 46.281589 -233.361403)
			(xy 46.350581 -233.312274) (xy 46.423931 -233.269925) (xy 46.500974 -233.234741) (xy 46.581013 -233.207039)
			(xy 46.663322 -233.187071) (xy 46.747157 -233.175018) (xy 46.831758 -233.170988) (xy 46.916359 -233.175018)
			(xy 47.000194 -233.187071) (xy 47.082503 -233.207039) (xy 47.162542 -233.234741) (xy 47.239585 -233.269925)
			(xy 47.312935 -233.312274) (xy 47.381927 -233.361403) (xy 47.445937 -233.416868) (xy 47.504385 -233.478166)
			(xy 47.556741 -233.544742) (xy 47.602531 -233.615994) (xy 47.641342 -233.691275) (xy 47.672821 -233.769905)
			(xy 47.696682 -233.851172) (xy 47.712711 -233.934338) (xy 47.720762 -234.018652) (xy 47.721266 -234.061)
			(xy 47.720687 -234.107396) (xy 47.711041 -234.199684) (xy 47.691844 -234.290468) (xy 47.663305 -234.378761)
			(xy 47.645066 -234.421426) (xy 47.641247 -234.431366) (xy 47.641247 -234.452634) (xy 47.645066 -234.462574)
			(xy 47.663308 -234.505237) (xy 47.691854 -234.593529) (xy 47.711047 -234.684314) (xy 47.720681 -234.776604)
			(xy 47.721266 -234.823) (xy 47.720815 -234.864253) (xy 47.713158 -234.946403) (xy 47.697928 -235.027491)
			(xy 47.675255 -235.10682) (xy 47.645336 -235.18371) (xy 47.608426 -235.257499) (xy 47.564843 -235.327554)
			(xy 47.514961 -235.393274) (xy 47.459208 -235.454092) (xy 47.398065 -235.509488) (xy 47.332055 -235.558984)
			(xy 47.261746 -235.602156) (xy 47.22495 -235.620814) (xy 47.216648 -235.625387) (xy 47.203895 -235.639387)
			(xy 47.197098 -235.657063) (xy 47.196756 -235.666534) (xy 47.196756 -235.757466) (xy 47.197127 -235.766935)
			(xy 47.203912 -235.784611) (xy 47.216646 -235.798623) (xy 47.22495 -235.803186) (xy 47.261761 -235.821818)
			(xy 47.332083 -235.864978) (xy 47.398104 -235.914467) (xy 47.459257 -235.969859) (xy 47.515015 -236.030677)
			(xy 47.5649 -236.096399) (xy 47.608483 -236.16646) (xy 47.645388 -236.240257) (xy 47.675299 -236.317155)
			(xy 47.697957 -236.396493) (xy 47.713169 -236.477589) (xy 47.720803 -236.559745) (xy 47.721266 -236.601)
			(xy 47.720687 -236.647396) (xy 47.711041 -236.739684) (xy 47.691844 -236.830468) (xy 47.663305 -236.918761)
			(xy 47.645066 -236.961426) (xy 47.641247 -236.971366) (xy 47.641247 -236.992634) (xy 47.645066 -237.002574)
			(xy 47.663308 -237.045237) (xy 47.691854 -237.133529) (xy 47.711047 -237.224314) (xy 47.720681 -237.316604)
			(xy 47.721266 -237.363) (xy 47.720805 -237.404852) (xy 47.712933 -237.488185) (xy 47.697267 -237.570411)
			(xy 47.673947 -237.650801) (xy 47.643179 -237.728645) (xy 47.605234 -237.803255) (xy 47.560448 -237.87397)
			(xy 47.509218 -237.940166) (xy 47.451996 -238.001257) (xy 47.389289 -238.056702) (xy 47.321651 -238.106012)
			(xy 47.28591 -238.127794) (xy 47.276512 -238.133382) (xy 47.26432 -238.1504) (xy 47.244254 -238.24438)
			(xy 47.248318 -238.264954) (xy 47.254668 -238.27359) (xy 47.280322 -238.311111) (xy 47.324738 -238.390419)
			(xy 47.360834 -238.473843) (xy 47.388236 -238.560512) (xy 47.406657 -238.649524) (xy 47.415906 -238.739951)
			(xy 47.416466 -238.7854) (xy 47.415887 -238.831796) (xy 47.406241 -238.924084) (xy 47.387044 -239.014868)
			(xy 47.358505 -239.103161) (xy 47.340266 -239.145826) (xy 47.336447 -239.155766) (xy 47.336447 -239.177034)
			(xy 47.340266 -239.186974) (xy 47.358508 -239.229637) (xy 47.387054 -239.317929) (xy 47.406247 -239.408714)
			(xy 47.415881 -239.501004) (xy 47.416466 -239.5474) (xy 47.415962 -239.589748) (xy 47.407911 -239.674062)
			(xy 47.391882 -239.757228) (xy 47.368021 -239.838495) (xy 47.336542 -239.917125) (xy 47.297731 -239.992406)
			(xy 47.251941 -240.063658) (xy 47.199585 -240.130234) (xy 47.141137 -240.191532) (xy 47.077127 -240.246997)
			(xy 47.008135 -240.296126) (xy 46.934785 -240.338475) (xy 46.857742 -240.373659) (xy 46.777703 -240.401361)
			(xy 46.695394 -240.421329) (xy 46.611559 -240.433382) (xy 46.526958 -240.437413) (xy 46.442357 -240.433382)
			(xy 46.358522 -240.421329) (xy 46.276213 -240.401361) (xy 46.196174 -240.373659) (xy 46.119131 -240.338475)
			(xy 46.045781 -240.296126) (xy 45.976789 -240.246997) (xy 45.912779 -240.191532) (xy 45.854331 -240.130234)
			(xy 45.801975 -240.063658) (xy 45.756185 -239.992406) (xy 45.717374 -239.917125) (xy 45.685895 -239.838495)
			(xy 45.662034 -239.757228) (xy 45.646005 -239.674062) (xy 45.637954 -239.589748) (xy 45.63745 -239.5474)
			(xy 43.606466 -239.5474) (xy 43.605962 -239.589748) (xy 43.597911 -239.674062) (xy 43.581882 -239.757228)
			(xy 43.558021 -239.838495) (xy 43.526542 -239.917125) (xy 43.487731 -239.992406) (xy 43.441941 -240.063658)
			(xy 43.389585 -240.130234) (xy 43.331137 -240.191532) (xy 43.267127 -240.246997) (xy 43.198135 -240.296126)
			(xy 43.124785 -240.338475) (xy 43.047742 -240.373659) (xy 42.967703 -240.401361) (xy 42.885394 -240.421329)
			(xy 42.801559 -240.433382) (xy 42.716958 -240.437413) (xy 42.632357 -240.433382) (xy 42.548522 -240.421329)
			(xy 42.466213 -240.401361) (xy 42.386174 -240.373659) (xy 42.309131 -240.338475) (xy 42.235781 -240.296126)
			(xy 42.166789 -240.246997) (xy 42.102779 -240.191532) (xy 42.044331 -240.130234) (xy 41.991975 -240.063658)
			(xy 41.946185 -239.992406) (xy 41.907374 -239.917125) (xy 41.875895 -239.838495) (xy 41.852034 -239.757228)
			(xy 41.836005 -239.674062) (xy 41.827954 -239.589748) (xy 41.82745 -239.5474) (xy 30.35046 -239.5474)
			(xy 30.35046 -241.909854) (xy 30.349966 -242.004118) (xy 30.342072 -242.192482) (xy 30.326296 -242.380349)
			(xy 30.302667 -242.567391) (xy 30.271226 -242.75328) (xy 30.232029 -242.937689) (xy 30.185144 -243.120294)
			(xy 30.130653 -243.300776) (xy 30.068652 -243.478818) (xy 29.99925 -243.654108) (xy 29.922569 -243.826337)
			(xy 29.838742 -243.995205) (xy 29.747918 -244.160414) (xy 29.655078 -244.31371) (xy 34.233104 -244.31371)
			(xy 34.233523 -244.275421) (xy 34.240149 -244.199131) (xy 34.253301 -244.123691) (xy 34.272882 -244.049659)
			(xy 34.285428 -244.013482) (xy 34.288064 -244.005043) (xy 34.288067 -243.987376) (xy 34.285428 -243.978938)
			(xy 34.272875 -243.942762) (xy 34.253277 -243.868733) (xy 34.240125 -243.793292) (xy 34.233515 -243.716999)
			(xy 34.233104 -243.67871) (xy 34.233562 -243.637607) (xy 34.241146 -243.555751) (xy 34.256251 -243.474943)
			(xy 34.278747 -243.395875) (xy 34.308443 -243.319219) (xy 34.345086 -243.245631) (xy 34.388362 -243.175737)
			(xy 34.437902 -243.110135) (xy 34.493285 -243.049383) (xy 34.554036 -242.994001) (xy 34.619639 -242.944461)
			(xy 34.689532 -242.901185) (xy 34.763121 -242.864542) (xy 34.839777 -242.834847) (xy 34.918845 -242.81235)
			(xy 34.999653 -242.797246) (xy 35.081509 -242.789662) (xy 35.122612 -242.789202) (xy 35.161544 -242.789625)
			(xy 35.239108 -242.796464) (xy 35.315776 -242.810064) (xy 35.390961 -242.830318) (xy 35.427666 -242.843304)
			(xy 35.436215 -242.846068) (xy 35.454169 -242.846068) (xy 35.462718 -242.843304) (xy 35.499432 -242.830345)
			(xy 35.574616 -242.810101) (xy 35.651281 -242.796499) (xy 35.728841 -242.789645) (xy 35.767772 -242.789202)
			(xy 35.806704 -242.789637) (xy 35.884268 -242.796473) (xy 35.960936 -242.810069) (xy 36.03612 -242.83032)
			(xy 36.072826 -242.843304) (xy 36.081375 -242.846068) (xy 36.099329 -242.846068) (xy 36.107878 -242.843304)
			(xy 36.144586 -242.830328) (xy 36.219772 -242.810088) (xy 36.296439 -242.796491) (xy 36.374001 -242.789642)
			(xy 36.412932 -242.789202) (xy 36.454035 -242.789636) (xy 36.535891 -242.797224) (xy 36.616697 -242.812332)
			(xy 36.695765 -242.834832) (xy 36.77242 -242.86453) (xy 36.846007 -242.901175) (xy 36.915899 -242.944453)
			(xy 36.9815 -242.993995) (xy 37.04225 -243.049379) (xy 37.097631 -243.110132) (xy 37.147171 -243.175735)
			(xy 37.190445 -243.24563) (xy 37.227087 -243.319219) (xy 37.256782 -243.395875) (xy 37.279278 -243.474943)
			(xy 37.294382 -243.555751) (xy 37.301966 -243.637607) (xy 37.30244 -243.67871) (xy 37.301995 -243.716998)
			(xy 37.295376 -243.793288) (xy 37.282232 -243.868727) (xy 37.262658 -243.94276) (xy 37.250116 -243.978938)
			(xy 37.247469 -243.987375) (xy 37.247472 -244.005044) (xy 37.250116 -244.013482) (xy 37.262677 -244.049655)
			(xy 37.282272 -244.123685) (xy 37.295422 -244.199127) (xy 37.30203 -244.27542) (xy 37.30244 -244.31371)
			(xy 37.301943 -244.354812) (xy 37.294357 -244.436664) (xy 37.279252 -244.517468) (xy 37.256756 -244.596533)
			(xy 37.227061 -244.673186) (xy 37.19042 -244.746771) (xy 37.147145 -244.816662) (xy 37.097607 -244.882263)
			(xy 37.042228 -244.943012) (xy 36.98148 -244.998393) (xy 36.915881 -245.047933) (xy 36.845991 -245.091209)
			(xy 36.772406 -245.127852) (xy 36.695754 -245.157549) (xy 36.61669 -245.180047) (xy 36.535886 -245.195154)
			(xy 36.454034 -245.202742) (xy 36.412932 -245.203218) (xy 36.373362 -245.202812) (xy 36.294534 -245.195801)
			(xy 36.21664 -245.181815) (xy 36.140297 -245.160963) (xy 36.103052 -245.147592) (xy 36.094385 -245.144752)
			(xy 36.076159 -245.144752) (xy 36.067492 -245.147592) (xy 36.030252 -245.160974) (xy 35.953906 -245.181817)
			(xy 35.876011 -245.195795) (xy 35.797182 -245.202799) (xy 35.757612 -245.203218) (xy 35.719323 -245.202797)
			(xy 35.643033 -245.196172) (xy 35.567593 -245.18302) (xy 35.493561 -245.16344) (xy 35.457384 -245.150894)
			(xy 35.448946 -245.148252) (xy 35.431278 -245.148252) (xy 35.42284 -245.150894) (xy 35.386664 -245.163448)
			(xy 35.312636 -245.183045) (xy 35.237195 -245.196197) (xy 35.160901 -245.202807) (xy 35.122612 -245.203218)
			(xy 35.081509 -245.202736) (xy 34.999655 -245.195153) (xy 34.918849 -245.180048) (xy 34.839781 -245.157553)
			(xy 34.763127 -245.127858) (xy 34.689539 -245.091217) (xy 34.619646 -245.047942) (xy 34.554044 -244.998403)
			(xy 34.493293 -244.943023) (xy 34.437911 -244.882273) (xy 34.38837 -244.816672) (xy 34.345094 -244.74678)
			(xy 34.308451 -244.673193) (xy 34.278754 -244.59654) (xy 34.256257 -244.517473) (xy 34.24115 -244.436667)
			(xy 34.233565 -244.354813) (xy 34.233104 -244.31371) (xy 29.655078 -244.31371) (xy 29.650255 -244.321674)
			(xy 29.545925 -244.478704) (xy 29.43511 -244.631227) (xy 29.318006 -244.778976) (xy 29.194818 -244.921691)
			(xy 29.065761 -245.059122) (xy 28.931062 -245.191029) (xy 28.790958 -245.317179) (xy 28.645694 -245.437352)
			(xy 28.495526 -245.551336) (xy 28.340715 -245.658932) (xy 28.181535 -245.759951) (xy 28.018265 -245.854215)
			(xy 27.85119 -245.94156) (xy 27.680604 -246.021831) (xy 27.506807 -246.094889) (xy 27.330102 -246.160605)
			(xy 27.150801 -246.218863) (xy 26.969217 -246.269563) (xy 26.785669 -246.312613) (xy 26.60048 -246.34794)
			(xy 26.413974 -246.375481) (xy 26.226478 -246.395187) (xy 26.038321 -246.407025) (xy 25.849834 -246.410974)
			(xy 25.661347 -246.407025) (xy 25.47319 -246.395187) (xy 25.285694 -246.375481) (xy 25.099188 -246.34794)
			(xy 24.913999 -246.312613) (xy 24.730451 -246.269563) (xy 24.548867 -246.218863) (xy 24.369566 -246.160605)
			(xy 24.192861 -246.094889) (xy 24.019064 -246.021831) (xy 23.848478 -245.94156) (xy 23.681403 -245.854215)
			(xy 23.518133 -245.759951) (xy 23.358953 -245.658932) (xy 23.204142 -245.551336) (xy 23.053974 -245.437352)
			(xy 22.90871 -245.317179) (xy 22.768606 -245.191029) (xy 22.633907 -245.059122) (xy 22.50485 -244.921691)
			(xy 22.381662 -244.778976) (xy 22.264558 -244.631227) (xy 22.153743 -244.478704) (xy 22.049413 -244.321674)
			(xy 21.95175 -244.160414) (xy 21.860926 -243.995205) (xy 21.777099 -243.826337) (xy 21.700418 -243.654108)
			(xy 21.631016 -243.478818) (xy 21.569015 -243.300776) (xy 21.514524 -243.120294) (xy 21.467639 -242.937689)
			(xy 21.428442 -242.75328) (xy 21.397001 -242.567391) (xy 21.373372 -242.380349) (xy 21.357596 -242.192482)
			(xy 21.349702 -242.004118) (xy 21.349208 -241.909854) (xy 1.651254 -241.909854) (xy 1.651254 -243.513864)
			(xy 2.81559 -243.513864) (xy 2.816026 -243.475576) (xy 2.822647 -243.399286) (xy 2.835794 -243.323846)
			(xy 2.85537 -243.249814) (xy 2.867914 -243.213636) (xy 2.870573 -243.205202) (xy 2.870561 -243.18753)
			(xy 2.867914 -243.179092) (xy 2.855347 -243.142921) (xy 2.835754 -243.06889) (xy 2.822605 -242.993448)
			(xy 2.815999 -242.917154) (xy 2.81559 -242.878864) (xy 2.816056 -242.837761) (xy 2.823641 -242.755906)
			(xy 2.838746 -242.675099) (xy 2.861242 -242.596031) (xy 2.890938 -242.519376) (xy 2.92758 -242.445788)
			(xy 2.970856 -242.375895) (xy 3.020396 -242.310293) (xy 3.075777 -242.249542) (xy 3.136528 -242.19416)
			(xy 3.20213 -242.144619) (xy 3.272023 -242.101343) (xy 3.345611 -242.0647) (xy 3.422265 -242.035004)
			(xy 3.501333 -242.012507) (xy 3.58214 -241.997401) (xy 3.663995 -241.989816) (xy 3.705098 -241.989356)
			(xy 3.74403 -241.989786) (xy 3.821594 -241.996624) (xy 3.898262 -242.010221) (xy 3.973446 -242.030474)
			(xy 4.010152 -242.043458) (xy 4.018701 -242.046222) (xy 4.036655 -242.046222) (xy 4.045204 -242.043458)
			(xy 4.081909 -242.030473) (xy 4.157097 -242.010236) (xy 4.233764 -241.996642) (xy 4.311326 -241.989795)
			(xy 4.350258 -241.989356) (xy 4.38919 -241.989798) (xy 4.466753 -241.996632) (xy 4.543421 -242.010226)
			(xy 4.618606 -242.030475) (xy 4.655312 -242.043458) (xy 4.663861 -242.046222) (xy 4.681815 -242.046222)
			(xy 4.690364 -242.043458) (xy 4.727073 -242.030484) (xy 4.802259 -242.010244) (xy 4.878926 -241.996647)
			(xy 4.956487 -241.989797) (xy 4.995418 -241.989356) (xy 5.036521 -241.989814) (xy 5.118377 -241.997399)
			(xy 5.199184 -242.012504) (xy 5.278252 -242.035001) (xy 5.354907 -242.064697) (xy 5.428496 -242.10134)
			(xy 5.498389 -242.144616) (xy 5.563991 -242.194157) (xy 5.624743 -242.249539) (xy 5.680125 -242.31029)
			(xy 5.729665 -242.375893) (xy 5.772941 -242.445786) (xy 5.809583 -242.519374) (xy 5.83928 -242.59603)
			(xy 5.861776 -242.675098) (xy 5.876881 -242.755905) (xy 5.884466 -242.837761) (xy 5.884926 -242.878864)
			(xy 5.884497 -242.917152) (xy 5.877874 -242.993443) (xy 5.864725 -243.068882) (xy 5.845147 -243.142914)
			(xy 5.832602 -243.179092) (xy 5.829978 -243.187534) (xy 5.829966 -243.205198) (xy 5.832602 -243.213636)
			(xy 5.845177 -243.249804) (xy 5.864769 -243.323836) (xy 5.877915 -243.399279) (xy 5.884518 -243.475574)
			(xy 5.884926 -243.513864) (xy 5.884414 -243.554966) (xy 5.876832 -243.63682) (xy 5.86173 -243.717625)
			(xy 5.839237 -243.796691) (xy 5.809544 -243.873346) (xy 5.772905 -243.946933) (xy 5.729632 -244.016826)
			(xy 5.680096 -244.082427) (xy 5.624717 -244.143179) (xy 5.563969 -244.198561) (xy 5.49837 -244.248102)
			(xy 5.42848 -244.291379) (xy 5.354895 -244.328022) (xy 5.278243 -244.35772) (xy 5.199177 -244.380218)
			(xy 5.118373 -244.395324) (xy 5.03652 -244.402911) (xy 4.995418 -244.403372) (xy 4.955849 -244.402936)
			(xy 4.877021 -244.395934) (xy 4.799127 -244.381956) (xy 4.722783 -244.361113) (xy 4.685538 -244.347746)
			(xy 4.676871 -244.344906) (xy 4.658645 -244.344906) (xy 4.649978 -244.347746) (xy 4.612728 -244.361101)
			(xy 4.536386 -244.381951) (xy 4.458494 -244.395938) (xy 4.379667 -244.402949) (xy 4.340098 -244.403372)
			(xy 4.30181 -244.402928) (xy 4.22552 -244.39631) (xy 4.15008 -244.383165) (xy 4.076048 -244.363591)
			(xy 4.03987 -244.351048) (xy 4.031432 -244.348406) (xy 4.013764 -244.348406) (xy 4.005326 -244.351048)
			(xy 3.969153 -244.363608) (xy 3.895123 -244.383203) (xy 3.819681 -244.396353) (xy 3.743388 -244.402961)
			(xy 3.705098 -244.403372) (xy 3.663996 -244.402895) (xy 3.582141 -244.39531) (xy 3.501336 -244.380205)
			(xy 3.42227 -244.357709) (xy 3.345616 -244.328013) (xy 3.272029 -244.291371) (xy 3.202137 -244.248096)
			(xy 3.136536 -244.198556) (xy 3.075786 -244.143175) (xy 3.020405 -244.082425) (xy 2.970866 -244.016824)
			(xy 2.92759 -243.946932) (xy 2.890948 -243.873346) (xy 2.861252 -243.796692) (xy 2.838755 -243.717626)
			(xy 2.82365 -243.636821) (xy 2.816065 -243.554966) (xy 2.81559 -243.513864) (xy 1.651254 -243.513864)
			(xy 1.651254 -246.500904) (xy 1.652778 -246.55145) (xy 1.651254 -246.601996) (xy 1.651254 -247.904)
			(xy 2.867406 -247.904) (xy 2.867902 -247.862398) (xy 2.875685 -247.779559) (xy 2.89117 -247.697808)
			(xy 2.914221 -247.617861) (xy 2.944637 -247.540415) (xy 2.982151 -247.466148) (xy 3.026437 -247.395709)
			(xy 3.077106 -247.329712) (xy 3.133717 -247.268735) (xy 3.195774 -247.213311) (xy 3.262736 -247.163924)
			(xy 3.334017 -247.121006) (xy 3.408994 -247.084931) (xy 3.487012 -247.056015) (xy 3.567389 -247.034511)
			(xy 3.649423 -247.020606) (xy 3.690874 -247.017032) (xy 3.701845 -247.015644) (xy 3.721199 -247.005004)
			(xy 3.728212 -246.996458) (xy 3.753289 -246.96315) (xy 3.808708 -246.900854) (xy 3.869715 -246.844019)
			(xy 3.935775 -246.793145) (xy 4.006307 -246.748679) (xy 4.080692 -246.71101) (xy 4.158277 -246.68047)
			(xy 4.23838 -246.657328) (xy 4.320298 -246.641786) (xy 4.40331 -246.63398) (xy 4.445 -246.633492)
			(xy 4.486102 -246.633967) (xy 4.567957 -246.641552) (xy 4.648762 -246.656657) (xy 4.727829 -246.679153)
			(xy 4.804483 -246.708849) (xy 4.87807 -246.745491) (xy 4.947962 -246.788766) (xy 5.013563 -246.838306)
			(xy 5.074313 -246.893687) (xy 5.129694 -246.954437) (xy 5.179234 -247.020038) (xy 5.222509 -247.08993)
			(xy 5.259151 -247.163517) (xy 5.288847 -247.240171) (xy 5.311343 -247.319238) (xy 5.326448 -247.400043)
			(xy 5.334033 -247.481898) (xy 5.334508 -247.523) (xy 5.334018 -247.564602) (xy 5.326234 -247.647442)
			(xy 5.310749 -247.729193) (xy 5.287698 -247.80914) (xy 5.257282 -247.886586) (xy 5.219767 -247.960854)
			(xy 5.175482 -248.031293) (xy 5.124812 -248.09729) (xy 5.0682 -248.158266) (xy 5.006143 -248.21369)
			(xy 4.93918 -248.263077) (xy 4.90277 -248.285) (xy 5.587492 -248.285) (xy 5.587964 -248.243036) (xy 5.59587 -248.15948)
			(xy 5.611611 -248.07704) (xy 5.635047 -247.99645) (xy 5.665971 -247.918426) (xy 5.704106 -247.843661)
			(xy 5.749114 -247.772821) (xy 5.800595 -247.706535) (xy 5.85809 -247.645394) (xy 5.92109 -247.58994)
			(xy 5.954776 -247.56491) (xy 5.962733 -247.558558) (xy 5.973227 -247.541135) (xy 5.975096 -247.531128)
			(xy 5.981761 -247.488766) (xy 6.002156 -247.405468) (xy 6.030475 -247.324519) (xy 6.066454 -247.246673)
			(xy 6.10976 -247.172651) (xy 6.15999 -247.103141) (xy 6.187948 -247.070626) (xy 6.194587 -247.062198)
			(xy 6.200871 -247.041708) (xy 6.20014 -247.031002) (xy 6.197023 -247.003869) (xy 6.193721 -246.949347)
			(xy 6.193536 -246.922036) (xy 6.19404 -246.879688) (xy 6.202091 -246.795374) (xy 6.21812 -246.712208)
			(xy 6.241981 -246.630941) (xy 6.27346 -246.552311) (xy 6.312271 -246.47703) (xy 6.358061 -246.405778)
			(xy 6.410417 -246.339202) (xy 6.468865 -246.277904) (xy 6.532875 -246.222439) (xy 6.601867 -246.17331)
			(xy 6.675217 -246.130961) (xy 6.75226 -246.095777) (xy 6.832299 -246.068075) (xy 6.914608 -246.048107)
			(xy 6.998443 -246.036054) (xy 7.083044 -246.032024) (xy 7.167645 -246.036054) (xy 7.25148 -246.048107)
			(xy 7.333789 -246.068075) (xy 7.393282 -246.088666) (xy 8.065891 -246.088666) (xy 8.068525 -246.004857)
			(xy 8.079035 -245.921668) (xy 8.097327 -245.839838) (xy 8.123238 -245.760091) (xy 8.156539 -245.683138)
			(xy 8.196935 -245.609659) (xy 8.244066 -245.540308) (xy 8.297514 -245.475701) (xy 8.356805 -245.41641)
			(xy 8.421413 -245.362962) (xy 8.490764 -245.315831) (xy 8.564243 -245.275437) (xy 8.641197 -245.242136)
			(xy 8.720943 -245.216225) (xy 8.802774 -245.197934) (xy 8.885963 -245.187425) (xy 8.969772 -245.184791)
			(xy 9.053457 -245.190057) (xy 9.136275 -245.203174) (xy 9.217491 -245.224027) (xy 9.296384 -245.25243)
			(xy 9.372254 -245.288132) (xy 9.444427 -245.330816) (xy 9.512263 -245.380102) (xy 9.57516 -245.435553)
			(xy 9.632559 -245.496677) (xy 9.683952 -245.562932) (xy 9.728881 -245.63373) (xy 9.766948 -245.708441)
			(xy 9.797815 -245.786403) (xy 9.821208 -245.866924) (xy 9.83692 -245.949289) (xy 9.844811 -246.032767)
			(xy 9.845294 -246.074692) (xy 9.84504 -246.098822) (xy 9.844786 -246.10949) (xy 9.85266 -246.129048)
			(xy 9.921494 -246.196104) (xy 9.941052 -246.20347) (xy 9.951974 -246.202962) (xy 9.999218 -246.201692)
			(xy 10.045614 -246.202269) (xy 10.137902 -246.211915) (xy 10.228686 -246.231113) (xy 10.316979 -246.259653)
			(xy 10.359644 -246.277892) (xy 10.369584 -246.281712) (xy 10.390852 -246.281712) (xy 10.400792 -246.277892)
			(xy 10.443452 -246.259641) (xy 10.531745 -246.231099) (xy 10.622531 -246.211907) (xy 10.714822 -246.202276)
			(xy 10.761218 -246.201692) (xy 10.802321 -246.202149) (xy 10.884176 -246.209736) (xy 10.964981 -246.224843)
			(xy 11.044048 -246.247341) (xy 11.120702 -246.277038) (xy 11.194289 -246.313681) (xy 11.264181 -246.356958)
			(xy 11.329782 -246.406498) (xy 11.390532 -246.461881) (xy 11.445913 -246.522632) (xy 11.495452 -246.588234)
			(xy 11.538728 -246.658127) (xy 11.575369 -246.731714) (xy 11.605065 -246.808369) (xy 11.627561 -246.887436)
			(xy 11.642666 -246.968242) (xy 11.650251 -247.050097) (xy 11.650726 -247.0912) (xy 11.650235 -247.13228)
			(xy 11.642658 -247.214089) (xy 11.62757 -247.29485) (xy 11.605098 -247.373877) (xy 11.575435 -247.450494)
			(xy 11.538832 -247.524049) (xy 11.495603 -247.593916) (xy 11.446114 -247.659498) (xy 11.390789 -247.720237)
			(xy 11.330098 -247.775616) (xy 11.26456 -247.825161) (xy 11.194731 -247.868452) (xy 11.121208 -247.905119)
			(xy 11.044617 -247.93485) (xy 10.96561 -247.957391) (xy 10.884862 -247.97255) (xy 10.803059 -247.980198)
			(xy 10.76198 -247.980708) (xy 10.750804 -247.980708) (xy 10.730992 -247.989598) (xy 10.666222 -248.063512)
			(xy 10.659872 -248.08434) (xy 10.661142 -248.095262) (xy 10.664567 -248.123458) (xy 10.668251 -248.180144)
			(xy 10.668508 -248.208546) (xy 10.668004 -248.250894) (xy 10.659953 -248.335208) (xy 10.643924 -248.418374)
			(xy 10.620063 -248.499641) (xy 10.588584 -248.578271) (xy 10.549773 -248.653552) (xy 10.503983 -248.724804)
			(xy 10.451627 -248.79138) (xy 10.409703 -248.835348) (xy 25.145996 -248.835348) (xy 25.145996 -248.750652)
			(xy 25.154047 -248.666338) (xy 25.170076 -248.583172) (xy 25.193937 -248.501905) (xy 25.225416 -248.423275)
			(xy 25.264227 -248.347994) (xy 25.310017 -248.276742) (xy 25.362373 -248.210166) (xy 25.420821 -248.148868)
			(xy 25.484831 -248.093403) (xy 25.553823 -248.044274) (xy 25.627173 -248.001925) (xy 25.704216 -247.966741)
			(xy 25.784255 -247.939039) (xy 25.866564 -247.919071) (xy 25.950399 -247.907018) (xy 26.035 -247.902988)
			(xy 26.119601 -247.907018) (xy 26.203436 -247.919071) (xy 26.285745 -247.939039) (xy 26.365784 -247.966741)
			(xy 26.442827 -248.001925) (xy 26.516177 -248.044274) (xy 26.585169 -248.093403) (xy 26.649179 -248.148868)
			(xy 26.707627 -248.210166) (xy 26.759983 -248.276742) (xy 26.805773 -248.347994) (xy 26.844584 -248.423275)
			(xy 26.876063 -248.501905) (xy 26.899924 -248.583172) (xy 26.912741 -248.649674) (xy 31.905444 -248.649674)
			(xy 31.905444 -248.564978) (xy 31.913495 -248.480664) (xy 31.929524 -248.397498) (xy 31.953385 -248.316231)
			(xy 31.984864 -248.237601) (xy 32.023675 -248.16232) (xy 32.069465 -248.091068) (xy 32.121821 -248.024492)
			(xy 32.180269 -247.963194) (xy 32.244279 -247.907729) (xy 32.313271 -247.8586) (xy 32.386621 -247.816251)
			(xy 32.463664 -247.781067) (xy 32.543703 -247.753365) (xy 32.626012 -247.733397) (xy 32.709847 -247.721344)
			(xy 32.794448 -247.717314) (xy 32.879049 -247.721344) (xy 32.962884 -247.733397) (xy 33.045193 -247.753365)
			(xy 33.125232 -247.781067) (xy 33.202275 -247.816251) (xy 33.275625 -247.8586) (xy 33.344617 -247.907729)
			(xy 33.408627 -247.963194) (xy 33.467075 -248.024492) (xy 33.519431 -248.091068) (xy 33.565221 -248.16232)
			(xy 33.604032 -248.237601) (xy 33.635511 -248.316231) (xy 33.637454 -248.32285) (xy 34.315654 -248.32285)
			(xy 34.319684 -248.238249) (xy 34.331737 -248.154413) (xy 34.351705 -248.072103) (xy 34.379407 -247.992064)
			(xy 34.414592 -247.915021) (xy 34.45694 -247.841671) (xy 34.50607 -247.772678) (xy 34.561535 -247.708668)
			(xy 34.622833 -247.65022) (xy 34.68941 -247.597864) (xy 34.760662 -247.552073) (xy 34.835944 -247.513263)
			(xy 34.914574 -247.481784) (xy 34.995841 -247.457922) (xy 35.079007 -247.441893) (xy 35.163321 -247.433842)
			(xy 35.20567 -247.433338) (xy 35.24418 -247.433764) (xy 35.320911 -247.440421) (xy 35.396779 -247.453687)
			(xy 35.471217 -247.473463) (xy 35.543665 -247.4996) (xy 35.578796 -247.51538) (xy 35.590166 -247.519929)
			(xy 35.614594 -247.518857) (xy 35.625532 -247.513348) (xy 35.666013 -247.490823) (xy 35.750736 -247.453342)
			(xy 35.838895 -247.424871) (xy 35.929537 -247.405717) (xy 36.021678 -247.396088) (xy 36.068 -247.395492)
			(xy 36.110348 -247.395996) (xy 36.194662 -247.404047) (xy 36.277828 -247.420076) (xy 36.359095 -247.443937)
			(xy 36.437725 -247.475416) (xy 36.513006 -247.514227) (xy 36.584258 -247.560017) (xy 36.650834 -247.612373)
			(xy 36.681771 -247.641872) (xy 37.123624 -247.641872) (xy 37.124025 -247.600767) (xy 37.131613 -247.518909)
			(xy 37.146722 -247.4381) (xy 37.169222 -247.35903) (xy 37.198922 -247.282373) (xy 37.235568 -247.208784)
			(xy 37.278848 -247.13889) (xy 37.328392 -247.073287) (xy 37.383778 -247.012536) (xy 37.444533 -246.957154)
			(xy 37.510139 -246.907614) (xy 37.580036 -246.864339) (xy 37.653628 -246.827698) (xy 37.730287 -246.798003)
			(xy 37.809359 -246.775508) (xy 37.890169 -246.760405) (xy 37.972027 -246.752823) (xy 38.013132 -246.752364)
			(xy 38.056373 -246.752858) (xy 38.142447 -246.761235) (xy 38.227303 -246.777927) (xy 38.310137 -246.802776)
			(xy 38.390169 -246.835547) (xy 38.466642 -246.875931) (xy 38.538834 -246.923547) (xy 38.606065 -246.977945)
			(xy 38.643711 -247.015) (xy 39.496492 -247.015) (xy 39.496996 -246.972652) (xy 39.505047 -246.888338)
			(xy 39.521076 -246.805172) (xy 39.544937 -246.723905) (xy 39.576416 -246.645275) (xy 39.615227 -246.569994)
			(xy 39.661017 -246.498742) (xy 39.713373 -246.432166) (xy 39.771821 -246.370868) (xy 39.835831 -246.315403)
			(xy 39.904823 -246.266274) (xy 39.978173 -246.223925) (xy 40.055216 -246.188741) (xy 40.135255 -246.161039)
			(xy 40.217564 -246.141071) (xy 40.301399 -246.129018) (xy 40.386 -246.124988) (xy 40.470601 -246.129018)
			(xy 40.554436 -246.141071) (xy 40.636745 -246.161039) (xy 40.716784 -246.188741) (xy 40.793827 -246.223925)
			(xy 40.867177 -246.266274) (xy 40.936169 -246.315403) (xy 41.000179 -246.370868) (xy 41.058627 -246.432166)
			(xy 41.110983 -246.498742) (xy 41.156773 -246.569994) (xy 41.195584 -246.645275) (xy 41.227063 -246.723905)
			(xy 41.250924 -246.805172) (xy 41.266953 -246.888338) (xy 41.275004 -246.972652) (xy 41.275508 -247.015)
			(xy 41.275167 -247.048919) (xy 41.269951 -247.116557) (xy 41.265094 -247.150128) (xy 41.263062 -247.164606)
			(xy 41.274238 -247.191022) (xy 41.373552 -247.259856) (xy 41.402254 -247.26138) (xy 41.415208 -247.254268)
			(xy 41.455022 -247.232711) (xy 41.538164 -247.196855) (xy 41.624517 -247.169624) (xy 41.713187 -247.151299)
			(xy 41.80326 -247.142071) (xy 41.848532 -247.141492) (xy 41.894927 -247.142099) (xy 41.987215 -247.151737)
			(xy 42.077998 -247.170926) (xy 42.166293 -247.199457) (xy 42.208958 -247.217692) (xy 42.218898 -247.221512)
			(xy 42.240166 -247.221512) (xy 42.250106 -247.217692) (xy 42.292764 -247.199437) (xy 42.381058 -247.170895)
			(xy 42.471844 -247.151705) (xy 42.564136 -247.142075) (xy 42.610532 -247.141492) (xy 42.65288 -247.141997)
			(xy 42.737191 -247.150051) (xy 42.820355 -247.166082) (xy 42.901618 -247.189946) (xy 42.980246 -247.221426)
			(xy 43.055525 -247.260237) (xy 43.126774 -247.306028) (xy 43.193347 -247.358385) (xy 43.254643 -247.416832)
			(xy 43.310105 -247.480841) (xy 43.359232 -247.549833) (xy 43.401579 -247.623181) (xy 43.436762 -247.700223)
			(xy 43.464462 -247.78026) (xy 43.48443 -247.862568) (xy 43.496483 -247.946401) (xy 43.500513 -248.031)
			(xy 43.496483 -248.115599) (xy 43.48443 -248.199432) (xy 43.464462 -248.28174) (xy 43.436762 -248.361777)
			(xy 43.401579 -248.438819) (xy 43.359232 -248.512167) (xy 43.310105 -248.581159) (xy 43.254643 -248.645168)
			(xy 43.193347 -248.703615) (xy 43.126774 -248.755972) (xy 43.055525 -248.801763) (xy 42.980246 -248.840574)
			(xy 42.901618 -248.872054) (xy 42.820355 -248.895918) (xy 42.737191 -248.911949) (xy 42.65288 -248.920003)
			(xy 42.610532 -248.920508) (xy 42.564137 -248.919914) (xy 42.471849 -248.910272) (xy 42.381065 -248.891079)
			(xy 42.292771 -248.862544) (xy 42.250106 -248.844308) (xy 42.240166 -248.840488) (xy 42.218898 -248.840488)
			(xy 42.208958 -248.844308) (xy 42.166291 -248.862542) (xy 42.078001 -248.891089) (xy 41.987217 -248.910285)
			(xy 41.894928 -248.919921) (xy 41.848532 -248.920508) (xy 41.808808 -248.920071) (xy 41.729679 -248.912971)
			(xy 41.651497 -248.898851) (xy 41.613074 -248.888758) (xy 41.602802 -248.886441) (xy 41.581977 -248.889385)
			(xy 41.564095 -248.900458) (xy 41.557702 -248.908824) (xy 41.532908 -248.943942) (xy 41.477466 -249.009647)
			(xy 41.415941 -249.069695) (xy 41.348908 -249.123525) (xy 41.276992 -249.170633) (xy 41.200866 -249.21058)
			(xy 41.121239 -249.242994) (xy 41.038855 -249.267571) (xy 40.954484 -249.284082) (xy 40.868914 -249.292372)
			(xy 40.825928 -249.292872) (xy 40.784824 -249.292421) (xy 40.702967 -249.284838) (xy 40.622159 -249.269734)
			(xy 40.543089 -249.247239) (xy 40.466433 -249.217543) (xy 40.392843 -249.180901) (xy 40.322949 -249.137625)
			(xy 40.257346 -249.088084) (xy 40.196594 -249.032701) (xy 40.141211 -248.971948) (xy 40.091671 -248.906345)
			(xy 40.048395 -248.83645) (xy 40.011754 -248.76286) (xy 39.982059 -248.686203) (xy 39.959564 -248.607133)
			(xy 39.944461 -248.526325) (xy 39.936879 -248.444468) (xy 39.93642 -248.403364) (xy 39.936986 -248.357246)
			(xy 39.946534 -248.265507) (xy 39.965525 -248.175248) (xy 39.993754 -248.087439) (xy 40.030918 -248.003023)
			(xy 40.05326 -247.962674) (xy 40.058594 -247.953276) (xy 40.06088 -247.932448) (xy 40.03167 -247.840754)
			(xy 40.017954 -247.825006) (xy 40.008302 -247.82018) (xy 39.970497 -247.801949) (xy 39.898194 -247.759316)
			(xy 39.83023 -247.710059) (xy 39.767209 -247.654618) (xy 39.709693 -247.593485) (xy 39.658193 -247.527205)
			(xy 39.613167 -247.456366) (xy 39.575017 -247.381601) (xy 39.544081 -247.303573) (xy 39.520635 -247.222978)
			(xy 39.504887 -247.140531) (xy 39.496978 -247.056968) (xy 39.496492 -247.015) (xy 38.643711 -247.015)
			(xy 38.667698 -247.038611) (xy 38.723152 -247.104973) (xy 38.771903 -247.176403) (xy 38.813492 -247.252228)
			(xy 38.847525 -247.331731) (xy 38.873681 -247.414163) (xy 38.891712 -247.498743) (xy 38.90145 -247.584675)
			(xy 38.90264 -247.627902) (xy 38.903122 -247.636888) (xy 38.909572 -247.653674) (xy 38.921428 -247.667194)
			(xy 38.937228 -247.675782) (xy 38.946074 -247.677432) (xy 38.987832 -247.683994) (xy 39.069932 -247.704141)
			(xy 39.149751 -247.731986) (xy 39.226568 -247.767278) (xy 39.299691 -247.809699) (xy 39.368459 -247.858865)
			(xy 39.432252 -247.914334) (xy 39.490495 -247.975605) (xy 39.542662 -248.042125) (xy 39.588284 -248.113295)
			(xy 39.626947 -248.188471) (xy 39.658305 -248.266977) (xy 39.682072 -248.348103) (xy 39.698036 -248.431118)
			(xy 39.706052 -248.515274) (xy 39.70655 -248.557542) (xy 39.706026 -248.600672) (xy 39.697672 -248.686526)
			(xy 39.681046 -248.771168) (xy 39.656306 -248.853804) (xy 39.623682 -248.933657) (xy 39.583482 -249.009976)
			(xy 39.536084 -249.082046) (xy 39.481931 -249.14919) (xy 39.421533 -249.210776) (xy 39.355458 -249.266227)
			(xy 39.284325 -249.315021) (xy 39.24681 -249.336306) (xy 39.237634 -249.34199) (xy 39.224646 -249.359204)
			(xy 39.221664 -249.36958) (xy 39.211761 -249.41129) (xy 39.189546 -249.4788) (xy 44.648387 -249.4788)
			(xy 44.652417 -249.3942) (xy 44.664471 -249.310365) (xy 44.684439 -249.228056) (xy 44.71214 -249.148018)
			(xy 44.747324 -249.070975) (xy 44.789672 -248.997626) (xy 44.8388 -248.928634) (xy 44.894264 -248.864625)
			(xy 44.955562 -248.806177) (xy 45.022137 -248.753821) (xy 45.093388 -248.70803) (xy 45.168669 -248.669219)
			(xy 45.247298 -248.63774) (xy 45.328563 -248.613878) (xy 45.411729 -248.597848) (xy 45.496042 -248.589796)
			(xy 45.53839 -248.589292) (xy 45.584785 -248.589878) (xy 45.677074 -248.599522) (xy 45.767858 -248.618717)
			(xy 45.856151 -248.647255) (xy 45.898816 -248.665492) (xy 45.908756 -248.669312) (xy 45.930024 -248.669312)
			(xy 45.939964 -248.665492) (xy 45.982628 -248.647251) (xy 46.070919 -248.618706) (xy 46.161704 -248.599512)
			(xy 46.253994 -248.589877) (xy 46.30039 -248.589292) (xy 46.346785 -248.589878) (xy 46.439074 -248.599522)
			(xy 46.529858 -248.618717) (xy 46.618151 -248.647255) (xy 46.660816 -248.665492) (xy 46.670756 -248.669312)
			(xy 46.692024 -248.669312) (xy 46.701964 -248.665492) (xy 46.744628 -248.647251) (xy 46.832919 -248.618706)
			(xy 46.923704 -248.599512) (xy 47.015994 -248.589877) (xy 47.06239 -248.589292) (xy 47.108785 -248.589878)
			(xy 47.201074 -248.599522) (xy 47.291858 -248.618717) (xy 47.380151 -248.647255) (xy 47.422816 -248.665492)
			(xy 47.432756 -248.669312) (xy 47.454024 -248.669312) (xy 47.463964 -248.665492) (xy 47.506628 -248.647251)
			(xy 47.594919 -248.618706) (xy 47.685704 -248.599512) (xy 47.777994 -248.589877) (xy 47.82439 -248.589292)
			(xy 47.86674 -248.58978) (xy 47.951055 -248.59783) (xy 48.034224 -248.613858) (xy 48.115492 -248.63772)
			(xy 48.194124 -248.669199) (xy 48.269408 -248.70801) (xy 48.340662 -248.753801) (xy 48.40724 -248.806158)
			(xy 48.46854 -248.864607) (xy 48.524007 -248.928618) (xy 48.573137 -248.997611) (xy 48.615487 -249.070963)
			(xy 48.650673 -249.148008) (xy 48.678375 -249.228048) (xy 48.698344 -249.31036) (xy 48.710398 -249.394197)
			(xy 48.714428 -249.4788) (xy 48.710398 -249.563403) (xy 48.698344 -249.64724) (xy 48.678375 -249.729552)
			(xy 48.650673 -249.809592) (xy 48.615487 -249.886637) (xy 48.573137 -249.959989) (xy 48.524007 -250.028982)
			(xy 48.46854 -250.092993) (xy 48.40724 -250.151442) (xy 48.340662 -250.203799) (xy 48.269408 -250.24959)
			(xy 48.194124 -250.288401) (xy 48.115492 -250.31988) (xy 48.034224 -250.343742) (xy 47.951055 -250.35977)
			(xy 47.86674 -250.36782) (xy 47.82439 -250.368308) (xy 47.777994 -250.367729) (xy 47.685706 -250.358083)
			(xy 47.594922 -250.338886) (xy 47.506629 -250.310346) (xy 47.463964 -250.292108) (xy 47.454024 -250.288288)
			(xy 47.432756 -250.288288) (xy 47.422816 -250.292108) (xy 47.380155 -250.310356) (xy 47.291862 -250.338899)
			(xy 47.201077 -250.358091) (xy 47.108786 -250.367724) (xy 47.06239 -250.368308) (xy 47.015994 -250.367729)
			(xy 46.923706 -250.358083) (xy 46.832922 -250.338886) (xy 46.744629 -250.310346) (xy 46.701964 -250.292108)
			(xy 46.692024 -250.288288) (xy 46.670756 -250.288288) (xy 46.660816 -250.292108) (xy 46.618155 -250.310356)
			(xy 46.529862 -250.338899) (xy 46.439077 -250.358091) (xy 46.346786 -250.367724) (xy 46.30039 -250.368308)
			(xy 46.253994 -250.367729) (xy 46.161706 -250.358083) (xy 46.070922 -250.338886) (xy 45.982629 -250.310346)
			(xy 45.939964 -250.292108) (xy 45.930024 -250.288288) (xy 45.908756 -250.288288) (xy 45.898816 -250.292108)
			(xy 45.856155 -250.310356) (xy 45.767862 -250.338899) (xy 45.677077 -250.358091) (xy 45.584786 -250.367724)
			(xy 45.53839 -250.368308) (xy 45.496042 -250.367804) (xy 45.411729 -250.359752) (xy 45.328563 -250.343722)
			(xy 45.247298 -250.31986) (xy 45.168669 -250.288381) (xy 45.093388 -250.24957) (xy 45.022137 -250.203779)
			(xy 44.955562 -250.151423) (xy 44.894264 -250.092975) (xy 44.8388 -250.028966) (xy 44.789672 -249.959974)
			(xy 44.747324 -249.886625) (xy 44.71214 -249.809582) (xy 44.684439 -249.729544) (xy 44.664471 -249.647235)
			(xy 44.652417 -249.5634) (xy 44.648387 -249.4788) (xy 39.189546 -249.4788) (xy 39.184963 -249.492728)
			(xy 39.150453 -249.571209) (xy 39.10855 -249.646004) (xy 39.059643 -249.71642) (xy 39.004187 -249.781802)
			(xy 38.942696 -249.841544) (xy 38.875742 -249.895091) (xy 38.803944 -249.941946) (xy 38.727971 -249.981674)
			(xy 38.648527 -250.013906) (xy 38.56635 -250.038343) (xy 38.482203 -250.054759) (xy 38.396867 -250.063)
			(xy 38.354 -250.063508) (xy 38.312898 -250.063033) (xy 38.231043 -250.055448) (xy 38.150238 -250.040343)
			(xy 38.071171 -250.017847) (xy 37.994517 -249.988151) (xy 37.92093 -249.951509) (xy 37.851038 -249.908234)
			(xy 37.785437 -249.858694) (xy 37.724687 -249.803313) (xy 37.669306 -249.742563) (xy 37.619766 -249.676962)
			(xy 37.576491 -249.60707) (xy 37.539849 -249.533483) (xy 37.510153 -249.456829) (xy 37.487657 -249.377762)
			(xy 37.472552 -249.296957) (xy 37.464967 -249.215102) (xy 37.464492 -249.174) (xy 37.465014 -249.129845)
			(xy 37.473768 -249.04197) (xy 37.491189 -248.955396) (xy 37.517107 -248.870975) (xy 37.551265 -248.789538)
			(xy 37.593327 -248.711889) (xy 37.64288 -248.638792) (xy 37.67074 -248.604532) (xy 37.67836 -248.595134)
			(xy 37.683948 -248.572528) (xy 37.661342 -248.470674) (xy 37.64661 -248.452386) (xy 37.635688 -248.447306)
			(xy 37.597865 -248.429076) (xy 37.525526 -248.386438) (xy 37.457528 -248.337173) (xy 37.394475 -248.281719)
			(xy 37.336929 -248.220569) (xy 37.285402 -248.154268) (xy 37.240353 -248.083406) (xy 37.202183 -248.008614)
			(xy 37.171232 -247.930557) (xy 37.147774 -247.849931) (xy 37.13202 -247.767452) (xy 37.124109 -247.683857)
			(xy 37.123624 -247.641872) (xy 36.681771 -247.641872) (xy 36.712132 -247.670821) (xy 36.767597 -247.734831)
			(xy 36.816726 -247.803823) (xy 36.859075 -247.877173) (xy 36.894259 -247.954216) (xy 36.921961 -248.034255)
			(xy 36.941929 -248.116564) (xy 36.953982 -248.200399) (xy 36.958013 -248.285) (xy 36.953982 -248.369601)
			(xy 36.941929 -248.453436) (xy 36.921961 -248.535745) (xy 36.894259 -248.615784) (xy 36.859075 -248.692827)
			(xy 36.816726 -248.766177) (xy 36.767597 -248.835169) (xy 36.712132 -248.899179) (xy 36.650834 -248.957627)
			(xy 36.584258 -249.009983) (xy 36.513006 -249.055773) (xy 36.437725 -249.094584) (xy 36.359095 -249.126063)
			(xy 36.277828 -249.149924) (xy 36.194662 -249.165953) (xy 36.110348 -249.174004) (xy 36.068 -249.174508)
			(xy 36.02949 -249.174098) (xy 35.952758 -249.167438) (xy 35.876889 -249.154169) (xy 35.802452 -249.134389)
			(xy 35.730004 -249.108248) (xy 35.694874 -249.092466) (xy 35.68349 -249.08796) (xy 35.659075 -249.089002)
			(xy 35.648138 -249.094498) (xy 35.607666 -249.117039) (xy 35.52294 -249.154516) (xy 35.434778 -249.182984)
			(xy 35.344135 -249.202134) (xy 35.251992 -249.21176) (xy 35.20567 -249.212354) (xy 35.163321 -249.211858)
			(xy 35.079007 -249.203807) (xy 34.995841 -249.187778) (xy 34.914574 -249.163916) (xy 34.835944 -249.132437)
			(xy 34.760662 -249.093627) (xy 34.68941 -249.047836) (xy 34.622833 -248.99548) (xy 34.561535 -248.937032)
			(xy 34.50607 -248.873022) (xy 34.45694 -248.804029) (xy 34.414592 -248.730679) (xy 34.379407 -248.653636)
			(xy 34.351705 -248.573597) (xy 34.331737 -248.491287) (xy 34.319684 -248.407451) (xy 34.315654 -248.32285)
			(xy 33.637454 -248.32285) (xy 33.659372 -248.397498) (xy 33.675401 -248.480664) (xy 33.683452 -248.564978)
			(xy 33.683956 -248.607326) (xy 33.683452 -248.649674) (xy 33.675401 -248.733988) (xy 33.659372 -248.817154)
			(xy 33.635511 -248.898421) (xy 33.604032 -248.977051) (xy 33.565221 -249.052332) (xy 33.519431 -249.123584)
			(xy 33.467075 -249.19016) (xy 33.408627 -249.251458) (xy 33.344617 -249.306923) (xy 33.275625 -249.356052)
			(xy 33.202275 -249.398401) (xy 33.125232 -249.433585) (xy 33.045193 -249.461287) (xy 32.962884 -249.481255)
			(xy 32.879049 -249.493308) (xy 32.794448 -249.497339) (xy 32.709847 -249.493308) (xy 32.626012 -249.481255)
			(xy 32.543703 -249.461287) (xy 32.463664 -249.433585) (xy 32.386621 -249.398401) (xy 32.313271 -249.356052)
			(xy 32.244279 -249.306923) (xy 32.180269 -249.251458) (xy 32.121821 -249.19016) (xy 32.069465 -249.123584)
			(xy 32.023675 -249.052332) (xy 31.984864 -248.977051) (xy 31.953385 -248.898421) (xy 31.929524 -248.817154)
			(xy 31.913495 -248.733988) (xy 31.905444 -248.649674) (xy 26.912741 -248.649674) (xy 26.915953 -248.666338)
			(xy 26.924004 -248.750652) (xy 26.924508 -248.793) (xy 26.924004 -248.835348) (xy 26.915953 -248.919662)
			(xy 26.899924 -249.002828) (xy 26.876063 -249.084095) (xy 26.844584 -249.162725) (xy 26.805773 -249.238006)
			(xy 26.759983 -249.309258) (xy 26.707627 -249.375834) (xy 26.649179 -249.437132) (xy 26.585169 -249.492597)
			(xy 26.516177 -249.541726) (xy 26.442827 -249.584075) (xy 26.365784 -249.619259) (xy 26.285745 -249.646961)
			(xy 26.203436 -249.666929) (xy 26.119601 -249.678982) (xy 26.035 -249.683013) (xy 25.950399 -249.678982)
			(xy 25.866564 -249.666929) (xy 25.784255 -249.646961) (xy 25.704216 -249.619259) (xy 25.627173 -249.584075)
			(xy 25.553823 -249.541726) (xy 25.484831 -249.492597) (xy 25.420821 -249.437132) (xy 25.362373 -249.375834)
			(xy 25.310017 -249.309258) (xy 25.264227 -249.238006) (xy 25.225416 -249.162725) (xy 25.193937 -249.084095)
			(xy 25.170076 -249.002828) (xy 25.154047 -248.919662) (xy 25.145996 -248.835348) (xy 10.409703 -248.835348)
			(xy 10.393179 -248.852678) (xy 10.329169 -248.908143) (xy 10.260177 -248.957272) (xy 10.186827 -248.999621)
			(xy 10.109784 -249.034805) (xy 10.029745 -249.062507) (xy 9.947436 -249.082475) (xy 9.863601 -249.094528)
			(xy 9.779 -249.098559) (xy 9.694399 -249.094528) (xy 9.610564 -249.082475) (xy 9.528255 -249.062507)
			(xy 9.448216 -249.034805) (xy 9.371173 -248.999621) (xy 9.297823 -248.957272) (xy 9.228831 -248.908143)
			(xy 9.164821 -248.852678) (xy 9.106373 -248.79138) (xy 9.054017 -248.724804) (xy 9.008227 -248.653552)
			(xy 8.969416 -248.578271) (xy 8.937937 -248.499641) (xy 8.914076 -248.418374) (xy 8.898047 -248.335208)
			(xy 8.889996 -248.250894) (xy 8.889492 -248.208546) (xy 8.889945 -248.16677) (xy 8.897791 -248.083586)
			(xy 8.913398 -248.001505) (xy 8.936631 -247.921247) (xy 8.967284 -247.843521) (xy 9.005087 -247.769009)
			(xy 9.049708 -247.698369) (xy 9.100753 -247.632222) (xy 9.157773 -247.571151) (xy 9.188704 -247.543066)
			(xy 9.196545 -247.535296) (xy 9.205351 -247.515081) (xy 9.20494 -247.493035) (xy 9.200642 -247.482868)
			(xy 9.183174 -247.446251) (xy 9.154206 -247.370464) (xy 9.132269 -247.292352) (xy 9.117545 -247.212565)
			(xy 9.110157 -247.131767) (xy 9.10971 -247.0912) (xy 9.109964 -247.06707) (xy 9.110218 -247.056402)
			(xy 9.102344 -247.036844) (xy 9.03351 -246.969788) (xy 9.013952 -246.962422) (xy 9.00303 -246.96293)
			(xy 8.955786 -246.9642) (xy 8.913861 -246.96371) (xy 8.830383 -246.955819) (xy 8.748018 -246.940107)
			(xy 8.667497 -246.916713) (xy 8.589535 -246.885845) (xy 8.514824 -246.847778) (xy 8.444027 -246.802848)
			(xy 8.377773 -246.751455) (xy 8.316649 -246.694056) (xy 8.261198 -246.631158) (xy 8.211912 -246.563322)
			(xy 8.169229 -246.491148) (xy 8.133528 -246.415278) (xy 8.105125 -246.336385) (xy 8.084273 -246.255169)
			(xy 8.071156 -246.172351) (xy 8.065891 -246.088666) (xy 7.393282 -246.088666) (xy 7.413828 -246.095777)
			(xy 7.490871 -246.130961) (xy 7.564221 -246.17331) (xy 7.633213 -246.222439) (xy 7.697223 -246.277904)
			(xy 7.755671 -246.339202) (xy 7.808027 -246.405778) (xy 7.853817 -246.47703) (xy 7.892628 -246.552311)
			(xy 7.924107 -246.630941) (xy 7.947968 -246.712208) (xy 7.963997 -246.795374) (xy 7.972048 -246.879688)
			(xy 7.972552 -246.922036) (xy 7.972125 -246.961394) (xy 7.965167 -247.039801) (xy 7.951308 -247.117286)
			(xy 7.930657 -247.193244) (xy 7.903375 -247.267081) (xy 7.869676 -247.338217) (xy 7.850124 -247.372378)
			(xy 7.845795 -247.380462) (xy 7.842677 -247.398523) (xy 7.846092 -247.416531) (xy 7.855605 -247.432197)
			(xy 7.86257 -247.438164) (xy 7.893933 -247.463378) (xy 7.95246 -247.518617) (xy 8.005756 -247.578918)
			(xy 8.053387 -247.643788) (xy 8.094961 -247.712696) (xy 8.13014 -247.785078) (xy 8.158635 -247.860343)
			(xy 8.180214 -247.937874) (xy 8.194699 -248.017038) (xy 8.201972 -248.097187) (xy 8.202422 -248.137426)
			(xy 8.201958 -248.178529) (xy 8.194371 -248.260383) (xy 8.179264 -248.341188) (xy 8.156766 -248.420254)
			(xy 8.127069 -248.496907) (xy 8.090425 -248.570494) (xy 8.047149 -248.640385) (xy 7.997609 -248.705986)
			(xy 7.942227 -248.766736) (xy 7.881477 -248.822116) (xy 7.815875 -248.871656) (xy 7.745983 -248.914931)
			(xy 7.672396 -248.951573) (xy 7.595743 -248.98127) (xy 7.516676 -249.003767) (xy 7.435871 -249.018873)
			(xy 7.354017 -249.026459) (xy 7.312914 -249.026934) (xy 7.269398 -249.026384) (xy 7.182785 -249.017865)
			(xy 7.097417 -249.000926) (xy 7.055612 -248.988834) (xy 7.043949 -248.985977) (xy 7.020347 -248.990232)
			(xy 7.0104 -248.996962) (xy 6.977407 -249.021077) (xy 6.907782 -249.063873) (xy 6.834523 -249.100099)
			(xy 6.758248 -249.129448) (xy 6.679602 -249.151672) (xy 6.599247 -249.166584) (xy 6.517863 -249.174058)
			(xy 6.477 -249.174508) (xy 6.435898 -249.174033) (xy 6.354043 -249.166448) (xy 6.273238 -249.151343)
			(xy 6.194171 -249.128847) (xy 6.117517 -249.099151) (xy 6.04393 -249.062509) (xy 5.974038 -249.019234)
			(xy 5.908437 -248.969694) (xy 5.847687 -248.914313) (xy 5.792306 -248.853563) (xy 5.742766 -248.787962)
			(xy 5.699491 -248.71807) (xy 5.662849 -248.644483) (xy 5.633153 -248.567829) (xy 5.610657 -248.488762)
			(xy 5.595552 -248.407957) (xy 5.587967 -248.326102) (xy 5.587492 -248.285) (xy 4.90277 -248.285)
			(xy 4.867899 -248.305996) (xy 4.792922 -248.34207) (xy 4.714903 -248.370986) (xy 4.634526 -248.39249)
			(xy 4.552491 -248.406394) (xy 4.51104 -248.409968) (xy 4.500061 -248.411311) (xy 4.480709 -248.421983)
			(xy 4.473702 -248.430542) (xy 4.448617 -248.463843) (xy 4.393199 -248.52614) (xy 4.332193 -248.582975)
			(xy 4.266134 -248.633849) (xy 4.195602 -248.678316) (xy 4.121218 -248.715985) (xy 4.043634 -248.746526)
			(xy 3.963532 -248.769669) (xy 3.881615 -248.785212) (xy 3.798603 -248.793019) (xy 3.756914 -248.793508)
			(xy 3.715811 -248.793044) (xy 3.633955 -248.785459) (xy 3.553149 -248.770354) (xy 3.474081 -248.747858)
			(xy 3.397426 -248.718162) (xy 3.323838 -248.68152) (xy 3.253944 -248.638244) (xy 3.188342 -248.588704)
			(xy 3.127591 -248.533322) (xy 3.072209 -248.472571) (xy 3.022668 -248.406969) (xy 2.979392 -248.337076)
			(xy 2.94275 -248.263488) (xy 2.913053 -248.186833) (xy 2.890557 -248.107765) (xy 2.875451 -248.026959)
			(xy 2.867866 -247.945103) (xy 2.867406 -247.904) (xy 1.651254 -247.904) (xy 1.651254 -251.206) (xy 4.189988 -251.206)
			(xy 4.194018 -251.121399) (xy 4.206071 -251.037564) (xy 4.226039 -250.955255) (xy 4.253741 -250.875216)
			(xy 4.288925 -250.798173) (xy 4.331274 -250.724823) (xy 4.380403 -250.655831) (xy 4.435868 -250.591821)
			(xy 4.497166 -250.533373) (xy 4.563742 -250.481017) (xy 4.634994 -250.435227) (xy 4.710275 -250.396416)
			(xy 4.788905 -250.364937) (xy 4.870172 -250.341076) (xy 4.953338 -250.325047) (xy 5.037652 -250.316996)
			(xy 5.08 -250.316492) (xy 5.123044 -250.316998) (xy 5.208728 -250.325319) (xy 5.293208 -250.341878)
			(xy 5.375693 -250.366521) (xy 5.455412 -250.399018) (xy 5.531618 -250.439064) (xy 5.603599 -250.486285)
			(xy 5.670681 -250.540239) (xy 5.732238 -250.600421) (xy 5.787692 -250.666268) (xy 5.836525 -250.737165)
			(xy 5.878282 -250.812448) (xy 5.912569 -250.891412) (xy 5.939068 -250.97332) (xy 5.95753 -251.057405)
			(xy 5.963158 -251.100082) (xy 5.964742 -251.10923) (xy 5.973405 -251.125629) (xy 5.987323 -251.137888)
			(xy 6.004683 -251.144413) (xy 6.013958 -251.144786) (xy 6.020308 -251.144786) (xy 6.06141 -251.145259)
			(xy 6.143265 -251.152845) (xy 6.22407 -251.16795) (xy 6.303136 -251.190447) (xy 6.37979 -251.220143)
			(xy 6.453377 -251.256786) (xy 6.523269 -251.300061) (xy 6.588869 -251.349601) (xy 6.649619 -251.404982)
			(xy 6.705 -251.465732) (xy 6.75454 -251.531333) (xy 6.797815 -251.601225) (xy 6.834457 -251.674812)
			(xy 6.864153 -251.751466) (xy 6.88665 -251.830532) (xy 6.901756 -251.911337) (xy 6.909341 -251.993192)
			(xy 6.909816 -252.034294) (xy 6.909329 -252.075942) (xy 6.901528 -252.158872) (xy 6.886003 -252.240709)
			(xy 6.86289 -252.320734) (xy 6.848094 -252.359668) (xy 6.84403 -252.370082) (xy 6.8453 -252.39218)
			(xy 6.89229 -252.480318) (xy 6.91007 -252.493526) (xy 6.920992 -252.496066) (xy 6.95945 -252.504923)
			(xy 7.034746 -252.528581) (xy 7.07136 -252.54331) (xy 7.084822 -252.548644) (xy 7.112508 -252.544326)
			(xy 7.203694 -252.466856) (xy 7.21233 -252.440186) (xy 7.209028 -252.425962) (xy 7.197964 -252.375699)
			(xy 7.186126 -252.273461) (xy 7.185406 -252.222) (xy 7.18591 -252.179652) (xy 7.193961 -252.095338)
			(xy 7.20999 -252.012172) (xy 7.233851 -251.930905) (xy 7.26533 -251.852275) (xy 7.304141 -251.776994)
			(xy 7.349931 -251.705742) (xy 7.402287 -251.639166) (xy 7.460735 -251.577868) (xy 7.524745 -251.522403)
			(xy 7.593737 -251.473274) (xy 7.667087 -251.430925) (xy 7.74413 -251.395741) (xy 7.824169 -251.368039)
			(xy 7.906478 -251.348071) (xy 7.990313 -251.336018) (xy 8.074914 -251.331988) (xy 8.159515 -251.336018)
			(xy 8.24335 -251.348071) (xy 8.325659 -251.368039) (xy 8.405698 -251.395741) (xy 8.482741 -251.430925)
			(xy 8.507144 -251.445014) (xy 8.986012 -251.445014) (xy 8.986516 -251.402666) (xy 8.994567 -251.318352)
			(xy 9.010596 -251.235186) (xy 9.034457 -251.153919) (xy 9.065936 -251.075289) (xy 9.104747 -251.000008)
			(xy 9.150537 -250.928756) (xy 9.202893 -250.86218) (xy 9.261341 -250.800882) (xy 9.325351 -250.745417)
			(xy 9.394343 -250.696288) (xy 9.467693 -250.653939) (xy 9.544736 -250.618755) (xy 9.624775 -250.591053)
			(xy 9.707084 -250.571085) (xy 9.790919 -250.559032) (xy 9.87552 -250.555002) (xy 9.960121 -250.559032)
			(xy 10.043956 -250.571085) (xy 10.126265 -250.591053) (xy 10.206304 -250.618755) (xy 10.283347 -250.653939)
			(xy 10.356697 -250.696288) (xy 10.425689 -250.745417) (xy 10.489699 -250.800882) (xy 10.548147 -250.86218)
			(xy 10.600503 -250.928756) (xy 10.646293 -251.000008) (xy 10.685104 -251.075289) (xy 10.716583 -251.153919)
			(xy 10.740444 -251.235186) (xy 10.756473 -251.318352) (xy 10.764524 -251.402666) (xy 10.765028 -251.445014)
			(xy 10.764586 -251.484057) (xy 10.757728 -251.561841) (xy 10.744084 -251.638725) (xy 10.723757 -251.714119)
			(xy 10.696905 -251.787443) (xy 10.6807 -251.822966) (xy 10.676636 -251.831856) (xy 10.675366 -251.850652)
			(xy 10.702544 -251.935234) (xy 10.714482 -251.949712) (xy 10.722864 -251.954538) (xy 10.759937 -251.975963)
			(xy 10.830201 -252.024911) (xy 10.895436 -252.080383) (xy 10.95504 -252.141866) (xy 11.008461 -252.208791)
			(xy 11.055205 -252.28054) (xy 11.094839 -252.356447) (xy 11.126996 -252.435812) (xy 11.147611 -252.50521)
			(xy 11.471148 -252.50521) (xy 11.47173 -252.458814) (xy 11.481374 -252.366526) (xy 11.50057 -252.275742)
			(xy 11.52911 -252.187449) (xy 11.547348 -252.144784) (xy 11.551161 -252.134842) (xy 11.551164 -252.113576)
			(xy 11.547348 -252.103636) (xy 11.52911 -252.060971) (xy 11.500563 -251.97268) (xy 11.481368 -251.881896)
			(xy 11.471733 -251.789606) (xy 11.471148 -251.74321) (xy 11.47173 -251.696814) (xy 11.481374 -251.604526)
			(xy 11.50057 -251.513742) (xy 11.52911 -251.425449) (xy 11.547348 -251.382784) (xy 11.551161 -251.372842)
			(xy 11.551164 -251.351576) (xy 11.547348 -251.341636) (xy 11.52911 -251.298971) (xy 11.500563 -251.21068)
			(xy 11.481368 -251.119896) (xy 11.471733 -251.027606) (xy 11.471148 -250.98121) (xy 11.47173 -250.934814)
			(xy 11.481374 -250.842526) (xy 11.50057 -250.751742) (xy 11.52911 -250.663449) (xy 11.547348 -250.620784)
			(xy 11.551161 -250.610842) (xy 11.551164 -250.589576) (xy 11.547348 -250.579636) (xy 11.52911 -250.536971)
			(xy 11.500563 -250.44868) (xy 11.481368 -250.357896) (xy 11.471733 -250.265606) (xy 11.471148 -250.21921)
			(xy 11.471676 -250.178109) (xy 11.47926 -250.096257) (xy 11.494363 -250.015455) (xy 11.516857 -249.93639)
			(xy 11.54655 -249.859739) (xy 11.583189 -249.786154) (xy 11.626462 -249.716263) (xy 11.675998 -249.650663)
			(xy 11.731375 -249.589913) (xy 11.792121 -249.534532) (xy 11.857718 -249.484992) (xy 11.927606 -249.441716)
			(xy 12.001189 -249.405072) (xy 12.077839 -249.375374) (xy 12.156902 -249.352875) (xy 12.237704 -249.337767)
			(xy 12.319555 -249.330179) (xy 12.360656 -249.329702) (xy 12.398944 -249.330131) (xy 12.475235 -249.336754)
			(xy 12.550674 -249.349903) (xy 12.624706 -249.369481) (xy 12.660884 -249.382026) (xy 12.669322 -249.384668)
			(xy 12.68699 -249.384668) (xy 12.695428 -249.382026) (xy 12.731597 -249.369454) (xy 12.805629 -249.349862)
			(xy 12.881072 -249.336715) (xy 12.957366 -249.33011) (xy 12.995656 -249.329702) (xy 13.036759 -249.330194)
			(xy 13.118614 -249.337775) (xy 13.19942 -249.352877) (xy 13.278488 -249.375371) (xy 13.355144 -249.405064)
			(xy 13.428732 -249.441704) (xy 13.498626 -249.484977) (xy 13.564228 -249.534516) (xy 13.62498 -249.589896)
			(xy 13.680363 -249.650645) (xy 13.729903 -249.716246) (xy 13.77318 -249.786138) (xy 13.809822 -249.859725)
			(xy 13.839519 -249.936379) (xy 13.862015 -250.015447) (xy 13.87712 -250.096252) (xy 13.884704 -250.178107)
			(xy 13.885164 -250.21921) (xy 13.884588 -250.265606) (xy 13.874942 -250.357895) (xy 13.855744 -250.448678)
			(xy 13.827203 -250.536972) (xy 13.808964 -250.579636) (xy 13.805139 -250.589574) (xy 13.805143 -250.610844)
			(xy 13.808964 -250.620784) (xy 13.827209 -250.663446) (xy 13.855754 -250.751738) (xy 13.874947 -250.842523)
			(xy 13.88458 -250.934814) (xy 13.885164 -250.98121) (xy 13.884588 -251.027606) (xy 13.874942 -251.119895)
			(xy 13.855744 -251.210678) (xy 13.827203 -251.298972) (xy 13.808964 -251.341636) (xy 13.805139 -251.351574)
			(xy 13.805143 -251.372844) (xy 13.808964 -251.382784) (xy 13.827209 -251.425446) (xy 13.855754 -251.513738)
			(xy 13.874947 -251.604523) (xy 13.88458 -251.696814) (xy 13.885164 -251.74321) (xy 13.884588 -251.789606)
			(xy 13.874942 -251.881895) (xy 13.855744 -251.972678) (xy 13.843567 -252.010348) (xy 29.463996 -252.010348)
			(xy 29.463996 -251.925652) (xy 29.472047 -251.841338) (xy 29.488076 -251.758172) (xy 29.511937 -251.676905)
			(xy 29.543416 -251.598275) (xy 29.582227 -251.522994) (xy 29.628017 -251.451742) (xy 29.680373 -251.385166)
			(xy 29.738821 -251.323868) (xy 29.802831 -251.268403) (xy 29.871823 -251.219274) (xy 29.945173 -251.176925)
			(xy 30.022216 -251.141741) (xy 30.102255 -251.114039) (xy 30.184564 -251.094071) (xy 30.268399 -251.082018)
			(xy 30.353 -251.077988) (xy 30.437601 -251.082018) (xy 30.521436 -251.094071) (xy 30.603745 -251.114039)
			(xy 30.683784 -251.141741) (xy 30.760827 -251.176925) (xy 30.834177 -251.219274) (xy 30.903169 -251.268403)
			(xy 30.967179 -251.323868) (xy 31.025627 -251.385166) (xy 31.077983 -251.451742) (xy 31.123773 -251.522994)
			(xy 31.162584 -251.598275) (xy 31.194063 -251.676905) (xy 31.217924 -251.758172) (xy 31.233953 -251.841338)
			(xy 31.242004 -251.925652) (xy 31.242508 -251.968) (xy 31.242004 -252.010348) (xy 31.233953 -252.094662)
			(xy 31.217924 -252.177828) (xy 31.194063 -252.259095) (xy 31.162584 -252.337725) (xy 31.123773 -252.413006)
			(xy 31.077983 -252.484258) (xy 31.025627 -252.550834) (xy 30.967179 -252.612132) (xy 30.903169 -252.667597)
			(xy 30.834177 -252.716726) (xy 30.760827 -252.759075) (xy 30.683784 -252.794259) (xy 30.644891 -252.80772)
			(xy 33.026361 -252.80772) (xy 33.030392 -252.72312) (xy 33.042445 -252.639285) (xy 33.062413 -252.556976)
			(xy 33.090114 -252.476938) (xy 33.125298 -252.399896) (xy 33.167646 -252.326546) (xy 33.216775 -252.257555)
			(xy 33.272239 -252.193545) (xy 33.333537 -252.135098) (xy 33.400112 -252.082742) (xy 33.471363 -252.036951)
			(xy 33.546644 -251.998141) (xy 33.625274 -251.966662) (xy 33.706539 -251.9428) (xy 33.789705 -251.926771)
			(xy 33.874018 -251.91872) (xy 33.916366 -251.918216) (xy 33.95759 -251.918683) (xy 34.039684 -251.926302)
			(xy 34.120721 -251.941485) (xy 34.200004 -251.964103) (xy 34.276854 -251.993963) (xy 34.350611 -252.030806)
			(xy 34.420641 -252.074318) (xy 34.486344 -252.124124) (xy 34.547155 -252.179798) (xy 34.602552 -252.24086)
			(xy 34.65206 -252.306788) (xy 34.695254 -252.377015) (xy 34.713926 -252.41377) (xy 34.719006 -252.424184)
			(xy 34.73704 -252.438408) (xy 34.836354 -252.461014) (xy 34.858706 -252.455934) (xy 34.867596 -252.448822)
			(xy 34.897297 -252.426041) (xy 34.959904 -252.385002) (xy 35.025734 -252.349362) (xy 35.059874 -252.334014)
			(xy 35.068654 -252.329622) (xy 35.082289 -252.315521) (xy 35.089648 -252.297339) (xy 35.0901 -252.287532)
			(xy 35.0901 -252.194314) (xy 35.089656 -252.184502) (xy 35.082315 -252.166306) (xy 35.068666 -252.152209)
			(xy 35.059874 -252.147832) (xy 35.020768 -252.130099) (xy 34.945779 -252.088263) (xy 34.875172 -252.039394)
			(xy 34.809604 -251.983947) (xy 34.749686 -251.922438) (xy 34.695975 -251.85544) (xy 34.648972 -251.783577)
			(xy 34.609115 -251.707518) (xy 34.576774 -251.627972) (xy 34.552252 -251.545678) (xy 34.535775 -251.461404)
			(xy 34.527498 -251.375935) (xy 34.526982 -251.333) (xy 34.527486 -251.290652) (xy 34.535537 -251.206338)
			(xy 34.551566 -251.123172) (xy 34.575427 -251.041905) (xy 34.606906 -250.963275) (xy 34.645717 -250.887994)
			(xy 34.691507 -250.816742) (xy 34.743863 -250.750166) (xy 34.802311 -250.688868) (xy 34.866321 -250.633403)
			(xy 34.935313 -250.584274) (xy 35.008663 -250.541925) (xy 35.085706 -250.506741) (xy 35.165745 -250.479039)
			(xy 35.248054 -250.459071) (xy 35.331889 -250.447018) (xy 35.41649 -250.442988) (xy 35.501091 -250.447018)
			(xy 35.584926 -250.459071) (xy 35.667235 -250.479039) (xy 35.747274 -250.506741) (xy 35.824317 -250.541925)
			(xy 35.897667 -250.584274) (xy 35.966659 -250.633403) (xy 36.030669 -250.688868) (xy 36.089117 -250.750166)
			(xy 36.141473 -250.816742) (xy 36.187263 -250.887994) (xy 36.226074 -250.963275) (xy 36.257553 -251.041905)
			(xy 36.281414 -251.123172) (xy 36.297443 -251.206338) (xy 36.305494 -251.290652) (xy 36.305998 -251.333)
			(xy 36.30546 -251.375934) (xy 36.297176 -251.461402) (xy 36.280695 -251.545674) (xy 36.256171 -251.627966)
			(xy 36.223831 -251.707512) (xy 36.183977 -251.783571) (xy 36.136979 -251.855436) (xy 36.083276 -251.922438)
			(xy 36.023366 -251.983954) (xy 35.957807 -252.039411) (xy 35.887209 -252.088292) (xy 35.81223 -252.130143)
			(xy 35.773106 -252.147832) (xy 35.764302 -252.152184) (xy 35.750671 -252.166303) (xy 35.743323 -252.184501)
			(xy 35.74288 -252.194314) (xy 35.74288 -252.287532) (xy 35.743301 -252.297346) (xy 35.750656 -252.315541)
			(xy 35.764312 -252.329637) (xy 35.773106 -252.334014) (xy 35.801123 -252.346575) (xy 35.855528 -252.375049)
			(xy 35.881818 -252.39091) (xy 35.890172 -252.39553) (xy 35.90897 -252.398783) (xy 35.918394 -252.39726)
			(xy 35.947858 -252.391418) (xy 35.957108 -252.389206) (xy 35.973163 -252.379036) (xy 35.9791 -252.371606)
			(xy 36.004129 -252.337999) (xy 36.059578 -252.275165) (xy 36.120692 -252.217826) (xy 36.186927 -252.166489)
			(xy 36.257698 -252.12161) (xy 36.332377 -252.083587) (xy 36.4103 -252.052756) (xy 36.490778 -252.02939)
			(xy 36.573097 -252.013699) (xy 36.656527 -252.005819) (xy 36.698428 -252.005338) (xy 36.74337 -252.005893)
			(xy 36.832796 -252.014959) (xy 36.920852 -252.032994) (xy 37.006641 -252.059817) (xy 37.048186 -252.076966)
			(xy 37.057841 -252.080538) (xy 37.078409 -252.080538) (xy 37.088064 -252.076966) (xy 37.129606 -252.059809)
			(xy 37.215396 -252.032992) (xy 37.303454 -252.014961) (xy 37.39288 -252.0059) (xy 37.437822 -252.005338)
			(xy 37.478927 -252.005731) (xy 37.560786 -252.013319) (xy 37.641595 -252.028427) (xy 37.720666 -252.050927)
			(xy 37.797324 -252.080627) (xy 37.870913 -252.117274) (xy 37.940808 -252.160554) (xy 38.006411 -252.210099)
			(xy 38.067163 -252.265485) (xy 38.122545 -252.326241) (xy 38.172085 -252.391848) (xy 38.21536 -252.461746)
			(xy 38.252 -252.535339) (xy 38.281695 -252.611998) (xy 38.304189 -252.691071) (xy 38.319291 -252.771882)
			(xy 38.326872 -252.853741) (xy 38.32733 -252.894846) (xy 38.32691 -252.935313) (xy 38.31956 -253.015912)
			(xy 38.318467 -253.02185) (xy 38.602413 -253.02185) (xy 38.606444 -252.937249) (xy 38.618497 -252.853414)
			(xy 38.638465 -252.771104) (xy 38.666167 -252.691065) (xy 38.701352 -252.614021) (xy 38.7437 -252.540671)
			(xy 38.792829 -252.471679) (xy 38.848294 -252.407669) (xy 38.909592 -252.349221) (xy 38.976169 -252.296865)
			(xy 39.047421 -252.251074) (xy 39.122702 -252.212263) (xy 39.201333 -252.180784) (xy 39.282599 -252.156922)
			(xy 39.365766 -252.140893) (xy 39.450079 -252.132842) (xy 39.492428 -252.132338) (xy 39.533114 -252.132799)
			(xy 39.614144 -252.140234) (xy 39.694158 -252.155037) (xy 39.772484 -252.177086) (xy 39.84847 -252.206197)
			(xy 39.92148 -252.242126) (xy 39.990903 -252.284572) (xy 40.056159 -252.333181) (xy 40.116703 -252.387547)
			(xy 40.1447 -252.417072) (xy 40.152574 -252.425708) (xy 40.17391 -252.43409) (xy 40.277034 -252.425962)
			(xy 40.296846 -252.414532) (xy 40.30345 -252.404626) (xy 40.328153 -252.368764) (xy 40.383572 -252.301587)
			(xy 40.445292 -252.240147) (xy 40.512721 -252.185035) (xy 40.585215 -252.136777) (xy 40.662079 -252.095837)
			(xy 40.742576 -252.062605) (xy 40.825936 -252.037401) (xy 40.91136 -252.020465) (xy 40.99803 -252.01196)
			(xy 41.041574 -252.011434) (xy 41.082733 -252.011921) (xy 41.164698 -252.01954) (xy 41.245608 -252.034696)
			(xy 41.324773 -252.05726) (xy 41.401516 -252.08704) (xy 41.47518 -252.12378) (xy 41.545137 -252.167166)
			(xy 41.610787 -252.216828) (xy 41.67157 -252.272341) (xy 41.726966 -252.33323) (xy 41.776501 -252.398976)
			(xy 41.819753 -252.469015) (xy 41.856351 -252.54275) (xy 41.885983 -252.61955) (xy 41.908395 -252.698758)
			(xy 41.91635 -252.739144) (xy 41.918742 -252.74924) (xy 41.930255 -252.766475) (xy 41.947625 -252.777785)
			(xy 41.957752 -252.780038) (xy 41.998652 -252.787536) (xy 42.078971 -252.809074) (xy 42.156928 -252.838016)
			(xy 42.231844 -252.874109) (xy 42.303062 -252.917039) (xy 42.369962 -252.966429) (xy 42.431959 -253.021849)
			(xy 42.488512 -253.082815) (xy 42.539126 -253.148793) (xy 42.58336 -253.219209) (xy 42.620828 -253.293446)
			(xy 42.651201 -253.370858) (xy 42.674215 -253.450766) (xy 42.689669 -253.532474) (xy 42.697428 -253.615268)
			(xy 42.697908 -253.656846) (xy 42.697351 -253.702303) (xy 42.68807 -253.792743) (xy 42.669611 -253.881764)
			(xy 42.642165 -253.968436) (xy 42.60602 -254.051857) (xy 42.561552 -254.131154) (xy 42.535856 -254.168656)
			(xy 42.530879 -254.176476) (xy 42.52631 -254.194422) (xy 42.52841 -254.212822) (xy 42.5323 -254.221234)
			(xy 42.555504 -254.26793) (xy 42.592046 -254.365594) (xy 42.605198 -254.416052) (xy 42.60846 -254.426998)
			(xy 42.622994 -254.444587) (xy 42.633138 -254.449834) (xy 42.670279 -254.467807) (xy 42.741398 -254.509651)
			(xy 42.808337 -254.557901) (xy 42.870519 -254.612143) (xy 42.927411 -254.671911) (xy 42.978523 -254.736691)
			(xy 43.023415 -254.805927) (xy 43.061703 -254.879022) (xy 43.093056 -254.955349) (xy 43.105578 -254.994664)
			(xy 43.109388 -255.007618) (xy 43.128946 -255.02616) (xy 43.240706 -255.052576) (xy 43.266614 -255.044956)
			(xy 43.276012 -255.035304) (xy 43.306541 -255.004266) (xy 43.372662 -254.947622) (xy 43.444001 -254.897711)
			(xy 43.519876 -254.855009) (xy 43.599561 -254.819926) (xy 43.682292 -254.792797) (xy 43.767278 -254.773881)
			(xy 43.810428 -254.768096) (xy 43.822874 -254.766572) (xy 43.843448 -254.752094) (xy 43.893486 -254.654812)
			(xy 43.893232 -254.629666) (xy 43.887136 -254.61849) (xy 43.866296 -254.579217) (xy 43.831711 -254.497305)
			(xy 43.805467 -254.412352) (xy 43.787825 -254.325206) (xy 43.778961 -254.236735) (xy 43.778424 -254.192278)
			(xy 43.778831 -254.151174) (xy 43.786419 -254.069315) (xy 43.801527 -253.988507) (xy 43.824026 -253.909437)
			(xy 43.853726 -253.83278) (xy 43.890371 -253.75919) (xy 43.933651 -253.689296) (xy 43.983195 -253.623694)
			(xy 44.03858 -253.562942) (xy 44.099335 -253.50756) (xy 44.164941 -253.45802) (xy 44.234838 -253.414745)
			(xy 44.308429 -253.378104) (xy 44.385088 -253.348409) (xy 44.464159 -253.325914) (xy 44.544969 -253.310811)
			(xy 44.626828 -253.303229) (xy 44.667932 -253.30277) (xy 44.706701 -253.303206) (xy 44.783945 -253.309951)
			(xy 44.860309 -253.323394) (xy 44.935212 -253.343433) (xy 45.008087 -253.369918) (xy 45.078379 -253.402646)
			(xy 45.112178 -253.421642) (xy 45.1231 -253.427992) (xy 45.147738 -253.429008) (xy 45.24629 -253.382018)
			(xy 45.261022 -253.362206) (xy 45.263054 -253.34976) (xy 45.269518 -253.312268) (xy 45.288032 -253.238468)
			(xy 45.312785 -253.166521) (xy 45.327824 -253.131574) (xy 45.331644 -253.121634) (xy 45.331644 -253.100366)
			(xy 45.327824 -253.090426) (xy 45.309581 -253.047763) (xy 45.281036 -252.959471) (xy 45.261842 -252.868686)
			(xy 45.252209 -252.776396) (xy 45.251624 -252.73) (xy 45.252052 -252.688896) (xy 45.259638 -252.607038)
			(xy 45.274744 -252.52623) (xy 45.297241 -252.44716) (xy 45.326939 -252.370504) (xy 45.363583 -252.296914)
			(xy 45.406861 -252.22702) (xy 45.456404 -252.161417) (xy 45.511788 -252.100665) (xy 45.572542 -252.045283)
			(xy 45.638146 -251.995743) (xy 45.708042 -251.952468) (xy 45.781633 -251.915826) (xy 45.858291 -251.886131)
			(xy 45.937361 -251.863636) (xy 46.01817 -251.848533) (xy 46.100028 -251.840951) (xy 46.141132 -251.840492)
			(xy 46.187527 -251.841099) (xy 46.279815 -251.850737) (xy 46.370598 -251.869926) (xy 46.458893 -251.898457)
			(xy 46.501558 -251.916692) (xy 46.511498 -251.920512) (xy 46.532766 -251.920512) (xy 46.542706 -251.916692)
			(xy 46.585364 -251.898437) (xy 46.673658 -251.869895) (xy 46.764444 -251.850705) (xy 46.856736 -251.841075)
			(xy 46.903132 -251.840492) (xy 46.949527 -251.841099) (xy 47.041815 -251.850737) (xy 47.132598 -251.869926)
			(xy 47.220893 -251.898457) (xy 47.263558 -251.916692) (xy 47.273498 -251.920512) (xy 47.294766 -251.920512)
			(xy 47.304706 -251.916692) (xy 47.347364 -251.898437) (xy 47.435658 -251.869895) (xy 47.526444 -251.850705)
			(xy 47.618736 -251.841075) (xy 47.665132 -251.840492) (xy 47.70342 -251.840929) (xy 47.77971 -251.84755)
			(xy 47.85515 -251.860696) (xy 47.929182 -251.880272) (xy 47.96536 -251.892816) (xy 47.973798 -251.895458)
			(xy 47.991466 -251.895458) (xy 47.999904 -251.892816) (xy 48.036076 -251.88025) (xy 48.110106 -251.860656)
			(xy 48.185548 -251.847508) (xy 48.261842 -251.840901) (xy 48.300132 -251.840492) (xy 48.341235 -251.840936)
			(xy 48.42309 -251.848524) (xy 48.503896 -251.863632) (xy 48.582963 -251.886131) (xy 48.659617 -251.915829)
			(xy 48.733204 -251.952474) (xy 48.803096 -251.995751) (xy 48.868697 -252.045293) (xy 48.929447 -252.100676)
			(xy 48.984828 -252.161428) (xy 49.034367 -252.22703) (xy 49.077642 -252.296924) (xy 49.114284 -252.370512)
			(xy 49.143979 -252.447167) (xy 49.166476 -252.526235) (xy 49.181581 -252.607042) (xy 49.189165 -252.688897)
			(xy 49.18964 -252.73) (xy 49.189063 -252.776396) (xy 49.179417 -252.868684) (xy 49.16022 -252.959468)
			(xy 49.131679 -253.047762) (xy 49.11344 -253.090426) (xy 49.109622 -253.100366) (xy 49.109622 -253.121634)
			(xy 49.11344 -253.131574) (xy 49.131687 -253.174235) (xy 49.16023 -253.262528) (xy 49.179422 -253.353313)
			(xy 49.189055 -253.445604) (xy 49.18964 -253.492) (xy 49.189133 -253.533102) (xy 49.181549 -253.614954)
			(xy 49.166444 -253.695758) (xy 49.143949 -253.774823) (xy 49.114254 -253.851475) (xy 49.077614 -253.925061)
			(xy 49.034341 -253.994952) (xy 48.984803 -254.060552) (xy 48.929424 -254.121302) (xy 48.868677 -254.176683)
			(xy 48.803078 -254.226223) (xy 48.733189 -254.269499) (xy 48.659604 -254.306141) (xy 48.582953 -254.335839)
			(xy 48.503889 -254.358337) (xy 48.423086 -254.373444) (xy 48.341234 -254.381032) (xy 48.300132 -254.381508)
			(xy 48.261844 -254.381082) (xy 48.185553 -254.374458) (xy 48.110114 -254.361308) (xy 48.036081 -254.341729)
			(xy 47.999904 -254.329184) (xy 47.991466 -254.326542) (xy 47.973798 -254.326542) (xy 47.96536 -254.329184)
			(xy 47.929192 -254.34176) (xy 47.85516 -254.361351) (xy 47.779717 -254.374497) (xy 47.703422 -254.3811)
			(xy 47.665132 -254.381508) (xy 47.618737 -254.380914) (xy 47.526449 -254.371272) (xy 47.435665 -254.352079)
			(xy 47.347371 -254.323544) (xy 47.304706 -254.305308) (xy 47.294766 -254.301488) (xy 47.273498 -254.301488)
			(xy 47.263558 -254.305308) (xy 47.220891 -254.323542) (xy 47.132601 -254.352089) (xy 47.041817 -254.371285)
			(xy 46.949528 -254.380921) (xy 46.903132 -254.381508) (xy 46.856737 -254.380914) (xy 46.764449 -254.371272)
			(xy 46.673665 -254.352079) (xy 46.585371 -254.323544) (xy 46.542706 -254.305308) (xy 46.532766 -254.301488)
			(xy 46.511498 -254.301488) (xy 46.501558 -254.305308) (xy 46.458891 -254.323542) (xy 46.370601 -254.352089)
			(xy 46.279817 -254.371285) (xy 46.187528 -254.380921) (xy 46.141132 -254.381508) (xy 46.102363 -254.381091)
			(xy 46.025118 -254.374343) (xy 45.948754 -254.360897) (xy 45.87385 -254.340854) (xy 45.800976 -254.314366)
			(xy 45.730684 -254.281634) (xy 45.696886 -254.262636) (xy 45.685964 -254.256286) (xy 45.661326 -254.25527)
			(xy 45.562774 -254.30226) (xy 45.548042 -254.322072) (xy 45.54601 -254.334518) (xy 45.538998 -254.374872)
			(xy 45.5185 -254.454179) (xy 45.490798 -254.531267) (xy 45.456128 -254.605481) (xy 45.414783 -254.676194)
			(xy 45.367113 -254.742808) (xy 45.313522 -254.804757) (xy 45.254463 -254.861518) (xy 45.190437 -254.91261)
			(xy 45.121985 -254.9576) (xy 45.049687 -254.996108) (xy 44.974156 -255.027807) (xy 44.896031 -255.052429)
			(xy 44.815974 -255.069766) (xy 44.775374 -255.075182) (xy 44.762928 -255.076706) (xy 44.742354 -255.091184)
			(xy 44.692316 -255.188466) (xy 44.69257 -255.213612) (xy 44.698666 -255.224788) (xy 44.71543 -255.257046)
			(xy 44.72051 -255.26746) (xy 44.738544 -255.281684) (xy 44.837858 -255.30429) (xy 44.86021 -255.29921)
			(xy 44.8691 -255.292098) (xy 44.902666 -255.266419) (xy 44.97383 -255.220824) (xy 45.048997 -255.182182)
			(xy 45.127489 -255.150841) (xy 45.2086 -255.127086) (xy 45.291598 -255.111128) (xy 45.375735 -255.103113)
			(xy 45.417994 -255.102614) (xy 45.460344 -255.103058) (xy 45.544662 -255.111109) (xy 45.627832 -255.127138)
			(xy 45.709102 -255.151) (xy 45.787736 -255.18248) (xy 45.863022 -255.221292) (xy 45.934277 -255.267085)
			(xy 46.000856 -255.319443) (xy 46.062157 -255.377893) (xy 46.117625 -255.441906) (xy 46.166757 -255.510901)
			(xy 46.209107 -255.584254) (xy 46.244293 -255.6613) (xy 46.271996 -255.741343) (xy 46.291965 -255.823656)
			(xy 46.30402 -255.907495) (xy 46.30805 -255.9921) (xy 46.30402 -256.076705) (xy 46.291965 -256.160544)
			(xy 46.271996 -256.242857) (xy 46.244293 -256.3229) (xy 46.209107 -256.399946) (xy 46.166757 -256.473299)
			(xy 46.117625 -256.542294) (xy 46.062157 -256.606307) (xy 46.000856 -256.664757) (xy 45.934277 -256.717115)
			(xy 45.863022 -256.762908) (xy 45.787736 -256.80172) (xy 45.709102 -256.8332) (xy 45.627832 -256.857062)
			(xy 45.544662 -256.873091) (xy 45.460344 -256.881142) (xy 45.417994 -256.88163) (xy 45.376771 -256.881171)
			(xy 45.294677 -256.87355) (xy 45.21364 -256.858364) (xy 45.134357 -256.835743) (xy 45.057508 -256.805882)
			(xy 44.983752 -256.769038) (xy 44.913722 -256.725525) (xy 44.84802 -256.675719) (xy 44.787209 -256.620046)
			(xy 44.731811 -256.558983) (xy 44.682302 -256.493056) (xy 44.639107 -256.422831) (xy 44.620434 -256.386076)
			(xy 44.615354 -256.375662) (xy 44.59732 -256.361438) (xy 44.498006 -256.338832) (xy 44.475654 -256.343912)
			(xy 44.466764 -256.351024) (xy 44.433202 -256.376708) (xy 44.362038 -256.422305) (xy 44.286871 -256.460947)
			(xy 44.208377 -256.492287) (xy 44.127266 -256.516042) (xy 44.044267 -256.531998) (xy 43.960129 -256.54001)
			(xy 43.91787 -256.540508) (xy 43.877051 -256.540043) (xy 43.795759 -256.532541) (xy 43.715496 -256.51762)
			(xy 43.636939 -256.495406) (xy 43.560748 -256.466087) (xy 43.487564 -256.429909) (xy 43.452542 -256.408936)
			(xy 43.444176 -256.404344) (xy 43.425388 -256.401075) (xy 43.415966 -256.402586) (xy 43.36669 -256.412238)
			(xy 43.363642 -256.416302) (xy 43.37812 -256.469134) (xy 43.381476 -256.479559) (xy 43.395424 -256.496413)
			(xy 43.405044 -256.501646) (xy 43.442159 -256.520198) (xy 43.513131 -256.563198) (xy 43.579789 -256.612622)
			(xy 43.641554 -256.668039) (xy 43.697889 -256.728968) (xy 43.748303 -256.79488) (xy 43.792359 -256.865201)
			(xy 43.829673 -256.93932) (xy 43.859922 -257.016592) (xy 43.882841 -257.096346) (xy 43.898233 -257.177888)
			(xy 43.905962 -257.260509) (xy 43.90644 -257.302) (xy 43.905936 -257.344348) (xy 43.897885 -257.428662)
			(xy 43.881856 -257.511828) (xy 43.857995 -257.593095) (xy 43.826516 -257.671725) (xy 43.787705 -257.747006)
			(xy 43.741915 -257.818258) (xy 43.689559 -257.884834) (xy 43.631111 -257.946132) (xy 43.567101 -258.001597)
			(xy 43.498109 -258.050726) (xy 43.424759 -258.093075) (xy 43.347716 -258.128259) (xy 43.267677 -258.155961)
			(xy 43.185368 -258.175929) (xy 43.101533 -258.187982) (xy 43.016932 -258.192013) (xy 42.932331 -258.187982)
			(xy 42.848496 -258.175929) (xy 42.766187 -258.155961) (xy 42.686148 -258.128259) (xy 42.609105 -258.093075)
			(xy 42.535755 -258.050726) (xy 42.466763 -258.001597) (xy 42.402753 -257.946132) (xy 42.344305 -257.884834)
			(xy 42.291949 -257.818258) (xy 42.246159 -257.747006) (xy 42.207348 -257.671725) (xy 42.175869 -257.593095)
			(xy 42.152008 -257.511828) (xy 42.135979 -257.428662) (xy 42.127928 -257.344348) (xy 42.127424 -257.302)
			(xy 42.12788 -257.261806) (xy 42.135114 -257.181743) (xy 42.14954 -257.10266) (xy 42.171042 -257.0252)
			(xy 42.199444 -256.949996) (xy 42.216578 -256.913634) (xy 42.223182 -256.900426) (xy 42.21988 -256.871216)
			(xy 42.143934 -256.776474) (xy 42.116248 -256.767076) (xy 42.10177 -256.770378) (xy 42.051214 -256.781662)
			(xy 41.948333 -256.793755) (xy 41.896538 -256.794508) (xy 41.855435 -256.794012) (xy 41.773581 -256.78643)
			(xy 41.692775 -256.771328) (xy 41.613707 -256.748834) (xy 41.537052 -256.719141) (xy 41.463464 -256.682501)
			(xy 41.393571 -256.639228) (xy 41.327969 -256.58969) (xy 41.267217 -256.53431) (xy 41.211835 -256.473561)
			(xy 41.162294 -256.407961) (xy 41.119017 -256.338069) (xy 41.082375 -256.264483) (xy 41.052678 -256.187829)
			(xy 41.030181 -256.108762) (xy 41.015075 -256.027957) (xy 41.00749 -255.946103) (xy 41.00703 -255.905)
			(xy 41.007569 -255.859753) (xy 41.016763 -255.769727) (xy 41.035047 -255.681098) (xy 41.062232 -255.594784)
			(xy 41.098037 -255.511674) (xy 41.142092 -255.432627) (xy 41.167558 -255.395222) (xy 41.17258 -255.387339)
			(xy 41.177151 -255.369235) (xy 41.176448 -255.359916) (xy 41.172892 -255.330198) (xy 41.171396 -255.321004)
			(xy 41.162671 -255.304562) (xy 41.155874 -255.298194) (xy 41.124485 -255.270108) (xy 41.066625 -255.20889)
			(xy 41.01481 -255.142477) (xy 40.969504 -255.071465) (xy 40.931113 -254.996488) (xy 40.89998 -254.918218)
			(xy 40.876384 -254.837355) (xy 40.860537 -254.754625) (xy 40.85258 -254.670767) (xy 40.85209 -254.62865)
			(xy 40.852645 -254.583193) (xy 40.861926 -254.492753) (xy 40.880386 -254.403732) (xy 40.907832 -254.317059)
			(xy 40.943978 -254.233639) (xy 40.988446 -254.154342) (xy 41.014142 -254.11684) (xy 41.019122 -254.109022)
			(xy 41.02369 -254.091075) (xy 41.021589 -254.072674) (xy 41.017698 -254.064262) (xy 40.998268 -254.025416)
			(xy 40.966167 -253.944702) (xy 40.942069 -253.861249) (xy 40.933624 -253.818644) (xy 40.931258 -253.80854)
			(xy 40.919734 -253.791304) (xy 40.902353 -253.779999) (xy 40.892222 -253.77775) (xy 40.851305 -253.770295)
			(xy 40.770966 -253.748756) (xy 40.692991 -253.719806) (xy 40.618061 -253.683699) (xy 40.546832 -253.64075)
			(xy 40.479927 -253.591335) (xy 40.41793 -253.535886) (xy 40.389302 -253.505716) (xy 40.381428 -253.49708)
			(xy 40.360092 -253.488698) (xy 40.256968 -253.496826) (xy 40.237156 -253.508256) (xy 40.230552 -253.518162)
			(xy 40.205844 -253.55402) (xy 40.150426 -253.621198) (xy 40.088707 -253.682638) (xy 40.021278 -253.737751)
			(xy 39.948785 -253.786009) (xy 39.871922 -253.82695) (xy 39.791425 -253.860182) (xy 39.708066 -253.885387)
			(xy 39.622642 -253.902323) (xy 39.535971 -253.910828) (xy 39.492428 -253.911354) (xy 39.450079 -253.910858)
			(xy 39.365766 -253.902807) (xy 39.282599 -253.886778) (xy 39.201333 -253.862916) (xy 39.122702 -253.831437)
			(xy 39.047421 -253.792626) (xy 38.976169 -253.746835) (xy 38.909592 -253.694479) (xy 38.848294 -253.636031)
			(xy 38.792829 -253.572021) (xy 38.7437 -253.503029) (xy 38.701352 -253.429679) (xy 38.666167 -253.352635)
			(xy 38.638465 -253.272596) (xy 38.618497 -253.190286) (xy 38.606444 -253.106451) (xy 38.602413 -253.02185)
			(xy 38.318467 -253.02185) (xy 38.304915 -253.09551) (xy 38.283097 -253.173447) (xy 38.254286 -253.24908)
			(xy 38.218721 -253.32178) (xy 38.176696 -253.390948) (xy 38.128558 -253.45601) (xy 38.074707 -253.516428)
			(xy 38.015589 -253.571703) (xy 37.983922 -253.596902) (xy 37.976078 -253.603632) (xy 37.966125 -253.621728)
			(xy 37.964618 -253.631954) (xy 37.960317 -253.671237) (xy 37.945646 -253.748893) (xy 37.92414 -253.82494)
			(xy 37.895969 -253.898779) (xy 37.861355 -253.969825) (xy 37.820572 -254.037519) (xy 37.773942 -254.101326)
			(xy 37.74821 -254.131318) (xy 37.740336 -254.140208) (xy 37.73424 -254.163068) (xy 37.755322 -254.265938)
			(xy 37.7698 -254.284734) (xy 37.780722 -254.289814) (xy 37.818075 -254.308263) (xy 37.889499 -254.351156)
			(xy 37.956601 -254.400539) (xy 38.018792 -254.45598) (xy 38.075527 -254.516992) (xy 38.126309 -254.583041)
			(xy 38.170694 -254.653548) (xy 38.208293 -254.727896) (xy 38.238776 -254.805434) (xy 38.261876 -254.885482)
			(xy 38.277391 -254.967339) (xy 38.285186 -255.050289) (xy 38.285674 -255.091946) (xy 38.285273 -255.130737)
			(xy 38.278538 -255.208025) (xy 38.265097 -255.284433) (xy 38.245052 -255.359381) (xy 38.218556 -255.432297)
			(xy 38.18581 -255.502629) (xy 38.166802 -255.536446) (xy 38.160452 -255.547114) (xy 38.159182 -255.57099)
			(xy 38.202362 -255.668526) (xy 38.220904 -255.683766) (xy 38.232842 -255.686306) (xy 38.274736 -255.696086)
			(xy 38.35657 -255.722636) (xy 38.435459 -255.756962) (xy 38.510666 -255.798745) (xy 38.541986 -255.820348)
			(xy 38.952928 -255.820348) (xy 38.952928 -255.735652) (xy 38.960979 -255.651338) (xy 38.977008 -255.568172)
			(xy 39.000869 -255.486905) (xy 39.032348 -255.408275) (xy 39.071159 -255.332994) (xy 39.116949 -255.261742)
			(xy 39.169305 -255.195166) (xy 39.227753 -255.133868) (xy 39.291763 -255.078403) (xy 39.360755 -255.029274)
			(xy 39.434105 -254.986925) (xy 39.511148 -254.951741) (xy 39.591187 -254.924039) (xy 39.673496 -254.904071)
			(xy 39.757331 -254.892018) (xy 39.841932 -254.887988) (xy 39.926533 -254.892018) (xy 40.010368 -254.904071)
			(xy 40.092677 -254.924039) (xy 40.172716 -254.951741) (xy 40.249759 -254.986925) (xy 40.323109 -255.029274)
			(xy 40.392101 -255.078403) (xy 40.456111 -255.133868) (xy 40.514559 -255.195166) (xy 40.566915 -255.261742)
			(xy 40.612705 -255.332994) (xy 40.651516 -255.408275) (xy 40.682995 -255.486905) (xy 40.706856 -255.568172)
			(xy 40.722885 -255.651338) (xy 40.730936 -255.735652) (xy 40.73144 -255.778) (xy 40.730936 -255.820348)
			(xy 40.722885 -255.904662) (xy 40.706856 -255.987828) (xy 40.682995 -256.069095) (xy 40.651516 -256.147725)
			(xy 40.612705 -256.223006) (xy 40.566915 -256.294258) (xy 40.514559 -256.360834) (xy 40.456111 -256.422132)
			(xy 40.392101 -256.477597) (xy 40.323109 -256.526726) (xy 40.249759 -256.569075) (xy 40.172716 -256.604259)
			(xy 40.092677 -256.631961) (xy 40.010368 -256.651929) (xy 39.926533 -256.663982) (xy 39.841932 -256.668013)
			(xy 39.757331 -256.663982) (xy 39.673496 -256.651929) (xy 39.591187 -256.631961) (xy 39.511148 -256.604259)
			(xy 39.434105 -256.569075) (xy 39.360755 -256.526726) (xy 39.291763 -256.477597) (xy 39.227753 -256.422132)
			(xy 39.169305 -256.360834) (xy 39.116949 -256.294258) (xy 39.071159 -256.223006) (xy 39.032348 -256.147725)
			(xy 39.000869 -256.069095) (xy 38.977008 -255.987828) (xy 38.960979 -255.904662) (xy 38.952928 -255.820348)
			(xy 38.541986 -255.820348) (xy 38.581487 -255.847594) (xy 38.647261 -255.903051) (xy 38.707373 -255.9646)
			(xy 38.761263 -256.031665) (xy 38.808426 -256.10362) (xy 38.848421 -256.179792) (xy 38.880876 -256.259469)
			(xy 38.905486 -256.341908) (xy 38.922022 -256.426338) (xy 38.93033 -256.511969) (xy 38.930834 -256.554986)
			(xy 38.93032 -256.596088) (xy 38.922737 -256.67794) (xy 38.907633 -256.758744) (xy 38.885139 -256.837809)
			(xy 38.855445 -256.914461) (xy 38.818806 -256.988047) (xy 38.775533 -257.057939) (xy 38.725996 -257.123539)
			(xy 38.670617 -257.184289) (xy 38.60987 -257.23967) (xy 38.544272 -257.28921) (xy 38.474382 -257.332486)
			(xy 38.400798 -257.369129) (xy 38.324147 -257.398826) (xy 38.245082 -257.421324) (xy 38.16428 -257.436431)
			(xy 38.082427 -257.444018) (xy 38.041326 -257.444494) (xy 37.999922 -257.444029) (xy 37.917473 -257.436318)
			(xy 37.836098 -257.420977) (xy 37.7565 -257.398141) (xy 37.679369 -257.368006) (xy 37.605373 -257.330834)
			(xy 37.535151 -257.286946) (xy 37.469312 -257.236722) (xy 37.408425 -257.180596) (xy 37.353017 -257.119056)
			(xy 37.303569 -257.052632) (xy 37.260507 -256.9819) (xy 37.224204 -256.907473) (xy 37.194976 -256.829995)
			(xy 37.183568 -256.79019) (xy 37.1805 -256.780615) (xy 37.168086 -256.764815) (xy 37.150568 -256.754971)
			(xy 37.140642 -256.75336) (xy 37.098008 -256.74766) (xy 37.014011 -256.729106) (xy 36.932197 -256.702532)
			(xy 36.85333 -256.668187) (xy 36.778146 -256.626389) (xy 36.707347 -256.577531) (xy 36.641593 -256.522068)
			(xy 36.5815 -256.460518) (xy 36.527628 -256.393455) (xy 36.480479 -256.321506) (xy 36.440495 -256.245342)
			(xy 36.408048 -256.165675) (xy 36.383441 -256.083248) (xy 36.366905 -255.998831) (xy 36.358593 -255.913213)
			(xy 36.358068 -255.870202) (xy 36.358523 -255.830577) (xy 36.365578 -255.75164) (xy 36.379624 -255.673644)
			(xy 36.400548 -255.597205) (xy 36.428186 -255.522929) (xy 36.462319 -255.451405) (xy 36.502675 -255.383199)
			(xy 36.525454 -255.350772) (xy 36.531517 -255.341491) (xy 36.535714 -255.319743) (xy 36.533582 -255.308862)
			(xy 36.525023 -255.273349) (xy 36.513053 -255.201281) (xy 36.507038 -255.128474) (xy 36.506658 -255.091946)
			(xy 36.507103 -255.051915) (xy 36.514295 -254.972175) (xy 36.528624 -254.893405) (xy 36.549975 -254.816242)
			(xy 36.578175 -254.74131) (xy 36.612996 -254.669216) (xy 36.654155 -254.600543) (xy 36.70132 -254.535847)
			(xy 36.727384 -254.50546) (xy 36.735258 -254.49657) (xy 36.741354 -254.47371) (xy 36.720272 -254.37084)
			(xy 36.705794 -254.352044) (xy 36.694872 -254.346964) (xy 36.658207 -254.32891) (xy 36.588052 -254.286973)
			(xy 36.522041 -254.238775) (xy 36.460731 -254.184724) (xy 36.40464 -254.125275) (xy 36.35424 -254.06093)
			(xy 36.309957 -253.992231) (xy 36.272165 -253.919759) (xy 36.241182 -253.844125) (xy 36.228782 -253.805182)
			(xy 36.224972 -253.792228) (xy 36.205414 -253.773686) (xy 36.093654 -253.74727) (xy 36.067746 -253.75489)
			(xy 36.058348 -253.764542) (xy 36.027843 -253.795605) (xy 35.961717 -253.852245) (xy 35.890373 -253.902153)
			(xy 35.814494 -253.944851) (xy 35.734806 -253.979931) (xy 35.652072 -254.007056) (xy 35.567083 -254.025967)
			(xy 35.523932 -254.03175) (xy 35.511486 -254.033274) (xy 35.490912 -254.047752) (xy 35.440874 -254.145034)
			(xy 35.441128 -254.17018) (xy 35.447224 -254.181356) (xy 35.46804 -254.220642) (xy 35.50263 -254.30255)
			(xy 35.528879 -254.387499) (xy 35.546526 -254.474643) (xy 35.555396 -254.563112) (xy 35.555936 -254.607568)
			(xy 35.555432 -254.649916) (xy 35.547381 -254.73423) (xy 35.531352 -254.817396) (xy 35.507491 -254.898663)
			(xy 35.476012 -254.977293) (xy 35.437201 -255.052574) (xy 35.391411 -255.123826) (xy 35.339055 -255.190402)
			(xy 35.280607 -255.2517) (xy 35.216597 -255.307165) (xy 35.147605 -255.356294) (xy 35.074255 -255.398643)
			(xy 34.997212 -255.433827) (xy 34.917173 -255.461529) (xy 34.834864 -255.481497) (xy 34.751029 -255.49355)
			(xy 34.666428 -255.497581) (xy 34.581827 -255.49355) (xy 34.497992 -255.481497) (xy 34.415683 -255.461529)
			(xy 34.335644 -255.433827) (xy 34.258601 -255.398643) (xy 34.185251 -255.356294) (xy 34.116259 -255.307165)
			(xy 34.052249 -255.2517) (xy 33.993801 -255.190402) (xy 33.941445 -255.123826) (xy 33.895655 -255.052574)
			(xy 33.856844 -254.977293) (xy 33.825365 -254.898663) (xy 33.801504 -254.817396) (xy 33.785475 -254.73423)
			(xy 33.777424 -254.649916) (xy 33.77692 -254.607568) (xy 33.777468 -254.56458) (xy 33.785776 -254.479005)
			(xy 33.802302 -254.394631) (xy 33.826891 -254.312245) (xy 33.859314 -254.232616) (xy 33.899269 -254.156487)
			(xy 33.946382 -254.084568) (xy 34.000215 -254.01753) (xy 34.060264 -253.955998) (xy 34.12597 -253.900548)
			(xy 34.19672 -253.851695) (xy 34.271852 -253.809897) (xy 34.350667 -253.775542) (xy 34.432429 -253.748952)
			(xy 34.516375 -253.730375) (xy 34.558986 -253.724664) (xy 34.571432 -253.72314) (xy 34.592006 -253.708662)
			(xy 34.642044 -253.61138) (xy 34.64179 -253.586234) (xy 34.635694 -253.575058) (xy 34.61893 -253.5428)
			(xy 34.61385 -253.532386) (xy 34.595816 -253.518162) (xy 34.496502 -253.495556) (xy 34.47415 -253.500636)
			(xy 34.46526 -253.507748) (xy 34.431702 -253.533437) (xy 34.360537 -253.579033) (xy 34.285369 -253.617675)
			(xy 34.206875 -253.649014) (xy 34.125763 -253.672768) (xy 34.042764 -253.688723) (xy 33.958625 -253.696735)
			(xy 33.916366 -253.697232) (xy 33.874018 -253.69672) (xy 33.789705 -253.688669) (xy 33.706539 -253.67264)
			(xy 33.625274 -253.648778) (xy 33.546644 -253.617299) (xy 33.471363 -253.578489) (xy 33.400112 -253.532698)
			(xy 33.333537 -253.480342) (xy 33.272239 -253.421895) (xy 33.216775 -253.357885) (xy 33.167646 -253.288894)
			(xy 33.125298 -253.215544) (xy 33.090114 -253.138502) (xy 33.062413 -253.058464) (xy 33.042445 -252.976155)
			(xy 33.030392 -252.89232) (xy 33.026361 -252.80772) (xy 30.644891 -252.80772) (xy 30.603745 -252.821961)
			(xy 30.521436 -252.841929) (xy 30.437601 -252.853982) (xy 30.353 -252.858013) (xy 30.268399 -252.853982)
			(xy 30.184564 -252.841929) (xy 30.102255 -252.821961) (xy 30.022216 -252.794259) (xy 29.945173 -252.759075)
			(xy 29.871823 -252.716726) (xy 29.802831 -252.667597) (xy 29.738821 -252.612132) (xy 29.680373 -252.550834)
			(xy 29.628017 -252.484258) (xy 29.582227 -252.413006) (xy 29.543416 -252.337725) (xy 29.511937 -252.259095)
			(xy 29.488076 -252.177828) (xy 29.472047 -252.094662) (xy 29.463996 -252.010348) (xy 13.843567 -252.010348)
			(xy 13.827203 -252.060972) (xy 13.808964 -252.103636) (xy 13.805139 -252.113574) (xy 13.805143 -252.134844)
			(xy 13.808964 -252.144784) (xy 13.815708 -252.160257) (xy 13.828157 -252.191634) (xy 13.833856 -252.207522)
			(xy 13.837412 -252.217428) (xy 13.851636 -252.232668) (xy 13.938758 -252.271022) (xy 13.959586 -252.271022)
			(xy 13.969238 -252.266958) (xy 14.010591 -252.249977) (xy 14.095964 -252.223444) (xy 14.183567 -252.205605)
			(xy 14.272518 -252.196642) (xy 14.317218 -252.196092) (xy 14.363614 -252.196669) (xy 14.455902 -252.206315)
			(xy 14.546686 -252.225513) (xy 14.634979 -252.254053) (xy 14.677644 -252.272292) (xy 14.687584 -252.276112)
			(xy 14.708852 -252.276112) (xy 14.718792 -252.272292) (xy 14.761452 -252.254041) (xy 14.849745 -252.225499)
			(xy 14.940531 -252.206307) (xy 15.032822 -252.196676) (xy 15.079218 -252.196092) (xy 15.125614 -252.196669)
			(xy 15.217902 -252.206315) (xy 15.308686 -252.225513) (xy 15.396979 -252.254053) (xy 15.439644 -252.272292)
			(xy 15.449584 -252.276112) (xy 15.470852 -252.276112) (xy 15.480792 -252.272292) (xy 15.523452 -252.254041)
			(xy 15.611745 -252.225499) (xy 15.702531 -252.206307) (xy 15.794822 -252.196676) (xy 15.841218 -252.196092)
			(xy 15.887614 -252.196669) (xy 15.979902 -252.206315) (xy 16.070686 -252.225513) (xy 16.158979 -252.254053)
			(xy 16.201644 -252.272292) (xy 16.211584 -252.276112) (xy 16.232852 -252.276112) (xy 16.242792 -252.272292)
			(xy 16.285452 -252.254041) (xy 16.373745 -252.225499) (xy 16.464531 -252.206307) (xy 16.556822 -252.196676)
			(xy 16.603218 -252.196092) (xy 16.645567 -252.19658) (xy 16.729882 -252.204631) (xy 16.81305 -252.22066)
			(xy 16.894318 -252.244522) (xy 16.97295 -252.276001) (xy 17.048233 -252.314812) (xy 17.119486 -252.360604)
			(xy 17.186064 -252.412961) (xy 17.247363 -252.47141) (xy 17.302829 -252.535421) (xy 17.351959 -252.604414)
			(xy 17.394308 -252.677765) (xy 17.429493 -252.75481) (xy 17.457196 -252.83485) (xy 17.477164 -252.917161)
			(xy 17.489218 -253.000997) (xy 17.493248 -253.0856) (xy 17.489218 -253.170203) (xy 17.477164 -253.254039)
			(xy 17.457196 -253.33635) (xy 17.429493 -253.41639) (xy 17.394308 -253.493435) (xy 17.351959 -253.566786)
			(xy 17.302829 -253.635779) (xy 17.247363 -253.69979) (xy 17.186064 -253.758239) (xy 17.119486 -253.810596)
			(xy 17.048233 -253.856388) (xy 16.97295 -253.895199) (xy 16.894318 -253.926678) (xy 16.81305 -253.95054)
			(xy 16.729882 -253.966569) (xy 16.645567 -253.97462) (xy 16.603218 -253.975108) (xy 16.556823 -253.974519)
			(xy 16.464534 -253.964876) (xy 16.373751 -253.945681) (xy 16.285457 -253.917145) (xy 16.242792 -253.898908)
			(xy 16.232852 -253.895088) (xy 16.211584 -253.895088) (xy 16.201644 -253.898908) (xy 16.158979 -253.917147)
			(xy 16.070688 -253.945692) (xy 15.979904 -253.964887) (xy 15.887614 -253.974522) (xy 15.841218 -253.975108)
			(xy 15.794823 -253.974519) (xy 15.702534 -253.964876) (xy 15.611751 -253.945681) (xy 15.523457 -253.917145)
			(xy 15.480792 -253.898908) (xy 15.470852 -253.895088) (xy 15.449584 -253.895088) (xy 15.439644 -253.898908)
			(xy 15.396979 -253.917147) (xy 15.308688 -253.945692) (xy 15.217904 -253.964887) (xy 15.125614 -253.974522)
			(xy 15.079218 -253.975108) (xy 15.032823 -253.974519) (xy 14.940534 -253.964876) (xy 14.849751 -253.945681)
			(xy 14.761457 -253.917145) (xy 14.718792 -253.898908) (xy 14.708852 -253.895088) (xy 14.687584 -253.895088)
			(xy 14.677644 -253.898908) (xy 14.634979 -253.917147) (xy 14.546688 -253.945692) (xy 14.455904 -253.964887)
			(xy 14.363614 -253.974522) (xy 14.317218 -253.975108) (xy 14.275144 -253.974676) (xy 14.191373 -253.966722)
			(xy 14.108728 -253.950892) (xy 14.027947 -253.927329) (xy 13.949752 -253.896242) (xy 13.874842 -253.85791)
			(xy 13.803887 -253.812676) (xy 13.73752 -253.760943) (xy 13.676335 -253.703174) (xy 13.62088 -253.639885)
			(xy 13.571648 -253.571642) (xy 13.529082 -253.499054) (xy 13.49356 -253.422772) (xy 13.479018 -253.383288)
			(xy 13.475462 -253.373382) (xy 13.461238 -253.358142) (xy 13.374116 -253.319788) (xy 13.353288 -253.319788)
			(xy 13.343636 -253.323852) (xy 13.302287 -253.340842) (xy 13.216912 -253.367373) (xy 13.129308 -253.385209)
			(xy 13.040357 -253.394169) (xy 12.995656 -253.394718) (xy 12.957368 -253.394284) (xy 12.881078 -253.387662)
			(xy 12.805638 -253.374515) (xy 12.731606 -253.354938) (xy 12.695428 -253.342394) (xy 12.68699 -253.339752)
			(xy 12.669322 -253.339752) (xy 12.660884 -253.342394) (xy 12.624714 -253.354963) (xy 12.550683 -253.374556)
			(xy 12.47524 -253.387704) (xy 12.398946 -253.394309) (xy 12.360656 -253.394718) (xy 12.319553 -253.394275)
			(xy 12.237698 -253.386687) (xy 12.156893 -253.371578) (xy 12.077826 -253.349078) (xy 12.001172 -253.319379)
			(xy 11.927586 -253.282735) (xy 11.857694 -253.239457) (xy 11.792094 -253.189915) (xy 11.731344 -253.134532)
			(xy 11.675963 -253.07378) (xy 11.626424 -253.008178) (xy 11.583149 -252.938285) (xy 11.546507 -252.864697)
			(xy 11.516811 -252.788042) (xy 11.494314 -252.708974) (xy 11.479209 -252.628168) (xy 11.471623 -252.546313)
			(xy 11.471148 -252.50521) (xy 11.147611 -252.50521) (xy 11.15138 -252.517899) (xy 11.167763 -252.601949)
			(xy 11.175995 -252.687184) (xy 11.176508 -252.73) (xy 11.176004 -252.772348) (xy 11.167953 -252.856662)
			(xy 11.151924 -252.939828) (xy 11.128063 -253.021095) (xy 11.096584 -253.099725) (xy 11.057773 -253.175006)
			(xy 11.011983 -253.246258) (xy 10.959627 -253.312834) (xy 10.901179 -253.374132) (xy 10.837169 -253.429597)
			(xy 10.768177 -253.478726) (xy 10.694827 -253.521075) (xy 10.617784 -253.556259) (xy 10.537745 -253.583961)
			(xy 10.455436 -253.603929) (xy 10.371601 -253.615982) (xy 10.287 -253.620013) (xy 10.202399 -253.615982)
			(xy 10.118564 -253.603929) (xy 10.036255 -253.583961) (xy 9.956216 -253.556259) (xy 9.879173 -253.521075)
			(xy 9.805823 -253.478726) (xy 9.736831 -253.429597) (xy 9.672821 -253.374132) (xy 9.614373 -253.312834)
			(xy 9.562017 -253.246258) (xy 9.516227 -253.175006) (xy 9.477416 -253.099725) (xy 9.445937 -253.021095)
			(xy 9.422076 -252.939828) (xy 9.406047 -252.856662) (xy 9.397996 -252.772348) (xy 9.397492 -252.73)
			(xy 9.397937 -252.690957) (xy 9.404794 -252.613173) (xy 9.418438 -252.536289) (xy 9.438764 -252.460895)
			(xy 9.465615 -252.387571) (xy 9.48182 -252.352048) (xy 9.485884 -252.343158) (xy 9.487154 -252.324362)
			(xy 9.459976 -252.23978) (xy 9.448038 -252.225302) (xy 9.439656 -252.220476) (xy 9.402585 -252.199048)
			(xy 9.332321 -252.150101) (xy 9.267085 -252.094629) (xy 9.207481 -252.033146) (xy 9.15406 -251.966221)
			(xy 9.107316 -251.894473) (xy 9.067682 -251.818566) (xy 9.035525 -251.739201) (xy 9.011141 -251.657115)
			(xy 8.994757 -251.573065) (xy 8.986525 -251.48783) (xy 8.986012 -251.445014) (xy 8.507144 -251.445014)
			(xy 8.556091 -251.473274) (xy 8.625083 -251.522403) (xy 8.689093 -251.577868) (xy 8.747541 -251.639166)
			(xy 8.799897 -251.705742) (xy 8.845687 -251.776994) (xy 8.884498 -251.852275) (xy 8.915977 -251.930905)
			(xy 8.939838 -252.012172) (xy 8.955867 -252.095338) (xy 8.963918 -252.179652) (xy 8.964422 -252.222)
			(xy 8.963956 -252.264089) (xy 8.956012 -252.347893) (xy 8.940186 -252.43057) (xy 8.916618 -252.511383)
			(xy 8.885521 -252.589607) (xy 8.847172 -252.664543) (xy 8.801915 -252.735521) (xy 8.750153 -252.801905)
			(xy 8.692351 -252.863102) (xy 8.629026 -252.918563) (xy 8.560744 -252.967793) (xy 8.488116 -253.010352)
			(xy 8.411791 -253.045858) (xy 8.332454 -253.073994) (xy 8.250813 -253.094508) (xy 8.20928 -253.101348)
			(xy 8.193024 -253.103888) (xy 8.16991 -253.126494) (xy 8.147558 -253.254002) (xy 8.161782 -253.283212)
			(xy 8.17626 -253.291086) (xy 8.214209 -253.312244) (xy 8.286217 -253.360873) (xy 8.353139 -253.416294)
			(xy 8.414337 -253.477978) (xy 8.469226 -253.545336) (xy 8.517284 -253.617727) (xy 8.558053 -253.69446)
			(xy 8.591144 -253.774803) (xy 8.61624 -253.857991) (xy 8.633104 -253.94323) (xy 8.641573 -254.029707)
			(xy 8.642096 -254.073152) (xy 8.641602 -254.114255) (xy 8.634021 -254.19611) (xy 8.61892 -254.276916)
			(xy 8.596426 -254.355984) (xy 8.566733 -254.43264) (xy 8.530094 -254.506228) (xy 8.48682 -254.576122)
			(xy 8.437282 -254.641725) (xy 8.381902 -254.702477) (xy 8.321153 -254.757859) (xy 8.255552 -254.8074)
			(xy 8.18566 -254.850676) (xy 8.112073 -254.887319) (xy 8.035419 -254.917015) (xy 7.956351 -254.939511)
			(xy 7.875546 -254.954616) (xy 7.793691 -254.9622) (xy 7.752588 -254.96266) (xy 7.710385 -254.962164)
			(xy 7.626357 -254.954178) (xy 7.543465 -254.938265) (xy 7.462453 -254.914569) (xy 7.384052 -254.883301)
			(xy 7.308967 -254.844745) (xy 7.237874 -254.799246) (xy 7.171412 -254.747215) (xy 7.11018 -254.68912)
			(xy 7.054729 -254.625484) (xy 7.005559 -254.556879) (xy 6.963111 -254.483923) (xy 6.927768 -254.407272)
			(xy 6.899848 -254.327618) (xy 6.889242 -254.286766) (xy 6.886564 -254.277937) (xy 6.876083 -254.262777)
			(xy 6.860941 -254.252272) (xy 6.84307 -254.247764) (xy 6.83387 -254.248412) (xy 6.808247 -254.251246)
			(xy 6.756779 -254.254295) (xy 6.731 -254.254508) (xy 6.690323 -254.254047) (xy 6.60931 -254.246607)
			(xy 6.529314 -254.231804) (xy 6.451003 -254.20976) (xy 6.375031 -254.180661) (xy 6.302032 -254.14475)
			(xy 6.232616 -254.102325) (xy 6.167361 -254.053741) (xy 6.106814 -253.999404) (xy 6.051479 -253.939767)
			(xy 6.001818 -253.875329) (xy 5.958246 -253.806627) (xy 5.939282 -253.770638) (xy 5.934456 -253.762139)
			(xy 5.919751 -253.749294) (xy 5.901303 -253.742901) (xy 5.89153 -253.742952) (xy 5.844286 -253.744222)
			(xy 5.803184 -253.743747) (xy 5.721329 -253.736162) (xy 5.640524 -253.721057) (xy 5.561458 -253.69856)
			(xy 5.484804 -253.668864) (xy 5.411217 -253.632222) (xy 5.341325 -253.588946) (xy 5.275724 -253.539407)
			(xy 5.214974 -253.484026) (xy 5.159593 -253.423276) (xy 5.110054 -253.357675) (xy 5.066778 -253.287783)
			(xy 5.030136 -253.214196) (xy 5.00044 -253.137542) (xy 4.977943 -253.058476) (xy 4.962838 -252.977671)
			(xy 4.955253 -252.895816) (xy 4.954778 -252.854714) (xy 4.955314 -252.8119) (xy 4.963539 -252.726668)
			(xy 4.979913 -252.642621) (xy 5.004286 -252.560535) (xy 5.036432 -252.48117) (xy 5.076053 -252.40526)
			(xy 5.122783 -252.333508) (xy 5.149088 -252.299724) (xy 5.156094 -252.290123) (xy 5.161117 -252.266921)
			(xy 5.15874 -252.255274) (xy 5.151684 -252.226844) (xy 5.140882 -252.169266) (xy 5.13715 -252.140212)
			(xy 5.135563 -252.131065) (xy 5.126899 -252.114667) (xy 5.112983 -252.102408) (xy 5.095624 -252.095882)
			(xy 5.08635 -252.095508) (xy 5.08 -252.095508) (xy 5.037652 -252.095004) (xy 4.953338 -252.086953)
			(xy 4.870172 -252.070924) (xy 4.788905 -252.047063) (xy 4.710275 -252.015584) (xy 4.634994 -251.976773)
			(xy 4.563742 -251.930983) (xy 4.497166 -251.878627) (xy 4.435868 -251.820179) (xy 4.380403 -251.756169)
			(xy 4.331274 -251.687177) (xy 4.288925 -251.613827) (xy 4.253741 -251.536784) (xy 4.226039 -251.456745)
			(xy 4.206071 -251.374436) (xy 4.194018 -251.290601) (xy 4.189988 -251.206) (xy 1.651254 -251.206)
			(xy 1.651254 -251.580904) (xy 1.652778 -251.63145) (xy 1.651254 -251.681996) (xy 1.651254 -252.00864)
			(xy 1.651727 -252.018946) (xy 1.659845 -252.03789) (xy 1.674785 -252.052087) (xy 1.684274 -252.056138)
			(xy 1.78816 -252.095254) (xy 1.818894 -252.08738) (xy 1.829308 -252.075442) (xy 1.857416 -252.044074)
			(xy 1.918633 -251.986216) (xy 1.985044 -251.934402) (xy 2.056054 -251.889096) (xy 2.131028 -251.850703)
			(xy 2.209295 -251.819568) (xy 2.290154 -251.795969) (xy 2.372881 -251.780117) (xy 2.456736 -251.772154)
			(xy 2.498852 -251.771658) (xy 2.539835 -251.772128) (xy 2.621452 -251.77967) (xy 2.702029 -251.794688)
			(xy 2.780884 -251.817056) (xy 2.857346 -251.846582) (xy 2.930768 -251.883017) (xy 3.000526 -251.926051)
			(xy 3.066031 -251.975321) (xy 3.126725 -252.030407) (xy 3.182094 -252.090844) (xy 3.207258 -252.123194)
			(xy 3.213608 -252.131322) (xy 3.230626 -252.141482) (xy 3.321558 -252.154436) (xy 3.340608 -252.149356)
			(xy 3.34899 -252.14326) (xy 3.381869 -252.11937) (xy 3.451239 -252.077014) (xy 3.524185 -252.041164)
			(xy 3.600098 -252.01212) (xy 3.678344 -251.990123) (xy 3.75827 -251.975358) (xy 3.83921 -251.967946)
			(xy 3.87985 -251.967492) (xy 3.920952 -251.967967) (xy 4.002807 -251.975552) (xy 4.083612 -251.990657)
			(xy 4.162679 -252.013153) (xy 4.239333 -252.042849) (xy 4.31292 -252.079491) (xy 4.382812 -252.122766)
			(xy 4.448413 -252.172306) (xy 4.509163 -252.227687) (xy 4.564544 -252.288437) (xy 4.614084 -252.354038)
			(xy 4.657359 -252.42393) (xy 4.694001 -252.497517) (xy 4.723697 -252.574171) (xy 4.746193 -252.653238)
			(xy 4.761298 -252.734043) (xy 4.768883 -252.815898) (xy 4.769358 -252.857) (xy 4.768831 -252.90082)
			(xy 4.760211 -252.988036) (xy 4.74306 -253.073982) (xy 4.717544 -253.157826) (xy 4.68391 -253.238755)
			(xy 4.642484 -253.315987) (xy 4.593666 -253.388772) (xy 4.537931 -253.456407) (xy 4.475817 -253.518235)
			(xy 4.442206 -253.546356) (xy 4.43357 -253.553214) (xy 4.423918 -253.572264) (xy 4.419346 -253.669546)
			(xy 4.42722 -253.689612) (xy 4.435094 -253.697232) (xy 4.466033 -253.728553) (xy 4.522244 -253.796318)
			(xy 4.571487 -253.869304) (xy 4.613279 -253.946797) (xy 4.647212 -254.028039) (xy 4.672954 -254.112236)
			(xy 4.690253 -254.198563) (xy 4.69894 -254.286178) (xy 4.699508 -254.3302) (xy 4.699004 -254.372548)
			(xy 4.690953 -254.456862) (xy 4.674924 -254.540028) (xy 4.651063 -254.621295) (xy 4.619584 -254.699925)
			(xy 4.580773 -254.775206) (xy 4.534983 -254.846458) (xy 4.482627 -254.913034) (xy 4.424179 -254.974332)
			(xy 4.360169 -255.029797) (xy 4.291177 -255.078926) (xy 4.217827 -255.121275) (xy 4.140784 -255.156459)
			(xy 4.060745 -255.184161) (xy 3.978436 -255.204129) (xy 3.894601 -255.216182) (xy 3.81 -255.220213)
			(xy 3.725399 -255.216182) (xy 3.641564 -255.204129) (xy 3.559255 -255.184161) (xy 3.479216 -255.156459)
			(xy 3.402173 -255.121275) (xy 3.328823 -255.078926) (xy 3.259831 -255.029797) (xy 3.195821 -254.974332)
			(xy 3.137373 -254.913034) (xy 3.085017 -254.846458) (xy 3.039227 -254.775206) (xy 3.000416 -254.699925)
			(xy 2.968937 -254.621295) (xy 2.945076 -254.540028) (xy 2.929047 -254.456862) (xy 2.920996 -254.372548)
			(xy 2.920492 -254.3302) (xy 2.921019 -254.28638) (xy 2.929639 -254.199164) (xy 2.94679 -254.113218)
			(xy 2.972306 -254.029374) (xy 3.00594 -253.948445) (xy 3.047366 -253.871213) (xy 3.096184 -253.798428)
			(xy 3.151919 -253.730793) (xy 3.214033 -253.668965) (xy 3.247644 -253.640844) (xy 3.25628 -253.633986)
			(xy 3.265932 -253.614936) (xy 3.270504 -253.517654) (xy 3.26263 -253.497588) (xy 3.254756 -253.489968)
			(xy 3.232468 -253.467539) (xy 3.190771 -253.419997) (xy 3.171444 -253.394972) (xy 3.165094 -253.386844)
			(xy 3.148076 -253.376684) (xy 3.057144 -253.36373) (xy 3.038094 -253.36881) (xy 3.029712 -253.374906)
			(xy 2.996832 -253.398795) (xy 2.927461 -253.441148) (xy 2.854515 -253.476995) (xy 2.778602 -253.506037)
			(xy 2.700357 -253.528032) (xy 2.620431 -253.542797) (xy 2.539491 -253.550208) (xy 2.498852 -253.550674)
			(xy 2.456735 -253.550182) (xy 2.372879 -253.542222) (xy 2.290151 -253.526372) (xy 2.209291 -253.502774)
			(xy 2.131023 -253.471639) (xy 2.056049 -253.433246) (xy 1.985039 -253.387938) (xy 1.918629 -253.336122)
			(xy 1.857413 -253.278261) (xy 1.829308 -253.24689) (xy 1.818894 -253.234952) (xy 1.78816 -253.227078)
			(xy 1.684274 -253.266194) (xy 1.674798 -253.270257) (xy 1.659895 -253.284475) (xy 1.65175 -253.303395)
			(xy 1.651254 -253.313692) (xy 1.651254 -255.27) (xy 9.031986 -255.27) (xy 9.03249 -255.227652) (xy 9.040541 -255.143338)
			(xy 9.05657 -255.060172) (xy 9.080431 -254.978905) (xy 9.11191 -254.900275) (xy 9.150721 -254.824994)
			(xy 9.196511 -254.753742) (xy 9.248867 -254.687166) (xy 9.307315 -254.625868) (xy 9.371325 -254.570403)
			(xy 9.440317 -254.521274) (xy 9.513667 -254.478925) (xy 9.59071 -254.443741) (xy 9.670749 -254.416039)
			(xy 9.753058 -254.396071) (xy 9.836893 -254.384018) (xy 9.921494 -254.379988) (xy 10.006095 -254.384018)
			(xy 10.08993 -254.396071) (xy 10.172239 -254.416039) (xy 10.252278 -254.443741) (xy 10.329321 -254.478925)
			(xy 10.402671 -254.521274) (xy 10.471663 -254.570403) (xy 10.535673 -254.625868) (xy 10.594121 -254.687166)
			(xy 10.646477 -254.753742) (xy 10.692267 -254.824994) (xy 10.731078 -254.900275) (xy 10.762557 -254.978905)
			(xy 10.786418 -255.060172) (xy 10.802447 -255.143338) (xy 10.810498 -255.227652) (xy 10.811002 -255.27)
			(xy 10.810436 -255.31498) (xy 10.801318 -255.404478) (xy 10.783216 -255.492599) (xy 10.756314 -255.578444)
			(xy 10.73912 -255.620012) (xy 10.73531 -255.629156) (xy 10.734802 -255.64846) (xy 10.766806 -255.733296)
			(xy 10.780014 -255.74752) (xy 10.788904 -255.751838) (xy 10.826737 -255.770379) (xy 10.899068 -255.813597)
			(xy 10.966986 -255.863464) (xy 11.029883 -255.919531) (xy 11.087194 -255.981296) (xy 11.138406 -256.048206)
			(xy 11.183059 -256.11966) (xy 11.220753 -256.195017) (xy 11.25115 -256.273601) (xy 11.273977 -256.354709)
			(xy 11.28903 -256.437612) (xy 11.293094 -256.479548) (xy 11.294618 -256.49555) (xy 11.314684 -256.519934)
			(xy 11.436858 -256.554224) (xy 11.46683 -256.544064) (xy 11.476228 -256.53111) (xy 11.505398 -256.492512)
			(xy 11.570821 -256.421233) (xy 11.606784 -256.38887) (xy 11.613766 -256.382172) (xy 11.622514 -256.364931)
			(xy 11.623802 -256.355342) (xy 11.626596 -256.325116) (xy 11.627051 -256.315538) (xy 11.621708 -256.297137)
			(xy 11.616182 -256.289302) (xy 11.590598 -256.255778) (xy 11.545185 -256.184714) (xy 11.506699 -256.109671)
			(xy 11.475488 -256.031324) (xy 11.45183 -255.950374) (xy 11.435939 -255.867549) (xy 11.427956 -255.783592)
			(xy 11.42746 -255.741424) (xy 11.427964 -255.699076) (xy 11.436015 -255.614762) (xy 11.452044 -255.531596)
			(xy 11.475905 -255.450329) (xy 11.507384 -255.371699) (xy 11.546195 -255.296418) (xy 11.591985 -255.225166)
			(xy 11.644341 -255.15859) (xy 11.702789 -255.097292) (xy 11.766799 -255.041827) (xy 11.835791 -254.992698)
			(xy 11.909141 -254.950349) (xy 11.986184 -254.915165) (xy 12.066223 -254.887463) (xy 12.148532 -254.867495)
			(xy 12.232367 -254.855442) (xy 12.316968 -254.851412) (xy 12.401569 -254.855442) (xy 12.485404 -254.867495)
			(xy 12.567713 -254.887463) (xy 12.647752 -254.915165) (xy 12.724795 -254.950349) (xy 12.798145 -254.992698)
			(xy 12.867137 -255.041827) (xy 12.931147 -255.097292) (xy 12.989595 -255.15859) (xy 13.041951 -255.225166)
			(xy 13.087741 -255.296418) (xy 13.126552 -255.371699) (xy 13.158031 -255.450329) (xy 13.181892 -255.531596)
			(xy 13.197921 -255.614762) (xy 13.205972 -255.699076) (xy 13.206476 -255.741424) (xy 13.205921 -255.785266)
			(xy 13.197272 -255.872522) (xy 13.18008 -255.958503) (xy 13.154512 -256.042376) (xy 13.13815 -256.083054)
			(xy 13.133578 -256.094484) (xy 13.135356 -256.118868) (xy 13.192252 -256.210308) (xy 13.213334 -256.222754)
			(xy 13.22578 -256.223516) (xy 13.283438 -256.22885) (xy 13.295884 -256.230628) (xy 13.319252 -256.221992)
			(xy 13.39215 -256.141474) (xy 13.398246 -256.117598) (xy 13.395452 -256.105406) (xy 13.384752 -256.055997)
			(xy 13.3733 -255.955549) (xy 13.372592 -255.905) (xy 13.373182 -255.858767) (xy 13.382743 -255.766798)
			(xy 13.401803 -255.676318) (xy 13.430155 -255.588307) (xy 13.467494 -255.503717) (xy 13.48994 -255.463294)
			(xy 13.495699 -255.452064) (xy 13.496488 -255.426867) (xy 13.491464 -255.415288) (xy 13.473281 -255.378072)
			(xy 13.443134 -255.300916) (xy 13.420286 -255.221294) (xy 13.404934 -255.139893) (xy 13.39721 -255.057418)
			(xy 13.396722 -255.016) (xy 13.397226 -254.973652) (xy 13.405277 -254.889338) (xy 13.421306 -254.806172)
			(xy 13.445167 -254.724905) (xy 13.476646 -254.646275) (xy 13.515457 -254.570994) (xy 13.561247 -254.499742)
			(xy 13.613603 -254.433166) (xy 13.672051 -254.371868) (xy 13.736061 -254.316403) (xy 13.805053 -254.267274)
			(xy 13.878403 -254.224925) (xy 13.955446 -254.189741) (xy 14.035485 -254.162039) (xy 14.117794 -254.142071)
			(xy 14.201629 -254.130018) (xy 14.28623 -254.125988) (xy 14.370831 -254.130018) (xy 14.454666 -254.142071)
			(xy 14.536975 -254.162039) (xy 14.617014 -254.189741) (xy 14.694057 -254.224925) (xy 14.767407 -254.267274)
			(xy 14.836399 -254.316403) (xy 14.900409 -254.371868) (xy 14.958857 -254.433166) (xy 15.011213 -254.499742)
			(xy 15.057003 -254.570994) (xy 15.095814 -254.646275) (xy 15.127293 -254.724905) (xy 15.151154 -254.806172)
			(xy 15.167183 -254.889338) (xy 15.175234 -254.973652) (xy 15.175738 -255.016) (xy 15.174976 -255.05283)
			(xy 15.174969 -255.061935) (xy 15.180596 -255.079236) (xy 15.191918 -255.093477) (xy 15.207505 -255.102861)
			(xy 15.216378 -255.1049) (xy 15.256711 -255.112836) (xy 15.335819 -255.135196) (xy 15.412523 -255.164771)
			(xy 15.44955 -255.182624) (xy 15.457999 -255.186348) (xy 15.476353 -255.188186) (xy 15.485364 -255.18618)
			(xy 15.514066 -255.17856) (xy 15.522857 -255.175831) (xy 15.537835 -255.165156) (xy 15.543276 -255.157732)
			(xy 15.567967 -255.121641) (xy 15.623363 -255.053971) (xy 15.685134 -254.992066) (xy 15.752682 -254.936523)
			(xy 15.825356 -254.887878) (xy 15.902455 -254.846602) (xy 15.983232 -254.813093) (xy 16.066909 -254.787675)
			(xy 16.152676 -254.770593) (xy 16.239706 -254.762012) (xy 16.283432 -254.761492) (xy 16.32605 -254.761999)
			(xy 16.410894 -254.770153) (xy 16.49457 -254.786382) (xy 16.57631 -254.810539) (xy 16.655366 -254.842402)
			(xy 16.731013 -254.881678) (xy 16.802557 -254.928008) (xy 16.869343 -254.980967) (xy 16.900398 -255.010158)
			(xy 16.908018 -255.017524) (xy 16.927576 -255.02489) (xy 17.022826 -255.01981) (xy 17.041622 -255.010412)
			(xy 17.04848 -255.002284) (xy 17.076582 -254.969579) (xy 17.138172 -254.909219) (xy 17.205313 -254.855102)
			(xy 17.277376 -254.807735) (xy 17.353684 -254.767564) (xy 17.433521 -254.734966) (xy 17.516138 -254.710246)
			(xy 17.600759 -254.693636) (xy 17.68659 -254.685292) (xy 17.729708 -254.684784) (xy 17.77081 -254.685259)
			(xy 17.852664 -254.692845) (xy 17.933469 -254.70795) (xy 18.012536 -254.730447) (xy 18.08919 -254.760143)
			(xy 18.162776 -254.796785) (xy 18.232668 -254.840061) (xy 18.298269 -254.8896) (xy 18.359019 -254.944981)
			(xy 18.4144 -255.005731) (xy 18.463939 -255.071332) (xy 18.507215 -255.141224) (xy 18.543857 -255.21481)
			(xy 18.573553 -255.291464) (xy 18.59605 -255.370531) (xy 18.611155 -255.451336) (xy 18.618741 -255.53319)
			(xy 18.619216 -255.574292) (xy 18.619043 -255.600516) (xy 18.615992 -255.652874) (xy 18.61312 -255.67894)
			(xy 18.61185 -255.688592) (xy 18.61693 -255.707388) (xy 18.67027 -255.779016) (xy 18.68678 -255.789176)
			(xy 18.696178 -255.790954) (xy 18.736886 -255.798602) (xy 18.816778 -255.820482) (xy 18.894289 -255.849695)
			(xy 18.96875 -255.885988) (xy 19.039513 -255.929046) (xy 19.105967 -255.978497) (xy 19.167535 -256.033911)
			(xy 19.223685 -256.09481) (xy 19.27393 -256.160666) (xy 19.317834 -256.230907) (xy 19.355018 -256.304926)
			(xy 19.385159 -256.382082) (xy 19.407996 -256.461706) (xy 19.423332 -256.543108) (xy 19.431033 -256.625583)
			(xy 19.431508 -256.667) (xy 19.43104 -256.709426) (xy 19.422957 -256.793892) (xy 19.406865 -256.877204)
			(xy 19.38291 -256.958604) (xy 19.35131 -257.037352) (xy 19.312352 -257.112732) (xy 19.266392 -257.184058)
			(xy 19.213845 -257.250682) (xy 19.184874 -257.28168) (xy 19.177518 -257.290224) (xy 19.170392 -257.311581)
			(xy 19.171158 -257.322828) (xy 19.174129 -257.349271) (xy 19.177308 -257.402392) (xy 19.177508 -257.429)
			(xy 19.177004 -257.471348) (xy 19.168953 -257.555662) (xy 19.152924 -257.638828) (xy 19.129063 -257.720095)
			(xy 19.097584 -257.798725) (xy 19.058773 -257.874006) (xy 19.012983 -257.945258) (xy 18.960627 -258.011834)
			(xy 18.935105 -258.0386) (xy 31.08452 -258.0386) (xy 31.0851 -257.992204) (xy 31.094746 -257.899916)
			(xy 31.113942 -257.809132) (xy 31.142482 -257.720839) (xy 31.16072 -257.678174) (xy 31.16454 -257.668234)
			(xy 31.16454 -257.646966) (xy 31.16072 -257.637026) (xy 31.142477 -257.594363) (xy 31.113932 -257.506071)
			(xy 31.094738 -257.415286) (xy 31.085105 -257.322996) (xy 31.08452 -257.2766) (xy 31.084952 -257.235496)
			(xy 31.092538 -257.153639) (xy 31.107644 -257.072831) (xy 31.130141 -256.993761) (xy 31.159839 -256.917105)
			(xy 31.196483 -256.843515) (xy 31.23976 -256.773621) (xy 31.289303 -256.708018) (xy 31.344687 -256.647267)
			(xy 31.40544 -256.591885) (xy 31.471044 -256.542345) (xy 31.54094 -256.499069) (xy 31.61453 -256.462427)
			(xy 31.691188 -256.432732) (xy 31.770258 -256.410237) (xy 31.851066 -256.395134) (xy 31.932924 -256.387551)
			(xy 31.974028 -256.387092) (xy 32.020423 -256.3877) (xy 32.112711 -256.397338) (xy 32.203494 -256.416526)
			(xy 32.291789 -256.445058) (xy 32.334454 -256.463292) (xy 32.344394 -256.467112) (xy 32.365662 -256.467112)
			(xy 32.375602 -256.463292) (xy 32.41826 -256.445038) (xy 32.506554 -256.416496) (xy 32.59734 -256.397306)
			(xy 32.689632 -256.387675) (xy 32.736028 -256.387092) (xy 32.782423 -256.3877) (xy 32.874711 -256.397338)
			(xy 32.965494 -256.416526) (xy 33.053789 -256.445058) (xy 33.096454 -256.463292) (xy 33.106394 -256.467112)
			(xy 33.127662 -256.467112) (xy 33.137602 -256.463292) (xy 33.18026 -256.445038) (xy 33.268554 -256.416496)
			(xy 33.35934 -256.397306) (xy 33.451632 -256.387675) (xy 33.498028 -256.387092) (xy 33.544423 -256.3877)
			(xy 33.636711 -256.397338) (xy 33.727494 -256.416526) (xy 33.815789 -256.445058) (xy 33.858454 -256.463292)
			(xy 33.868394 -256.467112) (xy 33.889662 -256.467112) (xy 33.899602 -256.463292) (xy 33.94226 -256.445038)
			(xy 34.030554 -256.416496) (xy 34.12134 -256.397306) (xy 34.213632 -256.387675) (xy 34.260028 -256.387092)
			(xy 34.301131 -256.38754) (xy 34.382986 -256.395127) (xy 34.463792 -256.410235) (xy 34.542859 -256.432734)
			(xy 34.619513 -256.462432) (xy 34.6931 -256.499076) (xy 34.762992 -256.542353) (xy 34.828593 -256.591894)
			(xy 34.889343 -256.647277) (xy 34.944724 -256.708029) (xy 34.994263 -256.773631) (xy 35.037538 -256.843525)
			(xy 35.07418 -256.917113) (xy 35.103875 -256.993768) (xy 35.126372 -257.072836) (xy 35.141477 -257.153642)
			(xy 35.149061 -257.235497) (xy 35.149536 -257.2766) (xy 35.148951 -257.322995) (xy 35.139306 -257.415284)
			(xy 35.120111 -257.506067) (xy 35.091573 -257.594361) (xy 35.073336 -257.637026) (xy 35.069519 -257.646966)
			(xy 35.069519 -257.668234) (xy 35.073336 -257.678174) (xy 35.091582 -257.720835) (xy 35.120126 -257.809128)
			(xy 35.139318 -257.899913) (xy 35.148951 -257.992204) (xy 35.149536 -258.0386) (xy 35.149033 -258.079702)
			(xy 35.141449 -258.161554) (xy 35.126344 -258.242358) (xy 35.103849 -258.321423) (xy 35.074154 -258.398076)
			(xy 35.037513 -258.471662) (xy 34.99424 -258.541553) (xy 34.944702 -258.607153) (xy 34.889323 -258.667903)
			(xy 34.828575 -258.723284) (xy 34.762976 -258.772824) (xy 34.693086 -258.8161) (xy 34.619502 -258.852743)
			(xy 34.54285 -258.88244) (xy 34.463785 -258.904938) (xy 34.382982 -258.920045) (xy 34.30113 -258.927632)
			(xy 34.260028 -258.928108) (xy 34.213633 -258.927515) (xy 34.121345 -258.917873) (xy 34.030561 -258.89868)
			(xy 33.942267 -258.870144) (xy 33.899602 -258.851908) (xy 33.889662 -258.848088) (xy 33.868394 -258.848088)
			(xy 33.858454 -258.851908) (xy 33.815788 -258.870144) (xy 33.727497 -258.89869) (xy 33.636713 -258.917886)
			(xy 33.544424 -258.927522) (xy 33.498028 -258.928108) (xy 33.451633 -258.927515) (xy 33.359345 -258.917873)
			(xy 33.268561 -258.89868) (xy 33.180267 -258.870144) (xy 33.137602 -258.851908) (xy 33.127662 -258.848088)
			(xy 33.106394 -258.848088) (xy 33.096454 -258.851908) (xy 33.053788 -258.870144) (xy 32.965497 -258.89869)
			(xy 32.874713 -258.917886) (xy 32.782424 -258.927522) (xy 32.736028 -258.928108) (xy 32.689633 -258.927515)
			(xy 32.597345 -258.917873) (xy 32.506561 -258.89868) (xy 32.418267 -258.870144) (xy 32.375602 -258.851908)
			(xy 32.365662 -258.848088) (xy 32.344394 -258.848088) (xy 32.334454 -258.851908) (xy 32.291788 -258.870144)
			(xy 32.203497 -258.89869) (xy 32.112713 -258.917886) (xy 32.020424 -258.927522) (xy 31.974028 -258.928108)
			(xy 31.932925 -258.927621) (xy 31.85107 -258.920039) (xy 31.770264 -258.904936) (xy 31.691196 -258.882441)
			(xy 31.614541 -258.852747) (xy 31.540953 -258.816107) (xy 31.47106 -258.772832) (xy 31.405458 -258.723294)
			(xy 31.344706 -258.667913) (xy 31.289324 -258.607164) (xy 31.239783 -258.541563) (xy 31.196507 -258.471671)
			(xy 31.159864 -258.398084) (xy 31.130168 -258.32143) (xy 31.107671 -258.242363) (xy 31.092565 -258.161557)
			(xy 31.08498 -258.079703) (xy 31.08452 -258.0386) (xy 18.935105 -258.0386) (xy 18.902179 -258.073132)
			(xy 18.838169 -258.128597) (xy 18.769177 -258.177726) (xy 18.695827 -258.220075) (xy 18.618784 -258.255259)
			(xy 18.538745 -258.282961) (xy 18.456436 -258.302929) (xy 18.372601 -258.314982) (xy 18.288 -258.319013)
			(xy 18.203399 -258.314982) (xy 18.119564 -258.302929) (xy 18.037255 -258.282961) (xy 17.957216 -258.255259)
			(xy 17.880173 -258.220075) (xy 17.806823 -258.177726) (xy 17.737831 -258.128597) (xy 17.673821 -258.073132)
			(xy 17.615373 -258.011834) (xy 17.563017 -257.945258) (xy 17.517227 -257.874006) (xy 17.478416 -257.798725)
			(xy 17.446937 -257.720095) (xy 17.423076 -257.638828) (xy 17.407047 -257.555662) (xy 17.398996 -257.471348)
			(xy 17.398492 -257.429) (xy 17.39896 -257.386574) (xy 17.407043 -257.302108) (xy 17.423135 -257.218796)
			(xy 17.44709 -257.137396) (xy 17.47869 -257.058648) (xy 17.517648 -256.983268) (xy 17.563608 -256.911942)
			(xy 17.616155 -256.845318) (xy 17.645126 -256.81432) (xy 17.652482 -256.805776) (xy 17.659608 -256.784419)
			(xy 17.658842 -256.773172) (xy 17.655871 -256.746729) (xy 17.652692 -256.693608) (xy 17.652492 -256.667)
			(xy 17.652664 -256.640776) (xy 17.655715 -256.588418) (xy 17.658588 -256.562352) (xy 17.659858 -256.5527)
			(xy 17.654778 -256.533904) (xy 17.601438 -256.462276) (xy 17.584928 -256.452116) (xy 17.57553 -256.450338)
			(xy 17.532379 -256.442197) (xy 17.447804 -256.41855) (xy 17.365973 -256.386679) (xy 17.287684 -256.346894)
			(xy 17.213699 -256.299583) (xy 17.144741 -256.245207) (xy 17.112742 -256.215134) (xy 17.105122 -256.207768)
			(xy 17.085564 -256.200402) (xy 16.990314 -256.205482) (xy 16.971518 -256.21488) (xy 16.96466 -256.223008)
			(xy 16.936534 -256.255692) (xy 16.874947 -256.316053) (xy 16.807809 -256.370172) (xy 16.73575 -256.41754)
			(xy 16.659445 -256.457713) (xy 16.579611 -256.490314) (xy 16.496997 -256.515037) (xy 16.412378 -256.531651)
			(xy 16.326549 -256.539998) (xy 16.283432 -256.540508) (xy 16.242443 -256.540052) (xy 16.160812 -256.532513)
			(xy 16.080222 -256.517496) (xy 16.001354 -256.495127) (xy 15.924879 -256.465598) (xy 15.887954 -256.447798)
			(xy 15.879523 -256.444026) (xy 15.861153 -256.442218) (xy 15.85214 -256.444242) (xy 15.823438 -256.451862)
			(xy 15.814645 -256.454585) (xy 15.799668 -256.465264) (xy 15.794228 -256.47269) (xy 15.769541 -256.508785)
			(xy 15.714144 -256.576453) (xy 15.652373 -256.638358) (xy 15.584824 -256.6939) (xy 15.512149 -256.742544)
			(xy 15.43505 -256.78382) (xy 15.354272 -256.817329) (xy 15.270596 -256.842747) (xy 15.184828 -256.859829)
			(xy 15.097798 -256.86841) (xy 15.054072 -256.86893) (xy 15.014742 -256.86848) (xy 14.93639 -256.861544)
			(xy 14.858955 -256.847721) (xy 14.783042 -256.827119) (xy 14.709243 -256.799897) (xy 14.638135 -256.766269)
			(xy 14.603984 -256.746756) (xy 14.594113 -256.741605) (xy 14.571976 -256.739494) (xy 14.561312 -256.742692)
			(xy 14.525246 -256.755139) (xy 14.451455 -256.774549) (xy 14.376272 -256.787569) (xy 14.300251 -256.794103)
			(xy 14.2621 -256.794508) (xy 14.233765 -256.794308) (xy 14.177207 -256.79075) (xy 14.14907 -256.787396)
			(xy 14.136624 -256.785618) (xy 14.113256 -256.794254) (xy 14.040358 -256.874772) (xy 14.034262 -256.898648)
			(xy 14.037056 -256.91084) (xy 14.047747 -256.960251) (xy 14.059205 -257.060697) (xy 14.059916 -257.111246)
			(xy 14.059477 -257.152349) (xy 14.051888 -257.234204) (xy 14.036779 -257.31501) (xy 14.014279 -257.394077)
			(xy 13.98458 -257.47073) (xy 13.947935 -257.544317) (xy 13.904657 -257.614209) (xy 13.855115 -257.679809)
			(xy 13.799732 -257.740559) (xy 13.73898 -257.79594) (xy 13.673377 -257.845479) (xy 13.603484 -257.888754)
			(xy 13.529896 -257.925396) (xy 13.453241 -257.955091) (xy 13.374173 -257.977588) (xy 13.293366 -257.992694)
			(xy 13.211511 -258.000279) (xy 13.170408 -258.000754) (xy 13.125775 -258.000182) (xy 13.036959 -257.991237)
			(xy 12.949486 -257.973436) (xy 12.864237 -257.946958) (xy 12.782072 -257.912071) (xy 12.703816 -257.869124)
			(xy 12.666726 -257.84429) (xy 12.65881 -257.839388) (xy 12.640722 -257.835043) (xy 12.622276 -257.837444)
			(xy 12.613894 -257.841496) (xy 12.575019 -257.861722) (xy 12.494087 -257.895344) (xy 12.410244 -257.920853)
			(xy 12.324301 -257.938003) (xy 12.237089 -257.946628) (xy 12.19327 -257.94716) (xy 12.151963 -257.94668)
			(xy 12.069706 -257.939004) (xy 11.988515 -257.923734) (xy 11.90909 -257.901003) (xy 11.832114 -257.871005)
			(xy 11.758251 -257.833999) (xy 11.688138 -257.790305) (xy 11.622377 -257.740298) (xy 11.561536 -257.68441)
			(xy 11.506139 -257.623121) (xy 11.456663 -257.556961) (xy 11.413534 -257.486498) (xy 11.377124 -257.412339)
			(xy 11.347747 -257.335125) (xy 11.325655 -257.255519) (xy 11.311039 -257.174208) (xy 11.307064 -257.13309)
			(xy 11.30554 -257.117088) (xy 11.285474 -257.092704) (xy 11.1633 -257.058414) (xy 11.133328 -257.068574)
			(xy 11.12393 -257.081528) (xy 11.098841 -257.11484) (xy 11.043391 -257.177139) (xy 10.982355 -257.233975)
			(xy 10.916268 -257.284849) (xy 10.845709 -257.329315) (xy 10.771299 -257.366982) (xy 10.69369 -257.397521)
			(xy 10.613564 -257.420662) (xy 10.531624 -257.436203) (xy 10.448589 -257.444007) (xy 10.406888 -257.444494)
			(xy 10.365784 -257.444059) (xy 10.283927 -257.436473) (xy 10.20312 -257.421366) (xy 10.124051 -257.398868)
			(xy 10.047395 -257.36917) (xy 9.973806 -257.332526) (xy 9.903913 -257.289248) (xy 9.83831 -257.239706)
			(xy 9.777559 -257.184323) (xy 9.722177 -257.12357) (xy 9.672637 -257.057966) (xy 9.629361 -256.988071)
			(xy 9.592719 -256.914481) (xy 9.563024 -256.837824) (xy 9.540528 -256.758755) (xy 9.525423 -256.677947)
			(xy 9.51784 -256.59609) (xy 9.51738 -256.554986) (xy 9.517977 -256.510007) (xy 9.527086 -256.42051)
			(xy 9.545179 -256.332389) (xy 9.572072 -256.246543) (xy 9.589262 -256.204974) (xy 9.593072 -256.19583)
			(xy 9.59358 -256.176526) (xy 9.561576 -256.09169) (xy 9.548368 -256.077466) (xy 9.539478 -256.073148)
			(xy 9.501948 -256.054806) (xy 9.430197 -256.01202) (xy 9.362775 -255.962695) (xy 9.300276 -255.907263)
			(xy 9.24325 -255.846215) (xy 9.192201 -255.780088) (xy 9.147578 -255.709465) (xy 9.109774 -255.634969)
			(xy 9.079124 -255.557256) (xy 9.055897 -255.477011) (xy 9.040297 -255.394941) (xy 9.032463 -255.31177)
			(xy 9.031986 -255.27) (xy 1.651254 -255.27) (xy 1.651254 -256.660904) (xy 1.652778 -256.71145) (xy 1.651254 -256.761996)
			(xy 1.651254 -258.0132) (xy 3.424682 -258.0132) (xy 3.425266 -257.966804) (xy 3.434911 -257.874516)
			(xy 3.454106 -257.783732) (xy 3.482644 -257.695439) (xy 3.500882 -257.652774) (xy 3.504787 -257.642852)
			(xy 3.504787 -257.621548) (xy 3.500882 -257.611626) (xy 3.482637 -257.568964) (xy 3.454093 -257.480672)
			(xy 3.4349 -257.389886) (xy 3.425267 -257.297596) (xy 3.424682 -257.2512) (xy 3.425167 -257.210098)
			(xy 3.432751 -257.128244) (xy 3.447856 -257.047439) (xy 3.470352 -256.968373) (xy 3.500048 -256.89172)
			(xy 3.536689 -256.818133) (xy 3.579964 -256.748241) (xy 3.629503 -256.682641) (xy 3.684883 -256.621891)
			(xy 3.745633 -256.566509) (xy 3.811233 -256.51697) (xy 3.881124 -256.473694) (xy 3.95471 -256.437052)
			(xy 4.031364 -256.407356) (xy 4.11043 -256.384859) (xy 4.191234 -256.369753) (xy 4.273088 -256.362167)
			(xy 4.31419 -256.361692) (xy 4.360585 -256.362278) (xy 4.452874 -256.371922) (xy 4.543658 -256.391117)
			(xy 4.631951 -256.419655) (xy 4.674616 -256.437892) (xy 4.684556 -256.441712) (xy 4.705824 -256.441712)
			(xy 4.715764 -256.437892) (xy 4.758428 -256.419651) (xy 4.846719 -256.391106) (xy 4.937504 -256.371912)
			(xy 5.029794 -256.362277) (xy 5.07619 -256.361692) (xy 5.122585 -256.362278) (xy 5.214874 -256.371922)
			(xy 5.305658 -256.391117) (xy 5.393951 -256.419655) (xy 5.436616 -256.437892) (xy 5.446556 -256.441712)
			(xy 5.467824 -256.441712) (xy 5.477764 -256.437892) (xy 5.520428 -256.419651) (xy 5.608719 -256.391106)
			(xy 5.699504 -256.371912) (xy 5.791794 -256.362277) (xy 5.83819 -256.361692) (xy 5.884585 -256.362278)
			(xy 5.976874 -256.371922) (xy 6.067658 -256.391117) (xy 6.155951 -256.419655) (xy 6.198616 -256.437892)
			(xy 6.208556 -256.441712) (xy 6.229824 -256.441712) (xy 6.239764 -256.437892) (xy 6.282428 -256.419651)
			(xy 6.370719 -256.391106) (xy 6.461504 -256.371912) (xy 6.553794 -256.362277) (xy 6.60019 -256.361692)
			(xy 6.641293 -256.362162) (xy 6.723148 -256.369746) (xy 6.803955 -256.38485) (xy 6.883023 -256.407346)
			(xy 6.959678 -256.437042) (xy 7.033266 -256.473684) (xy 7.103159 -256.516959) (xy 7.168761 -256.566499)
			(xy 7.229513 -256.62188) (xy 7.284895 -256.682631) (xy 7.334435 -256.748232) (xy 7.377711 -256.818125)
			(xy 7.414354 -256.891713) (xy 7.44405 -256.968368) (xy 7.466547 -257.047435) (xy 7.481653 -257.128242)
			(xy 7.489238 -257.210097) (xy 7.489698 -257.2512) (xy 7.489116 -257.297596) (xy 7.479471 -257.389884)
			(xy 7.460275 -257.480668) (xy 7.431736 -257.568961) (xy 7.413498 -257.611626) (xy 7.409593 -257.621548)
			(xy 7.409593 -257.642852) (xy 7.413498 -257.652774) (xy 7.431742 -257.695436) (xy 7.460287 -257.783729)
			(xy 7.47948 -257.874514) (xy 7.489113 -257.966804) (xy 7.489698 -258.0132) (xy 7.489248 -258.054303)
			(xy 7.481663 -258.13616) (xy 7.466557 -258.216967) (xy 7.44406 -258.296036) (xy 7.414363 -258.372691)
			(xy 7.37772 -258.44628) (xy 7.334444 -258.516173) (xy 7.284902 -258.581775) (xy 7.22952 -258.642527)
			(xy 7.168768 -258.697909) (xy 7.103165 -258.747449) (xy 7.033271 -258.790725) (xy 6.959682 -258.827367)
			(xy 6.883026 -258.857063) (xy 6.803957 -258.879559) (xy 6.72315 -258.894664) (xy 6.641293 -258.902248)
			(xy 6.60019 -258.902708) (xy 6.553794 -258.902129) (xy 6.461506 -258.892483) (xy 6.370722 -258.873286)
			(xy 6.282429 -258.844746) (xy 6.239764 -258.826508) (xy 6.229824 -258.822688) (xy 6.208556 -258.822688)
			(xy 6.198616 -258.826508) (xy 6.155955 -258.844756) (xy 6.067662 -258.873299) (xy 5.976877 -258.892491)
			(xy 5.884586 -258.902124) (xy 5.83819 -258.902708) (xy 5.791794 -258.902129) (xy 5.699506 -258.892483)
			(xy 5.608722 -258.873286) (xy 5.520429 -258.844746) (xy 5.477764 -258.826508) (xy 5.467824 -258.822688)
			(xy 5.446556 -258.822688) (xy 5.436616 -258.826508) (xy 5.393955 -258.844756) (xy 5.305662 -258.873299)
			(xy 5.214877 -258.892491) (xy 5.122586 -258.902124) (xy 5.07619 -258.902708) (xy 5.029794 -258.902129)
			(xy 4.937506 -258.892483) (xy 4.846722 -258.873286) (xy 4.758429 -258.844746) (xy 4.715764 -258.826508)
			(xy 4.705824 -258.822688) (xy 4.684556 -258.822688) (xy 4.674616 -258.826508) (xy 4.631955 -258.844756)
			(xy 4.543662 -258.873299) (xy 4.452877 -258.892491) (xy 4.360586 -258.902124) (xy 4.31419 -258.902708)
			(xy 4.273087 -258.902243) (xy 4.191233 -258.894657) (xy 4.110427 -258.879551) (xy 4.03136 -258.857054)
			(xy 3.954706 -258.827357) (xy 3.88112 -258.790715) (xy 3.811227 -258.747438) (xy 3.745627 -258.697898)
			(xy 3.684876 -258.642517) (xy 3.629495 -258.581766) (xy 3.579956 -258.516164) (xy 3.536681 -258.446272)
			(xy 3.500039 -258.372684) (xy 3.470343 -258.29603) (xy 3.447847 -258.216963) (xy 3.432742 -258.136157)
			(xy 3.425157 -258.054303) (xy 3.424682 -258.0132) (xy 1.651254 -258.0132) (xy 1.651254 -261.3152)
			(xy 3.424178 -261.3152) (xy 3.428208 -261.230599) (xy 3.440261 -261.146764) (xy 3.460229 -261.064455)
			(xy 3.487931 -260.984416) (xy 3.523115 -260.907373) (xy 3.565464 -260.834023) (xy 3.614593 -260.765031)
			(xy 3.670058 -260.701021) (xy 3.731356 -260.642573) (xy 3.797932 -260.590217) (xy 3.869184 -260.544427)
			(xy 3.944465 -260.505616) (xy 4.023095 -260.474137) (xy 4.104362 -260.450276) (xy 4.187528 -260.434247)
			(xy 4.271842 -260.426196) (xy 4.31419 -260.425692) (xy 4.360585 -260.426278) (xy 4.452874 -260.435922)
			(xy 4.543658 -260.455117) (xy 4.631951 -260.483655) (xy 4.674616 -260.501892) (xy 4.684556 -260.505712)
			(xy 4.705824 -260.505712) (xy 4.715764 -260.501892) (xy 4.758428 -260.483651) (xy 4.846719 -260.455106)
			(xy 4.937504 -260.435912) (xy 5.029794 -260.426277) (xy 5.07619 -260.425692) (xy 5.122585 -260.426278)
			(xy 5.214874 -260.435922) (xy 5.305658 -260.455117) (xy 5.393951 -260.483655) (xy 5.436616 -260.501892)
			(xy 5.446556 -260.505712) (xy 5.467824 -260.505712) (xy 5.477764 -260.501892) (xy 5.520428 -260.483651)
			(xy 5.608719 -260.455106) (xy 5.699504 -260.435912) (xy 5.791794 -260.426277) (xy 5.83819 -260.425692)
			(xy 5.884585 -260.426278) (xy 5.976874 -260.435922) (xy 6.067658 -260.455117) (xy 6.155951 -260.483655)
			(xy 6.198616 -260.501892) (xy 6.208556 -260.505712) (xy 6.229824 -260.505712) (xy 6.239764 -260.501892)
			(xy 6.282428 -260.483651) (xy 6.370719 -260.455106) (xy 6.461504 -260.435912) (xy 6.553794 -260.426277)
			(xy 6.60019 -260.425692) (xy 6.642538 -260.426196) (xy 6.726852 -260.434247) (xy 6.810018 -260.450276)
			(xy 6.891285 -260.474137) (xy 6.969915 -260.505616) (xy 7.045196 -260.544427) (xy 7.116448 -260.590217)
			(xy 7.183024 -260.642573) (xy 7.244322 -260.701021) (xy 7.299787 -260.765031) (xy 7.348916 -260.834023)
			(xy 7.387395 -260.90067) (xy 8.64896 -260.90067) (xy 8.65299 -260.816069) (xy 8.665043 -260.732234)
			(xy 8.685011 -260.649925) (xy 8.712713 -260.569887) (xy 8.747897 -260.492844) (xy 8.790246 -260.419494)
			(xy 8.839374 -260.350502) (xy 8.894839 -260.286492) (xy 8.956137 -260.228045) (xy 9.022713 -260.175689)
			(xy 9.093965 -260.129898) (xy 9.169246 -260.091088) (xy 9.247876 -260.059609) (xy 9.329142 -260.035748)
			(xy 9.412308 -260.019719) (xy 9.496622 -260.011668) (xy 9.53897 -260.011164) (xy 9.570706 -260.011462)
			(xy 9.634013 -260.01604) (xy 9.665462 -260.020308) (xy 9.677146 -260.021832) (xy 9.69899 -260.014974)
			(xy 9.77392 -259.944616) (xy 9.782048 -259.92328) (xy 9.781286 -259.911596) (xy 9.779989 -259.894226)
			(xy 9.778591 -259.859418) (xy 9.778492 -259.842) (xy 9.778996 -259.799652) (xy 9.787047 -259.715338)
			(xy 9.803076 -259.632172) (xy 9.826937 -259.550905) (xy 9.858416 -259.472275) (xy 9.897227 -259.396994)
			(xy 9.943017 -259.325742) (xy 9.995373 -259.259166) (xy 10.053821 -259.197868) (xy 10.117831 -259.142403)
			(xy 10.186823 -259.093274) (xy 10.260173 -259.050925) (xy 10.337216 -259.015741) (xy 10.417255 -258.988039)
			(xy 10.499564 -258.968071) (xy 10.583399 -258.956018) (xy 10.668 -258.951988) (xy 10.752601 -258.956018)
			(xy 10.836436 -258.968071) (xy 10.918745 -258.988039) (xy 10.998784 -259.015741) (xy 11.075827 -259.050925)
			(xy 11.149177 -259.093274) (xy 11.218169 -259.142403) (xy 11.282179 -259.197868) (xy 11.340627 -259.259166)
			(xy 11.392983 -259.325742) (xy 11.438773 -259.396994) (xy 11.477584 -259.472275) (xy 11.509063 -259.550905)
			(xy 11.532924 -259.632172) (xy 11.548953 -259.715338) (xy 11.557004 -259.799652) (xy 11.557508 -259.842)
			(xy 11.810492 -259.842) (xy 11.810967 -259.800898) (xy 11.818552 -259.719043) (xy 11.833657 -259.638238)
			(xy 11.856153 -259.559171) (xy 11.885849 -259.482517) (xy 11.922491 -259.40893) (xy 11.965766 -259.339038)
			(xy 12.015306 -259.273437) (xy 12.070687 -259.212687) (xy 12.131437 -259.157306) (xy 12.197038 -259.107766)
			(xy 12.26693 -259.064491) (xy 12.340517 -259.027849) (xy 12.417171 -258.998153) (xy 12.496238 -258.975657)
			(xy 12.577043 -258.960552) (xy 12.658898 -258.952967) (xy 12.7 -258.952492) (xy 12.705842 -258.952492)
			(xy 12.717851 -258.951904) (xy 12.739328 -258.941181) (xy 12.74699 -258.931918) (xy 12.772086 -258.898817)
			(xy 12.827506 -258.836933) (xy 12.888454 -258.780486) (xy 12.9544 -258.729969) (xy 13.02477 -258.685821)
			(xy 13.09895 -258.648427) (xy 13.176294 -258.618113) (xy 13.256127 -258.595144) (xy 13.337754 -258.579719)
			(xy 13.420464 -258.571972) (xy 13.462 -258.571492) (xy 13.503102 -258.571967) (xy 13.584957 -258.579552)
			(xy 13.665762 -258.594657) (xy 13.744829 -258.617153) (xy 13.821483 -258.646849) (xy 13.89507 -258.683491)
			(xy 13.964962 -258.726766) (xy 14.030563 -258.776306) (xy 14.091313 -258.831687) (xy 14.146694 -258.892437)
			(xy 14.196234 -258.958038) (xy 14.239509 -259.02793) (xy 14.276151 -259.101517) (xy 14.305847 -259.178171)
			(xy 14.328343 -259.257238) (xy 14.343448 -259.338043) (xy 14.351033 -259.419898) (xy 14.351508 -259.461)
			(xy 14.35101 -259.502505) (xy 14.343274 -259.585154) (xy 14.32787 -259.666723) (xy 14.304931 -259.746501)
			(xy 14.274657 -259.823794) (xy 14.237312 -259.897929) (xy 14.193221 -259.968262) (xy 14.168374 -260.001512)
			(xy 14.162035 -260.010712) (xy 14.157209 -260.0325) (xy 14.162035 -260.054288) (xy 14.168374 -260.063488)
			(xy 14.193221 -260.096738) (xy 14.237317 -260.167069) (xy 14.274667 -260.241204) (xy 14.304944 -260.318496)
			(xy 14.327885 -260.398275) (xy 14.342755 -260.477) (xy 14.984988 -260.477) (xy 14.989018 -260.392399)
			(xy 15.001071 -260.308564) (xy 15.021039 -260.226255) (xy 15.048741 -260.146216) (xy 15.083925 -260.069173)
			(xy 15.126274 -259.995823) (xy 15.175403 -259.926831) (xy 15.230868 -259.862821) (xy 15.292166 -259.804373)
			(xy 15.358742 -259.752017) (xy 15.429994 -259.706227) (xy 15.505275 -259.667416) (xy 15.583905 -259.635937)
			(xy 15.665172 -259.612076) (xy 15.748338 -259.596047) (xy 15.832652 -259.587996) (xy 15.875 -259.587492)
			(xy 15.914569 -259.587919) (xy 15.993397 -259.594924) (xy 16.071291 -259.608904) (xy 16.147635 -259.62975)
			(xy 16.18488 -259.643118) (xy 16.1929 -259.645807) (xy 16.209805 -259.64619) (xy 16.225917 -259.641058)
			(xy 16.232886 -259.63626) (xy 16.265792 -259.612377) (xy 16.335195 -259.570007) (xy 16.408174 -259.534148)
			(xy 16.484122 -259.505098) (xy 16.562404 -259.483101) (xy 16.642367 -259.468339) (xy 16.723343 -259.460937)
			(xy 16.764 -259.460492) (xy 16.806348 -259.460996) (xy 16.890662 -259.469047) (xy 16.973828 -259.485076)
			(xy 17.055095 -259.508937) (xy 17.133725 -259.540416) (xy 17.209006 -259.579227) (xy 17.280258 -259.625017)
			(xy 17.346834 -259.677373) (xy 17.408132 -259.735821) (xy 17.463597 -259.799831) (xy 17.512726 -259.868823)
			(xy 17.555075 -259.942173) (xy 17.590259 -260.019216) (xy 17.617961 -260.099255) (xy 17.637929 -260.181564)
			(xy 17.649982 -260.265399) (xy 17.654013 -260.35) (xy 17.649982 -260.434601) (xy 17.637929 -260.518436)
			(xy 17.617961 -260.600745) (xy 17.602178 -260.646348) (xy 17.906996 -260.646348) (xy 17.906996 -260.561652)
			(xy 17.915047 -260.477338) (xy 17.931076 -260.394172) (xy 17.954937 -260.312905) (xy 17.986416 -260.234275)
			(xy 18.025227 -260.158994) (xy 18.071017 -260.087742) (xy 18.123373 -260.021166) (xy 18.181821 -259.959868)
			(xy 18.245831 -259.904403) (xy 18.314823 -259.855274) (xy 18.388173 -259.812925) (xy 18.465216 -259.777741)
			(xy 18.545255 -259.750039) (xy 18.627564 -259.730071) (xy 18.711399 -259.718018) (xy 18.796 -259.713988)
			(xy 18.880601 -259.718018) (xy 18.964436 -259.730071) (xy 19.046745 -259.750039) (xy 19.126784 -259.777741)
			(xy 19.203827 -259.812925) (xy 19.277177 -259.855274) (xy 19.346169 -259.904403) (xy 19.410179 -259.959868)
			(xy 19.468627 -260.021166) (xy 19.520983 -260.087742) (xy 19.566773 -260.158994) (xy 19.605584 -260.234275)
			(xy 19.637063 -260.312905) (xy 19.660924 -260.394172) (xy 19.676953 -260.477338) (xy 19.685004 -260.561652)
			(xy 19.685508 -260.604) (xy 19.685004 -260.646348) (xy 19.676953 -260.730662) (xy 19.660924 -260.813828)
			(xy 19.637063 -260.895095) (xy 19.605584 -260.973725) (xy 19.566773 -261.049006) (xy 19.520983 -261.120258)
			(xy 19.468627 -261.186834) (xy 19.418886 -261.239) (xy 36.31692 -261.239) (xy 36.317406 -261.196425)
			(xy 36.325543 -261.111665) (xy 36.341743 -261.028071) (xy 36.365857 -260.946407) (xy 36.397665 -260.867421)
			(xy 36.436876 -260.791837) (xy 36.48313 -260.720345) (xy 36.536004 -260.653601) (xy 36.595014 -260.592215)
			(xy 36.659621 -260.53675) (xy 36.729233 -260.487712) (xy 36.803212 -260.445551) (xy 36.880881 -260.410652)
			(xy 36.96153 -260.383336) (xy 37.044421 -260.363851) (xy 37.08654 -260.35762) (xy 37.098732 -260.355842)
			(xy 37.118544 -260.34238) (xy 37.169344 -260.249416) (xy 37.17036 -260.22554) (xy 37.16528 -260.214364)
			(xy 37.149556 -260.179298) (xy 37.12351 -260.106989) (xy 37.103797 -260.032704) (xy 37.090565 -259.956996)
			(xy 37.083911 -259.880428) (xy 37.083492 -259.842) (xy 37.083996 -259.799652) (xy 37.092047 -259.715338)
			(xy 37.108076 -259.632172) (xy 37.131937 -259.550905) (xy 37.163416 -259.472275) (xy 37.202227 -259.396994)
			(xy 37.248017 -259.325742) (xy 37.300373 -259.259166) (xy 37.358821 -259.197868) (xy 37.422831 -259.142403)
			(xy 37.491823 -259.093274) (xy 37.565173 -259.050925) (xy 37.642216 -259.015741) (xy 37.722255 -258.988039)
			(xy 37.804564 -258.968071) (xy 37.888399 -258.956018) (xy 37.973 -258.951988) (xy 38.057601 -258.956018)
			(xy 38.141436 -258.968071) (xy 38.223745 -258.988039) (xy 38.303784 -259.015741) (xy 38.380827 -259.050925)
			(xy 38.454177 -259.093274) (xy 38.523169 -259.142403) (xy 38.587179 -259.197868) (xy 38.645627 -259.259166)
			(xy 38.697983 -259.325742) (xy 38.743773 -259.396994) (xy 38.782584 -259.472275) (xy 38.814063 -259.550905)
			(xy 38.837924 -259.632172) (xy 38.853953 -259.715338) (xy 38.862004 -259.799652) (xy 38.862508 -259.842)
			(xy 39.623492 -259.842) (xy 39.623967 -259.800898) (xy 39.631552 -259.719043) (xy 39.646657 -259.638238)
			(xy 39.669153 -259.559171) (xy 39.698849 -259.482517) (xy 39.735491 -259.40893) (xy 39.778766 -259.339038)
			(xy 39.828306 -259.273437) (xy 39.883687 -259.212687) (xy 39.944437 -259.157306) (xy 40.010038 -259.107766)
			(xy 40.07993 -259.064491) (xy 40.153517 -259.027849) (xy 40.230171 -258.998153) (xy 40.309238 -258.975657)
			(xy 40.390043 -258.960552) (xy 40.471898 -258.952967) (xy 40.513 -258.952492) (xy 40.559396 -258.953075)
			(xy 40.651684 -258.96272) (xy 40.742468 -258.981916) (xy 40.830761 -259.010454) (xy 40.873426 -259.028692)
			(xy 40.883366 -259.032512) (xy 40.904634 -259.032512) (xy 40.914574 -259.028692) (xy 40.957236 -259.010447)
			(xy 41.045529 -258.981903) (xy 41.136314 -258.96271) (xy 41.228604 -258.953077) (xy 41.275 -258.952492)
			(xy 41.316102 -258.952967) (xy 41.397957 -258.960552) (xy 41.478762 -258.975657) (xy 41.557829 -258.998153)
			(xy 41.634483 -259.027849) (xy 41.70807 -259.064491) (xy 41.777962 -259.107766) (xy 41.843563 -259.157306)
			(xy 41.904313 -259.212687) (xy 41.959694 -259.273437) (xy 42.009234 -259.339038) (xy 42.052509 -259.40893)
			(xy 42.089151 -259.482517) (xy 42.118847 -259.559171) (xy 42.141343 -259.638238) (xy 42.156448 -259.719043)
			(xy 42.164033 -259.800898) (xy 42.164508 -259.842) (xy 42.164061 -259.882211) (xy 42.156801 -259.962304)
			(xy 42.142341 -260.041414) (xy 42.120798 -260.118897) (xy 42.092349 -260.194118) (xy 42.087066 -260.205)
			(xy 42.525953 -260.205) (xy 42.529984 -260.120398) (xy 42.542037 -260.036562) (xy 42.562005 -259.954251)
			(xy 42.589706 -259.874211) (xy 42.62489 -259.797166) (xy 42.667239 -259.723815) (xy 42.716367 -259.654821)
			(xy 42.771832 -259.59081) (xy 42.833129 -259.53236) (xy 42.899706 -259.480001) (xy 42.970957 -259.434208)
			(xy 43.046239 -259.395396) (xy 43.124869 -259.363914) (xy 43.206136 -259.340049) (xy 43.289303 -259.324017)
			(xy 43.373617 -259.315963) (xy 43.415966 -259.315458) (xy 43.459636 -259.316017) (xy 43.546554 -259.324585)
			(xy 43.632215 -259.341631) (xy 43.715791 -259.366992) (xy 43.79648 -259.400422) (xy 43.873503 -259.441601)
			(xy 43.946118 -259.490132) (xy 44.013627 -259.545546) (xy 44.04487 -259.576062) (xy 44.05316 -259.583394)
			(xy 44.073944 -259.590916) (xy 44.085002 -259.59054) (xy 44.1037 -259.589087) (xy 44.141178 -259.587564)
			(xy 44.159932 -259.587492) (xy 44.20228 -259.587997) (xy 44.286591 -259.596051) (xy 44.369755 -259.612082)
			(xy 44.451018 -259.635946) (xy 44.529646 -259.667426) (xy 44.604925 -259.706237) (xy 44.676174 -259.752028)
			(xy 44.689075 -259.762174) (xy 45.353728 -259.762174) (xy 45.353728 -259.677478) (xy 45.361779 -259.593164)
			(xy 45.377808 -259.509998) (xy 45.401669 -259.428731) (xy 45.433148 -259.350101) (xy 45.471959 -259.27482)
			(xy 45.517749 -259.203568) (xy 45.570105 -259.136992) (xy 45.628553 -259.075694) (xy 45.692563 -259.020229)
			(xy 45.761555 -258.9711) (xy 45.834905 -258.928751) (xy 45.911948 -258.893567) (xy 45.991987 -258.865865)
			(xy 46.074296 -258.845897) (xy 46.158131 -258.833844) (xy 46.242732 -258.829814) (xy 46.327333 -258.833844)
			(xy 46.411168 -258.845897) (xy 46.493477 -258.865865) (xy 46.573516 -258.893567) (xy 46.650559 -258.928751)
			(xy 46.723909 -258.9711) (xy 46.792901 -259.020229) (xy 46.856911 -259.075694) (xy 46.915359 -259.136992)
			(xy 46.967715 -259.203568) (xy 47.013505 -259.27482) (xy 47.052316 -259.350101) (xy 47.083795 -259.428731)
			(xy 47.107656 -259.509998) (xy 47.123685 -259.593164) (xy 47.131736 -259.677478) (xy 47.13224 -259.719826)
			(xy 47.131736 -259.762174) (xy 47.123685 -259.846488) (xy 47.107656 -259.929654) (xy 47.083795 -260.010921)
			(xy 47.052316 -260.089551) (xy 47.013505 -260.164832) (xy 46.967715 -260.236084) (xy 46.915359 -260.30266)
			(xy 46.856911 -260.363958) (xy 46.792901 -260.419423) (xy 46.723909 -260.468552) (xy 46.650559 -260.510901)
			(xy 46.573516 -260.546085) (xy 46.493477 -260.573787) (xy 46.411168 -260.593755) (xy 46.327333 -260.605808)
			(xy 46.242732 -260.609839) (xy 46.158131 -260.605808) (xy 46.074296 -260.593755) (xy 45.991987 -260.573787)
			(xy 45.911948 -260.546085) (xy 45.834905 -260.510901) (xy 45.761555 -260.468552) (xy 45.692563 -260.419423)
			(xy 45.628553 -260.363958) (xy 45.570105 -260.30266) (xy 45.517749 -260.236084) (xy 45.471959 -260.164832)
			(xy 45.433148 -260.089551) (xy 45.401669 -260.010921) (xy 45.377808 -259.929654) (xy 45.361779 -259.846488)
			(xy 45.353728 -259.762174) (xy 44.689075 -259.762174) (xy 44.742747 -259.804385) (xy 44.804043 -259.862832)
			(xy 44.859505 -259.926841) (xy 44.908632 -259.995833) (xy 44.950979 -260.069181) (xy 44.986162 -260.146223)
			(xy 45.013862 -260.22626) (xy 45.03383 -260.308568) (xy 45.045883 -260.392401) (xy 45.049913 -260.477)
			(xy 45.045883 -260.561599) (xy 45.03383 -260.645432) (xy 45.013862 -260.72774) (xy 44.986162 -260.807777)
			(xy 44.950979 -260.884819) (xy 44.908632 -260.958167) (xy 44.859505 -261.027159) (xy 44.804043 -261.091168)
			(xy 44.742747 -261.149615) (xy 44.676174 -261.201972) (xy 44.604925 -261.247763) (xy 44.529646 -261.286574)
			(xy 44.451018 -261.318054) (xy 44.369755 -261.341918) (xy 44.286591 -261.357949) (xy 44.20228 -261.366003)
			(xy 44.159932 -261.366508) (xy 44.116262 -261.36596) (xy 44.029343 -261.357392) (xy 43.943682 -261.340345)
			(xy 43.860105 -261.314983) (xy 43.779416 -261.281551) (xy 43.702393 -261.24037) (xy 43.629778 -261.191838)
			(xy 43.56227 -261.136421) (xy 43.531028 -261.105904) (xy 43.522742 -261.098567) (xy 43.501955 -261.091049)
			(xy 43.490896 -261.091426) (xy 43.472198 -261.092879) (xy 43.43472 -261.094402) (xy 43.415966 -261.094474)
			(xy 43.373617 -261.094037) (xy 43.289303 -261.085983) (xy 43.206136 -261.069951) (xy 43.124869 -261.046086)
			(xy 43.046239 -261.014604) (xy 42.970957 -260.975792) (xy 42.899706 -260.929999) (xy 42.833129 -260.87764)
			(xy 42.771832 -260.81919) (xy 42.716367 -260.755179) (xy 42.667239 -260.686185) (xy 42.62489 -260.612834)
			(xy 42.589706 -260.535789) (xy 42.562005 -260.455749) (xy 42.542037 -260.373438) (xy 42.529984 -260.289602)
			(xy 42.525953 -260.205) (xy 42.087066 -260.205) (xy 42.057226 -260.266464) (xy 42.015715 -260.335344)
			(xy 41.992296 -260.368034) (xy 41.98619 -260.377302) (xy 41.981846 -260.39904) (xy 41.983914 -260.409944)
			(xy 41.995246 -260.46075) (xy 42.007337 -260.564143) (xy 42.008044 -260.616192) (xy 42.007526 -260.657293)
			(xy 41.999942 -260.739145) (xy 41.984838 -260.819948) (xy 41.962344 -260.899013) (xy 41.93265 -260.975665)
			(xy 41.89601 -261.049251) (xy 41.852738 -261.119142) (xy 41.803201 -261.184742) (xy 41.747823 -261.245492)
			(xy 41.687076 -261.300873) (xy 41.621478 -261.350413) (xy 41.551589 -261.393689) (xy 41.478006 -261.430332)
			(xy 41.401355 -261.46003) (xy 41.322291 -261.482528) (xy 41.241489 -261.497636) (xy 41.159637 -261.505224)
			(xy 41.118536 -261.5057) (xy 41.075333 -261.505183) (xy 40.989336 -261.496789) (xy 40.904557 -261.480097)
			(xy 40.821797 -261.455264) (xy 40.741834 -261.422524) (xy 40.665422 -261.382186) (xy 40.593281 -261.334628)
			(xy 40.526091 -261.280301) (xy 40.464485 -261.219715) (xy 40.409043 -261.153441) (xy 40.360288 -261.082104)
			(xy 40.318679 -261.006376) (xy 40.284609 -260.926971) (xy 40.258398 -260.844636) (xy 40.240293 -260.760148)
			(xy 40.23487 -260.717284) (xy 40.233409 -260.708027) (xy 40.224773 -260.691414) (xy 40.210735 -260.679025)
			(xy 40.202104 -260.675374) (xy 40.163371 -260.660381) (xy 40.088591 -260.624227) (xy 40.017507 -260.581259)
			(xy 39.950739 -260.53185) (xy 39.888869 -260.476431) (xy 39.832435 -260.415485) (xy 39.781929 -260.349543)
			(xy 39.737792 -260.279179) (xy 39.700408 -260.205006) (xy 39.670101 -260.127671) (xy 39.647138 -260.047847)
			(xy 39.631716 -259.96623) (xy 39.623972 -259.883531) (xy 39.623492 -259.842) (xy 38.862508 -259.842)
			(xy 38.861945 -259.88677) (xy 38.852954 -259.975859) (xy 38.835052 -260.063592) (xy 38.808421 -260.149081)
			(xy 38.791388 -260.190488) (xy 38.786308 -260.202426) (xy 38.788594 -260.227826) (xy 38.850824 -260.320282)
			(xy 38.87343 -260.331966) (xy 38.886384 -260.331712) (xy 38.9001 -260.331712) (xy 38.942449 -260.332176)
			(xy 39.026765 -260.340227) (xy 39.109933 -260.356256) (xy 39.191201 -260.380119) (xy 39.269833 -260.411598)
			(xy 39.345116 -260.450409) (xy 39.41637 -260.496201) (xy 39.482947 -260.548558) (xy 39.544247 -260.607007)
			(xy 39.599713 -260.671018) (xy 39.648843 -260.740012) (xy 39.691192 -260.813364) (xy 39.726378 -260.890408)
			(xy 39.75408 -260.970449) (xy 39.774048 -261.05276) (xy 39.786102 -261.136597) (xy 39.790133 -261.2212)
			(xy 39.786102 -261.305803) (xy 39.774048 -261.38964) (xy 39.75408 -261.471951) (xy 39.726378 -261.551992)
			(xy 39.691192 -261.629036) (xy 39.648843 -261.702388) (xy 39.599713 -261.771382) (xy 39.544247 -261.835393)
			(xy 39.482947 -261.893842) (xy 39.41637 -261.946199) (xy 39.345116 -261.991991) (xy 39.269833 -262.030802)
			(xy 39.191201 -262.062281) (xy 39.109933 -262.086144) (xy 39.026765 -262.102173) (xy 38.942449 -262.110224)
			(xy 38.9001 -262.110728) (xy 38.855668 -262.11018) (xy 38.767248 -262.101313) (xy 38.680154 -262.083668)
			(xy 38.595255 -262.057421) (xy 38.513399 -262.022834) (xy 38.474142 -262.002016) (xy 38.46625 -261.998104)
			(xy 38.448855 -261.995417) (xy 38.431584 -261.998816) (xy 38.42385 -262.003032) (xy 38.389387 -262.023046)
			(xy 38.317555 -262.057578) (xy 38.242921 -262.085542) (xy 38.166083 -262.106715) (xy 38.08766 -262.120926)
			(xy 38.008279 -262.128062) (xy 37.968428 -262.128508) (xy 37.922033 -262.127915) (xy 37.829745 -262.118273)
			(xy 37.738961 -262.09908) (xy 37.650667 -262.070544) (xy 37.608002 -262.052308) (xy 37.598062 -262.048488)
			(xy 37.576794 -262.048488) (xy 37.566854 -262.052308) (xy 37.524188 -262.070544) (xy 37.435897 -262.09909)
			(xy 37.345113 -262.118286) (xy 37.252824 -262.127922) (xy 37.206428 -262.128508) (xy 37.165325 -262.128021)
			(xy 37.08347 -262.120439) (xy 37.002664 -262.105336) (xy 36.923596 -262.082841) (xy 36.846941 -262.053147)
			(xy 36.773353 -262.016507) (xy 36.70346 -261.973232) (xy 36.637858 -261.923694) (xy 36.577106 -261.868313)
			(xy 36.521724 -261.807564) (xy 36.472183 -261.741963) (xy 36.428907 -261.672071) (xy 36.392264 -261.598484)
			(xy 36.362568 -261.52183) (xy 36.340071 -261.442763) (xy 36.324965 -261.361957) (xy 36.31738 -261.280103)
			(xy 36.31692 -261.239) (xy 19.418886 -261.239) (xy 19.410179 -261.248132) (xy 19.346169 -261.303597)
			(xy 19.277177 -261.352726) (xy 19.203827 -261.395075) (xy 19.126784 -261.430259) (xy 19.046745 -261.457961)
			(xy 18.964436 -261.477929) (xy 18.880601 -261.489982) (xy 18.796 -261.494013) (xy 18.711399 -261.489982)
			(xy 18.627564 -261.477929) (xy 18.545255 -261.457961) (xy 18.465216 -261.430259) (xy 18.388173 -261.395075)
			(xy 18.314823 -261.352726) (xy 18.245831 -261.303597) (xy 18.181821 -261.248132) (xy 18.123373 -261.186834)
			(xy 18.071017 -261.120258) (xy 18.025227 -261.049006) (xy 17.986416 -260.973725) (xy 17.954937 -260.895095)
			(xy 17.931076 -260.813828) (xy 17.915047 -260.730662) (xy 17.906996 -260.646348) (xy 17.602178 -260.646348)
			(xy 17.590259 -260.680784) (xy 17.555075 -260.757827) (xy 17.512726 -260.831177) (xy 17.463597 -260.900169)
			(xy 17.408132 -260.964179) (xy 17.346834 -261.022627) (xy 17.280258 -261.074983) (xy 17.209006 -261.120773)
			(xy 17.133725 -261.159584) (xy 17.055095 -261.191063) (xy 16.973828 -261.214924) (xy 16.890662 -261.230953)
			(xy 16.806348 -261.239004) (xy 16.764 -261.239508) (xy 16.724431 -261.239081) (xy 16.645603 -261.232076)
			(xy 16.567709 -261.218096) (xy 16.491365 -261.19725) (xy 16.45412 -261.183882) (xy 16.4461 -261.181193)
			(xy 16.429195 -261.18081) (xy 16.413083 -261.185942) (xy 16.406114 -261.19074) (xy 16.373208 -261.214623)
			(xy 16.303805 -261.256993) (xy 16.230826 -261.292852) (xy 16.154878 -261.321902) (xy 16.076596 -261.343899)
			(xy 15.996633 -261.358661) (xy 15.915657 -261.366063) (xy 15.875 -261.366508) (xy 15.832652 -261.366004)
			(xy 15.748338 -261.357953) (xy 15.665172 -261.341924) (xy 15.583905 -261.318063) (xy 15.505275 -261.286584)
			(xy 15.429994 -261.247773) (xy 15.358742 -261.201983) (xy 15.292166 -261.149627) (xy 15.230868 -261.091179)
			(xy 15.175403 -261.027169) (xy 15.126274 -260.958177) (xy 15.083925 -260.884827) (xy 15.048741 -260.807784)
			(xy 15.021039 -260.727745) (xy 15.001071 -260.645436) (xy 14.989018 -260.561601) (xy 14.984988 -260.477)
			(xy 14.342755 -260.477) (xy 14.343292 -260.479844) (xy 14.351028 -260.562494) (xy 14.351508 -260.604)
			(xy 14.351033 -260.645102) (xy 14.343448 -260.726957) (xy 14.328343 -260.807762) (xy 14.305847 -260.886829)
			(xy 14.276151 -260.963483) (xy 14.239509 -261.03707) (xy 14.196234 -261.106962) (xy 14.146694 -261.172563)
			(xy 14.091313 -261.233313) (xy 14.030563 -261.288694) (xy 13.964962 -261.338234) (xy 13.89507 -261.381509)
			(xy 13.821483 -261.418151) (xy 13.744829 -261.447847) (xy 13.665762 -261.470343) (xy 13.584957 -261.485448)
			(xy 13.503102 -261.493033) (xy 13.462 -261.493508) (xy 13.420609 -261.493046) (xy 13.338185 -261.485368)
			(xy 13.25683 -261.470062) (xy 13.177251 -261.447261) (xy 13.100136 -261.417161) (xy 13.026152 -261.380024)
			(xy 12.95594 -261.336171) (xy 12.890109 -261.285981) (xy 12.829228 -261.22989) (xy 12.773823 -261.168383)
			(xy 12.724376 -261.101992) (xy 12.681314 -261.031293) (xy 12.64501 -260.956897) (xy 12.615778 -260.879448)
			(xy 12.593871 -260.799618) (xy 12.586208 -260.75894) (xy 12.583916 -260.748814) (xy 12.572513 -260.731487)
			(xy 12.555186 -260.720084) (xy 12.54506 -260.717792) (xy 12.504386 -260.710124) (xy 12.424567 -260.688199)
			(xy 12.34713 -260.658952) (xy 12.272745 -260.622637) (xy 12.202057 -260.579567) (xy 12.135675 -260.530117)
			(xy 12.074176 -260.474712) (xy 12.01809 -260.413833) (xy 11.967903 -260.348007) (xy 11.924049 -260.277802)
			(xy 11.886908 -260.203827) (xy 11.856801 -260.126721) (xy 11.833987 -260.047151) (xy 11.818666 -259.965805)
			(xy 11.810969 -259.883388) (xy 11.810492 -259.842) (xy 11.557508 -259.842) (xy 11.557143 -259.879308)
			(xy 11.550898 -259.953663) (xy 11.538452 -260.027234) (xy 11.519891 -260.099505) (xy 11.507978 -260.134862)
			(xy 11.504676 -260.144006) (xy 11.505438 -260.162802) (xy 11.54049 -260.243574) (xy 11.553698 -260.257036)
			(xy 11.562588 -260.2611) (xy 11.601432 -260.278907) (xy 11.675843 -260.320926) (xy 11.74588 -260.369889)
			(xy 11.810897 -260.425345) (xy 11.870295 -260.486782) (xy 11.923525 -260.553634) (xy 11.970098 -260.625284)
			(xy 12.009582 -260.70107) (xy 12.041614 -260.780295) (xy 12.065899 -260.862227) (xy 12.082213 -260.94611)
			(xy 12.090404 -261.031172) (xy 12.090908 -261.0739) (xy 12.090433 -261.115002) (xy 12.082848 -261.196857)
			(xy 12.067743 -261.277662) (xy 12.045247 -261.356729) (xy 12.015551 -261.433383) (xy 11.978909 -261.50697)
			(xy 11.935634 -261.576862) (xy 11.886094 -261.642463) (xy 11.830713 -261.703213) (xy 11.769963 -261.758594)
			(xy 11.704362 -261.808134) (xy 11.63447 -261.851409) (xy 11.560883 -261.888051) (xy 11.484229 -261.917747)
			(xy 11.405162 -261.940243) (xy 11.324357 -261.955348) (xy 11.242502 -261.962933) (xy 11.2014 -261.963408)
			(xy 11.156961 -261.962864) (xy 11.068526 -261.954006) (xy 10.981416 -261.936369) (xy 10.8965 -261.910128)
			(xy 10.814627 -261.875546) (xy 10.736612 -261.832968) (xy 10.663235 -261.782818) (xy 10.628884 -261.75462)
			(xy 10.622023 -261.749303) (xy 10.605797 -261.743176) (xy 10.588457 -261.742822) (xy 10.580116 -261.745222)
			(xy 10.53498 -261.759501) (xy 10.442445 -261.779512) (xy 10.348307 -261.789573) (xy 10.30097 -261.79018)
			(xy 10.254575 -261.789575) (xy 10.162287 -261.779937) (xy 10.071503 -261.760747) (xy 9.983209 -261.732215)
			(xy 9.940544 -261.71398) (xy 9.930604 -261.71016) (xy 9.909336 -261.71016) (xy 9.899396 -261.71398)
			(xy 9.856737 -261.732233) (xy 9.768444 -261.760775) (xy 9.677658 -261.779966) (xy 9.585366 -261.789597)
			(xy 9.53897 -261.79018) (xy 9.496622 -261.789672) (xy 9.412308 -261.781621) (xy 9.329142 -261.765592)
			(xy 9.247876 -261.741731) (xy 9.169246 -261.710252) (xy 9.093965 -261.671442) (xy 9.022713 -261.625651)
			(xy 8.956137 -261.573295) (xy 8.894839 -261.514848) (xy 8.839374 -261.450838) (xy 8.790246 -261.381846)
			(xy 8.747897 -261.308496) (xy 8.712713 -261.231453) (xy 8.685011 -261.151415) (xy 8.665043 -261.069106)
			(xy 8.65299 -260.985271) (xy 8.64896 -260.90067) (xy 7.387395 -260.90067) (xy 7.391265 -260.907373)
			(xy 7.426449 -260.984416) (xy 7.454151 -261.064455) (xy 7.474119 -261.146764) (xy 7.486172 -261.230599)
			(xy 7.490203 -261.3152) (xy 7.486172 -261.399801) (xy 7.474119 -261.483636) (xy 7.454151 -261.565945)
			(xy 7.426449 -261.645984) (xy 7.391265 -261.723027) (xy 7.348916 -261.796377) (xy 7.299787 -261.865369)
			(xy 7.244322 -261.929379) (xy 7.183024 -261.987827) (xy 7.116448 -262.040183) (xy 7.045196 -262.085973)
			(xy 6.969915 -262.124784) (xy 6.891285 -262.156263) (xy 6.810018 -262.180124) (xy 6.726852 -262.196153)
			(xy 6.642538 -262.204204) (xy 6.60019 -262.204708) (xy 6.553794 -262.204129) (xy 6.461506 -262.194483)
			(xy 6.370722 -262.175286) (xy 6.282429 -262.146746) (xy 6.239764 -262.128508) (xy 6.229824 -262.124688)
			(xy 6.208556 -262.124688) (xy 6.198616 -262.128508) (xy 6.155955 -262.146756) (xy 6.067662 -262.175299)
			(xy 5.976877 -262.194491) (xy 5.884586 -262.204124) (xy 5.83819 -262.204708) (xy 5.791794 -262.204129)
			(xy 5.699506 -262.194483) (xy 5.608722 -262.175286) (xy 5.520429 -262.146746) (xy 5.477764 -262.128508)
			(xy 5.467824 -262.124688) (xy 5.446556 -262.124688) (xy 5.436616 -262.128508) (xy 5.393955 -262.146756)
			(xy 5.305662 -262.175299) (xy 5.214877 -262.194491) (xy 5.122586 -262.204124) (xy 5.07619 -262.204708)
			(xy 5.029794 -262.204129) (xy 4.937506 -262.194483) (xy 4.846722 -262.175286) (xy 4.758429 -262.146746)
			(xy 4.715764 -262.128508) (xy 4.705824 -262.124688) (xy 4.684556 -262.124688) (xy 4.674616 -262.128508)
			(xy 4.631955 -262.146756) (xy 4.543662 -262.175299) (xy 4.452877 -262.194491) (xy 4.360586 -262.204124)
			(xy 4.31419 -262.204708) (xy 4.271842 -262.204204) (xy 4.187528 -262.196153) (xy 4.104362 -262.180124)
			(xy 4.023095 -262.156263) (xy 3.944465 -262.124784) (xy 3.869184 -262.085973) (xy 3.797932 -262.040183)
			(xy 3.731356 -261.987827) (xy 3.670058 -261.929379) (xy 3.614593 -261.865369) (xy 3.565464 -261.796377)
			(xy 3.523115 -261.723027) (xy 3.487931 -261.645984) (xy 3.460229 -261.565945) (xy 3.440261 -261.483636)
			(xy 3.428208 -261.399801) (xy 3.424178 -261.3152) (xy 1.651254 -261.3152) (xy 1.651254 -261.740904)
			(xy 1.652778 -261.79145) (xy 1.651254 -261.841996) (xy 1.651254 -265.121136) (xy 14.397482 -265.121136)
			(xy 14.39791 -265.082848) (xy 14.404533 -265.006557) (xy 14.417683 -264.931118) (xy 14.437261 -264.857086)
			(xy 14.449806 -264.820908) (xy 14.45243 -264.812466) (xy 14.452441 -264.794802) (xy 14.449806 -264.786364)
			(xy 14.437231 -264.750196) (xy 14.41764 -264.676164) (xy 14.404493 -264.600721) (xy 14.39789 -264.524426)
			(xy 14.397482 -264.486136) (xy 14.397986 -264.445034) (xy 14.405568 -264.36318) (xy 14.42067 -264.282374)
			(xy 14.443164 -264.203307) (xy 14.472857 -264.126653) (xy 14.509496 -264.053065) (xy 14.552769 -263.983172)
			(xy 14.602307 -263.91757) (xy 14.657686 -263.856818) (xy 14.718434 -263.801436) (xy 14.784034 -263.751895)
			(xy 14.853925 -263.708619) (xy 14.92751 -263.671975) (xy 15.004163 -263.642278) (xy 15.083229 -263.619781)
			(xy 15.164034 -263.604675) (xy 15.245888 -263.597089) (xy 15.28699 -263.596628) (xy 15.326559 -263.597061)
			(xy 15.405387 -263.604065) (xy 15.483281 -263.618043) (xy 15.559625 -263.638887) (xy 15.59687 -263.652254)
			(xy 15.605537 -263.655094) (xy 15.623763 -263.655094) (xy 15.63243 -263.652254) (xy 15.669679 -263.638896)
			(xy 15.746021 -263.618047) (xy 15.823914 -263.604061) (xy 15.902741 -263.59705) (xy 15.94231 -263.596628)
			(xy 15.980598 -263.597069) (xy 16.056888 -263.603688) (xy 16.132328 -263.616834) (xy 16.20636 -263.636409)
			(xy 16.242538 -263.648952) (xy 16.250976 -263.651594) (xy 16.268644 -263.651594) (xy 16.277082 -263.648952)
			(xy 16.313255 -263.63639) (xy 16.387285 -263.616796) (xy 16.462727 -263.603646) (xy 16.53902 -263.597038)
			(xy 16.57731 -263.596628) (xy 16.618412 -263.597107) (xy 16.700266 -263.604692) (xy 16.781072 -263.619797)
			(xy 16.860138 -263.642293) (xy 16.936792 -263.671989) (xy 17.010379 -263.70863) (xy 17.080271 -263.751905)
			(xy 17.145871 -263.801445) (xy 17.206622 -263.856826) (xy 17.262003 -263.917575) (xy 17.311542 -263.983176)
			(xy 17.354818 -264.053068) (xy 17.39146 -264.126654) (xy 17.421156 -264.203308) (xy 17.443653 -264.282375)
			(xy 17.458758 -264.36318) (xy 17.466343 -264.445034) (xy 17.466818 -264.486136) (xy 17.466382 -264.524424)
			(xy 17.459761 -264.600714) (xy 17.446614 -264.676154) (xy 17.427038 -264.750186) (xy 17.414494 -264.786364)
			(xy 17.411835 -264.794798) (xy 17.411846 -264.81247) (xy 17.414494 -264.820908) (xy 17.427061 -264.857079)
			(xy 17.446655 -264.93111) (xy 17.459803 -265.006552) (xy 17.466409 -265.082846) (xy 17.466818 -265.121136)
			(xy 42.03192 -265.121136) (xy 42.032346 -265.082848) (xy 42.03897 -265.006557) (xy 42.05212 -264.931117)
			(xy 42.071699 -264.857085) (xy 42.084244 -264.820908) (xy 42.086866 -264.812465) (xy 42.086878 -264.794802)
			(xy 42.084244 -264.786364) (xy 42.071671 -264.750195) (xy 42.052079 -264.676164) (xy 42.038932 -264.600721)
			(xy 42.032328 -264.524426) (xy 42.03192 -264.486136) (xy 42.032387 -264.445033) (xy 42.039969 -264.363176)
			(xy 42.055072 -264.282369) (xy 42.077566 -264.2033) (xy 42.107261 -264.126643) (xy 42.143902 -264.053054)
			(xy 42.187177 -263.98316) (xy 42.236717 -263.917557) (xy 42.292099 -263.856805) (xy 42.352851 -263.801423)
			(xy 42.418453 -263.751882) (xy 42.488347 -263.708606) (xy 42.561936 -263.671964) (xy 42.638592 -263.642269)
			(xy 42.717661 -263.619773) (xy 42.798468 -263.60467) (xy 42.880325 -263.597087) (xy 42.921428 -263.596628)
			(xy 42.960997 -263.59705) (xy 43.039825 -263.604057) (xy 43.117719 -263.618038) (xy 43.194063 -263.638885)
			(xy 43.231308 -263.652254) (xy 43.239975 -263.655094) (xy 43.258201 -263.655094) (xy 43.266868 -263.652254)
			(xy 43.304113 -263.638885) (xy 43.380457 -263.618039) (xy 43.458351 -263.604056) (xy 43.537179 -263.597049)
			(xy 43.576748 -263.596628) (xy 43.615036 -263.597058) (xy 43.691327 -263.603681) (xy 43.766766 -263.616829)
			(xy 43.840799 -263.636407) (xy 43.876976 -263.648952) (xy 43.885414 -263.651594) (xy 43.903082 -263.651594)
			(xy 43.91152 -263.648952) (xy 43.947689 -263.636379) (xy 44.021721 -263.616788) (xy 44.097164 -263.603641)
			(xy 44.173458 -263.597037) (xy 44.211748 -263.596628) (xy 44.252852 -263.597021) (xy 44.33471 -263.604611)
			(xy 44.415518 -263.619721) (xy 44.494587 -263.642222) (xy 44.571243 -263.671923) (xy 44.644832 -263.70857)
			(xy 44.714725 -263.751851) (xy 44.780326 -263.801396) (xy 44.841077 -263.856783) (xy 44.896457 -263.917538)
			(xy 44.945996 -263.983145) (xy 44.98927 -264.053042) (xy 45.025911 -264.126634) (xy 45.055605 -264.203292)
			(xy 45.078099 -264.282364) (xy 45.093201 -264.363173) (xy 45.100783 -264.445032) (xy 45.101256 -264.486136)
			(xy 45.100823 -264.524424) (xy 45.094202 -264.600714) (xy 45.081054 -264.676154) (xy 45.061477 -264.750186)
			(xy 45.048932 -264.786364) (xy 45.046271 -264.794797) (xy 45.046283 -264.81247) (xy 45.048932 -264.820908)
			(xy 45.061501 -264.857078) (xy 45.081093 -264.931109) (xy 45.094241 -265.006552) (xy 45.100847 -265.082846)
			(xy 45.101256 -265.121136) (xy 45.100768 -265.162238) (xy 45.09318 -265.24409) (xy 45.078073 -265.324893)
			(xy 45.055575 -265.403958) (xy 45.025878 -265.48061) (xy 44.989236 -265.554195) (xy 44.945961 -265.624085)
			(xy 44.896423 -265.689685) (xy 44.841043 -265.750434) (xy 44.780294 -265.805815) (xy 44.714695 -265.855354)
			(xy 44.644805 -265.89863) (xy 44.571221 -265.935274) (xy 44.49457 -265.964971) (xy 44.415505 -265.98747)
			(xy 44.334702 -266.002578) (xy 44.25285 -266.010167) (xy 44.211748 -266.010644) (xy 44.172816 -266.010201)
			(xy 44.095253 -266.003367) (xy 44.018585 -265.989773) (xy 43.9434 -265.969524) (xy 43.906694 -265.956542)
			(xy 43.898145 -265.953778) (xy 43.880191 -265.953778) (xy 43.871642 -265.956542) (xy 43.834933 -265.969514)
			(xy 43.759747 -265.989755) (xy 43.68308 -266.003352) (xy 43.605519 -266.010203) (xy 43.566588 -266.010644)
			(xy 43.527656 -266.010219) (xy 43.450092 -266.003379) (xy 43.373424 -265.989781) (xy 43.298239 -265.969527)
			(xy 43.261534 -265.956542) (xy 43.252985 -265.953778) (xy 43.235031 -265.953778) (xy 43.226482 -265.956542)
			(xy 43.189769 -265.969503) (xy 43.114584 -265.989746) (xy 43.037919 -266.003347) (xy 42.960359 -266.010201)
			(xy 42.921428 -266.010644) (xy 42.880327 -266.010107) (xy 42.798476 -266.002525) (xy 42.717673 -265.987423)
			(xy 42.638608 -265.96493) (xy 42.561956 -265.935238) (xy 42.488371 -265.8986) (xy 42.41848 -265.855328)
			(xy 42.352879 -265.805793) (xy 42.292129 -265.750416) (xy 42.236748 -265.68967) (xy 42.187208 -265.624073)
			(xy 42.143932 -265.554185) (xy 42.107288 -265.480603) (xy 42.077591 -265.403953) (xy 42.055092 -265.32489)
			(xy 42.039984 -265.244088) (xy 42.032396 -265.162237) (xy 42.03192 -265.121136) (xy 17.466818 -265.121136)
			(xy 17.466368 -265.162239) (xy 17.45878 -265.244093) (xy 17.443672 -265.324899) (xy 17.421173 -265.403966)
			(xy 17.391474 -265.480619) (xy 17.35483 -265.554206) (xy 17.311553 -265.624097) (xy 17.262012 -265.689698)
			(xy 17.206629 -265.750448) (xy 17.145878 -265.805828) (xy 17.080276 -265.855368) (xy 17.010383 -265.898643)
			(xy 16.936795 -265.935285) (xy 16.860141 -265.964981) (xy 16.781073 -265.987478) (xy 16.700268 -266.002583)
			(xy 16.618413 -266.010169) (xy 16.57731 -266.010644) (xy 16.538378 -266.010212) (xy 16.460814 -266.003375)
			(xy 16.384146 -265.989778) (xy 16.308962 -265.969526) (xy 16.272256 -265.956542) (xy 16.263707 -265.953778)
			(xy 16.245753 -265.953778) (xy 16.237204 -265.956542) (xy 16.200499 -265.969525) (xy 16.125311 -265.989763)
			(xy 16.048643 -266.003357) (xy 15.971082 -266.010205) (xy 15.93215 -266.010644) (xy 15.893218 -266.0102)
			(xy 15.815655 -266.003366) (xy 15.738987 -265.989773) (xy 15.663802 -265.969524) (xy 15.627096 -265.956542)
			(xy 15.618547 -265.953778) (xy 15.600593 -265.953778) (xy 15.592044 -265.956542) (xy 15.555335 -265.969513)
			(xy 15.480149 -265.989754) (xy 15.403482 -266.003352) (xy 15.325921 -266.010203) (xy 15.28699 -266.010644)
			(xy 15.245887 -266.010188) (xy 15.164031 -266.002603) (xy 15.083224 -265.987497) (xy 15.004156 -265.965)
			(xy 14.9275 -265.935304) (xy 14.853912 -265.898661) (xy 14.784019 -265.855385) (xy 14.718417 -265.805844)
			(xy 14.657665 -265.750462) (xy 14.602283 -265.68971) (xy 14.552743 -265.624108) (xy 14.509467 -265.554214)
			(xy 14.472825 -265.480626) (xy 14.443128 -265.403971) (xy 14.420632 -265.324902) (xy 14.405527 -265.244095)
			(xy 14.397942 -265.162239) (xy 14.397482 -265.121136) (xy 1.651254 -265.121136) (xy 1.651254 -266.820904)
			(xy 1.652778 -266.87145) (xy 1.651254 -266.921996) (xy 1.651254 -269.93088) (xy 2.665988 -269.93088)
			(xy 2.670018 -269.846279) (xy 2.682071 -269.762444) (xy 2.702039 -269.680135) (xy 2.729741 -269.600096)
			(xy 2.764925 -269.523053) (xy 2.807274 -269.449703) (xy 2.856403 -269.380711) (xy 2.911868 -269.316701)
			(xy 2.973166 -269.258253) (xy 3.039742 -269.205897) (xy 3.110994 -269.160107) (xy 3.186275 -269.121296)
			(xy 3.264905 -269.089817) (xy 3.346172 -269.065956) (xy 3.429338 -269.049927) (xy 3.513652 -269.041876)
			(xy 3.556 -269.041372) (xy 3.602396 -269.041957) (xy 3.694684 -269.051601) (xy 3.785468 -269.070797)
			(xy 3.873761 -269.099335) (xy 3.916426 -269.117572) (xy 3.926366 -269.121392) (xy 3.947634 -269.121392)
			(xy 3.957574 -269.117572) (xy 4.000236 -269.099326) (xy 4.088528 -269.070783) (xy 4.179314 -269.05159)
			(xy 4.271604 -269.041957) (xy 4.318 -269.041372) (xy 4.364396 -269.041957) (xy 4.456684 -269.051601)
			(xy 4.547468 -269.070797) (xy 4.635761 -269.099335) (xy 4.678426 -269.117572) (xy 4.688366 -269.121392)
			(xy 4.709634 -269.121392) (xy 4.719574 -269.117572) (xy 4.762236 -269.099326) (xy 4.850528 -269.070783)
			(xy 4.941314 -269.05159) (xy 5.033604 -269.041957) (xy 5.08 -269.041372) (xy 5.126396 -269.041957)
			(xy 5.218684 -269.051601) (xy 5.309468 -269.070797) (xy 5.397761 -269.099335) (xy 5.440426 -269.117572)
			(xy 5.450366 -269.121392) (xy 5.471634 -269.121392) (xy 5.481574 -269.117572) (xy 5.524236 -269.099326)
			(xy 5.612528 -269.070783) (xy 5.703314 -269.05159) (xy 5.795604 -269.041957) (xy 5.842 -269.041372)
			(xy 5.888396 -269.041957) (xy 5.980684 -269.051601) (xy 6.071468 -269.070797) (xy 6.159761 -269.099335)
			(xy 6.202426 -269.117572) (xy 6.212366 -269.121392) (xy 6.233634 -269.121392) (xy 6.243574 -269.117572)
			(xy 6.286236 -269.099326) (xy 6.374528 -269.070783) (xy 6.465314 -269.05159) (xy 6.557604 -269.041957)
			(xy 6.604 -269.041372) (xy 6.646348 -269.041876) (xy 6.730662 -269.049927) (xy 6.813828 -269.065956)
			(xy 6.895095 -269.089817) (xy 6.973725 -269.121296) (xy 7.049006 -269.160107) (xy 7.120258 -269.205897)
			(xy 7.186834 -269.258253) (xy 7.248132 -269.316701) (xy 7.303597 -269.380711) (xy 7.352726 -269.449703)
			(xy 7.395075 -269.523053) (xy 7.430259 -269.600096) (xy 7.457961 -269.680135) (xy 7.477929 -269.762444)
			(xy 7.489982 -269.846279) (xy 7.494013 -269.93088) (xy 7.489982 -270.015481) (xy 7.477929 -270.099316)
			(xy 7.457961 -270.181625) (xy 7.430259 -270.261664) (xy 7.395075 -270.338707) (xy 7.352726 -270.412057)
			(xy 7.303597 -270.481049) (xy 7.248132 -270.545059) (xy 7.186834 -270.603507) (xy 7.120258 -270.655863)
			(xy 7.049006 -270.701653) (xy 6.973725 -270.740464) (xy 6.895095 -270.771943) (xy 6.813828 -270.795804)
			(xy 6.730662 -270.811833) (xy 6.646348 -270.819884) (xy 6.604 -270.820388) (xy 6.557604 -270.819807)
			(xy 6.465316 -270.810162) (xy 6.374532 -270.790965) (xy 6.286239 -270.762426) (xy 6.243574 -270.744188)
			(xy 6.233634 -270.740368) (xy 6.212366 -270.740368) (xy 6.202426 -270.744188) (xy 6.159763 -270.762432)
			(xy 6.071471 -270.790976) (xy 5.980686 -270.81017) (xy 5.888396 -270.819803) (xy 5.842 -270.820388)
			(xy 5.795604 -270.819807) (xy 5.703316 -270.810162) (xy 5.612532 -270.790965) (xy 5.524239 -270.762426)
			(xy 5.481574 -270.744188) (xy 5.471634 -270.740368) (xy 5.450366 -270.740368) (xy 5.440426 -270.744188)
			(xy 5.397763 -270.762432) (xy 5.309471 -270.790976) (xy 5.218686 -270.81017) (xy 5.126396 -270.819803)
			(xy 5.08 -270.820388) (xy 5.033604 -270.819807) (xy 4.941316 -270.810162) (xy 4.850532 -270.790965)
			(xy 4.762239 -270.762426) (xy 4.719574 -270.744188) (xy 4.709634 -270.740368) (xy 4.688366 -270.740368)
			(xy 4.678426 -270.744188) (xy 4.635763 -270.762432) (xy 4.547471 -270.790976) (xy 4.456686 -270.81017)
			(xy 4.364396 -270.819803) (xy 4.318 -270.820388) (xy 4.271604 -270.819807) (xy 4.179316 -270.810162)
			(xy 4.088532 -270.790965) (xy 4.000239 -270.762426) (xy 3.957574 -270.744188) (xy 3.947634 -270.740368)
			(xy 3.926366 -270.740368) (xy 3.916426 -270.744188) (xy 3.873763 -270.762432) (xy 3.785471 -270.790976)
			(xy 3.694686 -270.81017) (xy 3.602396 -270.819803) (xy 3.556 -270.820388) (xy 3.513652 -270.819884)
			(xy 3.429338 -270.811833) (xy 3.346172 -270.795804) (xy 3.264905 -270.771943) (xy 3.186275 -270.740464)
			(xy 3.110994 -270.701653) (xy 3.039742 -270.655863) (xy 2.973166 -270.603507) (xy 2.911868 -270.545059)
			(xy 2.856403 -270.481049) (xy 2.807274 -270.412057) (xy 2.764925 -270.338707) (xy 2.729741 -270.261664)
			(xy 2.702039 -270.181625) (xy 2.682071 -270.099316) (xy 2.670018 -270.015481) (xy 2.665988 -269.93088)
			(xy 1.651254 -269.93088) (xy 1.651254 -271.900904) (xy 1.652778 -271.95145) (xy 1.651254 -272.001996)
			(xy 1.651254 -274.139406) (xy 13.258292 -274.139406) (xy 13.258802 -274.096817) (xy 13.266957 -274.01203)
			(xy 13.283183 -273.928412) (xy 13.307332 -273.846729) (xy 13.339183 -273.76773) (xy 13.358368 -273.729704)
			(xy 13.363556 -273.718521) (xy 13.36356 -273.693895) (xy 13.358368 -273.682714) (xy 13.339194 -273.644683)
			(xy 13.307353 -273.565682) (xy 13.283206 -273.484) (xy 13.266974 -273.400384) (xy 13.258806 -273.3156)
			(xy 13.258292 -273.273012) (xy 13.258808 -273.230469) (xy 13.266926 -273.145771) (xy 13.283099 -273.062235)
			(xy 13.307178 -272.980627) (xy 13.338944 -272.901693) (xy 13.378105 -272.826154) (xy 13.400786 -272.790158)
			(xy 13.405737 -272.781744) (xy 13.409469 -272.762599) (xy 13.405736 -272.743455) (xy 13.400786 -272.73504)
			(xy 13.378157 -272.699044) (xy 13.339064 -272.623534) (xy 13.307352 -272.544639) (xy 13.28331 -272.463078)
			(xy 13.267158 -272.379597) (xy 13.259044 -272.294955) (xy 13.258546 -272.25244) (xy 13.259033 -272.209851)
			(xy 13.267194 -272.125063) (xy 13.283426 -272.041445) (xy 13.30758 -271.959762) (xy 13.339434 -271.880764)
			(xy 13.358622 -271.842738) (xy 13.363784 -271.831546) (xy 13.363802 -271.806929) (xy 13.358622 -271.795748)
			(xy 13.339457 -271.757713) (xy 13.307615 -271.678712) (xy 13.283466 -271.597031) (xy 13.267232 -271.513417)
			(xy 13.259062 -271.428634) (xy 13.258546 -271.386046) (xy 13.25911 -271.344946) (xy 13.266691 -271.263095)
			(xy 13.281791 -271.182293) (xy 13.304282 -271.103229) (xy 13.333973 -271.026578) (xy 13.370609 -270.952993)
			(xy 13.413878 -270.883102) (xy 13.463412 -270.817502) (xy 13.518787 -270.756752) (xy 13.579531 -270.701371)
			(xy 13.645126 -270.65183) (xy 13.715012 -270.608554) (xy 13.788594 -270.57191) (xy 13.865242 -270.542211)
			(xy 13.944304 -270.519712) (xy 14.025104 -270.504603) (xy 14.106954 -270.497015) (xy 14.148054 -270.496538)
			(xy 14.191546 -270.497065) (xy 14.278119 -270.505524) (xy 14.363451 -270.522394) (xy 14.44673 -270.547515)
			(xy 14.487144 -270.563594) (xy 14.500098 -270.569182) (xy 14.527276 -270.565118) (xy 14.618716 -270.491458)
			(xy 14.628368 -270.465804) (xy 14.625828 -270.451834) (xy 14.619282 -270.412922) (xy 14.612285 -270.334319)
			(xy 14.611858 -270.294862) (xy 14.612353 -270.252273) (xy 14.620512 -270.167486) (xy 14.636742 -270.083867)
			(xy 14.660894 -270.002185) (xy 14.692747 -269.923186) (xy 14.711934 -269.88516) (xy 14.717148 -269.873986)
			(xy 14.717132 -269.849352) (xy 14.711934 -269.83817) (xy 14.692741 -269.800148) (xy 14.660904 -269.721144)
			(xy 14.636761 -269.63946) (xy 14.620534 -269.555842) (xy 14.61237 -269.471057) (xy 14.611858 -269.428468)
			(xy 14.612362 -269.38612) (xy 14.620413 -269.301806) (xy 14.636442 -269.21864) (xy 14.660303 -269.137373)
			(xy 14.691782 -269.058743) (xy 14.730593 -268.983462) (xy 14.776383 -268.91221) (xy 14.828739 -268.845634)
			(xy 14.887187 -268.784336) (xy 14.951197 -268.728871) (xy 15.020189 -268.679742) (xy 15.093539 -268.637393)
			(xy 15.170582 -268.602209) (xy 15.250621 -268.574507) (xy 15.33293 -268.554539) (xy 15.416765 -268.542486)
			(xy 15.501366 -268.538456) (xy 15.585967 -268.542486) (xy 15.669802 -268.554539) (xy 15.752111 -268.574507)
			(xy 15.83215 -268.602209) (xy 15.909193 -268.637393) (xy 15.982543 -268.679742) (xy 16.051535 -268.728871)
			(xy 16.115545 -268.784336) (xy 16.173993 -268.845634) (xy 16.226349 -268.91221) (xy 16.272139 -268.983462)
			(xy 16.31095 -269.058743) (xy 16.342429 -269.137373) (xy 16.36629 -269.21864) (xy 16.382319 -269.301806)
			(xy 16.39037 -269.38612) (xy 16.390874 -269.428468) (xy 16.390346 -269.471056) (xy 16.382194 -269.555842)
			(xy 16.365972 -269.63946) (xy 16.341827 -269.721143) (xy 16.309981 -269.800143) (xy 16.290798 -269.83817)
			(xy 16.28583 -269.849406) (xy 16.285815 -269.873933) (xy 16.290798 -269.88516) (xy 16.309968 -269.923193)
			(xy 16.341809 -270.002194) (xy 16.365956 -270.083876) (xy 16.382189 -270.167491) (xy 16.390359 -270.252274)
			(xy 16.390874 -270.294862) (xy 16.390412 -270.335966) (xy 16.39022 -270.338042) (xy 18.378932 -270.338042)
			(xy 18.379388 -270.297565) (xy 18.386743 -270.216944) (xy 18.401386 -270.137325) (xy 18.423196 -270.059363)
			(xy 18.451994 -269.983704) (xy 18.469356 -269.947136) (xy 18.473841 -269.936695) (xy 18.47409 -269.913999)
			(xy 18.469864 -269.903448) (xy 18.45397 -269.868216) (xy 18.427651 -269.795537) (xy 18.407744 -269.720846)
			(xy 18.394399 -269.644709) (xy 18.387716 -269.567701) (xy 18.387314 -269.529052) (xy 18.387818 -269.486704)
			(xy 18.395869 -269.40239) (xy 18.411898 -269.319224) (xy 18.435759 -269.237957) (xy 18.467238 -269.159327)
			(xy 18.506049 -269.084046) (xy 18.551839 -269.012794) (xy 18.604195 -268.946218) (xy 18.662643 -268.88492)
			(xy 18.726653 -268.829455) (xy 18.795645 -268.780326) (xy 18.868995 -268.737977) (xy 18.946038 -268.702793)
			(xy 19.026077 -268.675091) (xy 19.108386 -268.655123) (xy 19.192221 -268.64307) (xy 19.276822 -268.63904)
			(xy 19.361423 -268.64307) (xy 19.445258 -268.655123) (xy 19.527567 -268.675091) (xy 19.607606 -268.702793)
			(xy 19.684649 -268.737977) (xy 19.757999 -268.780326) (xy 19.826991 -268.829455) (xy 19.891001 -268.88492)
			(xy 19.949449 -268.946218) (xy 20.001805 -269.012794) (xy 20.047595 -269.084046) (xy 20.086406 -269.159327)
			(xy 20.117885 -269.237957) (xy 20.141746 -269.319224) (xy 20.157775 -269.40239) (xy 20.165826 -269.486704)
			(xy 20.16633 -269.529052) (xy 20.165875 -269.569529) (xy 20.158521 -269.65015) (xy 20.143878 -269.729769)
			(xy 20.122067 -269.807731) (xy 20.093269 -269.883391) (xy 20.075906 -269.919958) (xy 20.071426 -269.930401)
			(xy 20.071298 -269.942056) (xy 45.175424 -269.942056) (xy 45.175898 -269.900547) (xy 45.183617 -269.817888)
			(xy 45.199011 -269.73631) (xy 45.221947 -269.656523) (xy 45.236638 -269.617698) (xy 45.239774 -269.60869)
			(xy 45.239758 -269.589628) (xy 45.236638 -269.580614) (xy 45.221951 -269.541788) (xy 45.19903 -269.461998)
			(xy 45.183637 -269.38042) (xy 45.175904 -269.297764) (xy 45.175424 -269.256256) (xy 45.175825 -269.215152)
			(xy 45.183414 -269.133295) (xy 45.198524 -269.052487) (xy 45.221025 -268.973418) (xy 45.250725 -268.896762)
			(xy 45.287372 -268.823174) (xy 45.330652 -268.753281) (xy 45.380197 -268.687679) (xy 45.435583 -268.626929)
			(xy 45.496338 -268.571548) (xy 45.561944 -268.522009) (xy 45.63184 -268.478735) (xy 45.705432 -268.442095)
			(xy 45.78209 -268.4124) (xy 45.861161 -268.389906) (xy 45.94197 -268.374803) (xy 46.023828 -268.367221)
			(xy 46.064932 -268.366748) (xy 46.111327 -268.36735) (xy 46.203615 -268.376989) (xy 46.294399 -268.396179)
			(xy 46.382693 -268.424712) (xy 46.425358 -268.442948) (xy 46.435298 -268.446768) (xy 46.456566 -268.446768)
			(xy 46.466506 -268.442948) (xy 46.509165 -268.424696) (xy 46.597459 -268.396153) (xy 46.688245 -268.376962)
			(xy 46.780536 -268.367331) (xy 46.826932 -268.366748) (xy 46.873327 -268.36735) (xy 46.965615 -268.376989)
			(xy 47.056399 -268.396179) (xy 47.144693 -268.424712) (xy 47.187358 -268.442948) (xy 47.197298 -268.446768)
			(xy 47.218566 -268.446768) (xy 47.228506 -268.442948) (xy 47.271165 -268.424696) (xy 47.359459 -268.396153)
			(xy 47.450245 -268.376962) (xy 47.542536 -268.367331) (xy 47.588932 -268.366748) (xy 47.635327 -268.36735)
			(xy 47.727615 -268.376989) (xy 47.818399 -268.396179) (xy 47.906693 -268.424712) (xy 47.949358 -268.442948)
			(xy 47.959298 -268.446768) (xy 47.980566 -268.446768) (xy 47.990506 -268.442948) (xy 48.033165 -268.424696)
			(xy 48.121459 -268.396153) (xy 48.212245 -268.376962) (xy 48.304536 -268.367331) (xy 48.350932 -268.366748)
			(xy 48.392034 -268.367236) (xy 48.473886 -268.374823) (xy 48.55469 -268.38993) (xy 48.633755 -268.412428)
			(xy 48.710407 -268.442125) (xy 48.783992 -268.478767) (xy 48.853882 -268.522042) (xy 48.919482 -268.57158)
			(xy 48.980231 -268.62696) (xy 49.035612 -268.687709) (xy 49.085152 -268.753308) (xy 49.128428 -268.823198)
			(xy 49.165071 -268.896782) (xy 49.194768 -268.973434) (xy 49.217267 -269.052499) (xy 49.232375 -269.133302)
			(xy 49.239963 -269.215154) (xy 49.24044 -269.256256) (xy 49.239972 -269.297765) (xy 49.232252 -269.380424)
			(xy 49.216856 -269.462002) (xy 49.193918 -269.541789) (xy 49.179226 -269.580614) (xy 49.176139 -269.589635)
			(xy 49.176123 -269.608684) (xy 49.179226 -269.617698) (xy 49.19392 -269.656521) (xy 49.216838 -269.736313)
			(xy 49.232229 -269.817891) (xy 49.23996 -269.900547) (xy 49.24044 -269.942056) (xy 49.239906 -269.983158)
			(xy 49.232325 -270.06501) (xy 49.217224 -270.145814) (xy 49.194732 -270.22488) (xy 49.165041 -270.301534)
			(xy 49.128403 -270.37512) (xy 49.085132 -270.445013) (xy 49.035596 -270.510614) (xy 48.980219 -270.571365)
			(xy 48.919473 -270.626748) (xy 48.853875 -270.676289) (xy 48.783987 -270.719566) (xy 48.710403 -270.75621)
			(xy 48.633752 -270.785908) (xy 48.554688 -270.808407) (xy 48.473885 -270.823515) (xy 48.392033 -270.831102)
			(xy 48.350932 -270.831564) (xy 48.304537 -270.830974) (xy 48.212248 -270.821331) (xy 48.121464 -270.802138)
			(xy 48.033171 -270.773601) (xy 47.990506 -270.755364) (xy 47.980566 -270.751544) (xy 47.959298 -270.751544)
			(xy 47.949358 -270.755364) (xy 47.90669 -270.773596) (xy 47.8184 -270.802144) (xy 47.727617 -270.821341)
			(xy 47.635328 -270.830977) (xy 47.588932 -270.831564) (xy 47.542537 -270.830974) (xy 47.450248 -270.821331)
			(xy 47.359464 -270.802138) (xy 47.271171 -270.773601) (xy 47.228506 -270.755364) (xy 47.218566 -270.751544)
			(xy 47.197298 -270.751544) (xy 47.187358 -270.755364) (xy 47.14469 -270.773596) (xy 47.0564 -270.802144)
			(xy 46.965617 -270.821341) (xy 46.873328 -270.830977) (xy 46.826932 -270.831564) (xy 46.780537 -270.830974)
			(xy 46.688248 -270.821331) (xy 46.597464 -270.802138) (xy 46.509171 -270.773601) (xy 46.466506 -270.755364)
			(xy 46.456566 -270.751544) (xy 46.435298 -270.751544) (xy 46.425358 -270.755364) (xy 46.38269 -270.773596)
			(xy 46.2944 -270.802144) (xy 46.203617 -270.821341) (xy 46.111328 -270.830977) (xy 46.064932 -270.831564)
			(xy 46.023828 -270.831117) (xy 45.941971 -270.823535) (xy 45.861162 -270.808431) (xy 45.782092 -270.785935)
			(xy 45.705435 -270.75624) (xy 45.631845 -270.719597) (xy 45.561951 -270.676321) (xy 45.496347 -270.62678)
			(xy 45.435595 -270.571396) (xy 45.380213 -270.510644) (xy 45.330672 -270.44504) (xy 45.287397 -270.375144)
			(xy 45.250755 -270.301554) (xy 45.221061 -270.224897) (xy 45.198566 -270.145826) (xy 45.183464 -270.065017)
			(xy 45.175882 -269.98316) (xy 45.175424 -269.942056) (xy 20.071298 -269.942056) (xy 20.071176 -269.953095)
			(xy 20.075398 -269.963646) (xy 20.091287 -269.99888) (xy 20.117607 -270.071559) (xy 20.137516 -270.146248)
			(xy 20.150862 -270.222385) (xy 20.157546 -270.299393) (xy 20.157948 -270.338042) (xy 20.157515 -270.377849)
			(xy 20.150389 -270.457143) (xy 20.136208 -270.535483) (xy 20.115084 -270.612244) (xy 20.087186 -270.68681)
			(xy 20.052739 -270.758585) (xy 20.012016 -270.826996) (xy 19.989038 -270.859504) (xy 19.983196 -270.867632)
			(xy 19.978624 -270.88592) (xy 19.989546 -270.974312) (xy 19.99869 -270.990822) (xy 20.00631 -270.997172)
			(xy 20.039332 -271.025276) (xy 20.100297 -271.086946) (xy 20.154972 -271.154257) (xy 20.202837 -271.226569)
			(xy 20.243438 -271.303196) (xy 20.276389 -271.38341) (xy 20.301377 -271.46645) (xy 20.318166 -271.551527)
			(xy 20.326596 -271.637835) (xy 20.327112 -271.681194) (xy 20.326579 -271.724443) (xy 20.318178 -271.810531)
			(xy 20.301454 -271.895396) (xy 20.276566 -271.978235) (xy 20.243749 -272.058265) (xy 20.223988 -272.096738)
			(xy 20.21904 -272.107605) (xy 20.218624 -272.131443) (xy 20.223226 -272.142458) (xy 20.240174 -272.17863)
			(xy 20.268249 -272.25342) (xy 20.289505 -272.330427) (xy 20.303771 -272.40903) (xy 20.31093 -272.488595)
			(xy 20.311364 -272.528538) (xy 20.31088 -272.570902) (xy 20.302826 -272.655247) (xy 20.286787 -272.738444)
			(xy 20.262908 -272.819737) (xy 20.24761 -272.859246) (xy 20.244228 -272.868907) (xy 20.244609 -272.889352)
			(xy 20.248372 -272.89887) (xy 20.267188 -272.942085) (xy 20.296646 -273.031623) (xy 20.316483 -273.123772)
			(xy 20.326477 -273.2175) (xy 20.327112 -273.26463) (xy 20.326594 -273.307879) (xy 20.31819 -273.393968)
			(xy 20.301462 -273.478833) (xy 20.276571 -273.561672) (xy 20.243751 -273.641701) (xy 20.223988 -273.680174)
			(xy 20.221779 -273.685) (xy 29.86278 -273.685) (xy 29.863227 -273.646712) (xy 29.869845 -273.570422)
			(xy 29.882989 -273.494983) (xy 29.902562 -273.42095) (xy 29.915104 -273.384772) (xy 29.917746 -273.376334)
			(xy 29.917746 -273.358666) (xy 29.915104 -273.350228) (xy 29.902547 -273.314054) (xy 29.882951 -273.240024)
			(xy 29.8698 -273.164583) (xy 29.863191 -273.088289) (xy 29.86278 -273.05) (xy 29.863227 -273.011712)
			(xy 29.869845 -272.935422) (xy 29.882989 -272.859983) (xy 29.902562 -272.78595) (xy 29.915104 -272.749772)
			(xy 29.917746 -272.741334) (xy 29.917746 -272.723666) (xy 29.915104 -272.715228) (xy 29.902547 -272.679054)
			(xy 29.882951 -272.605024) (xy 29.8698 -272.529583) (xy 29.863191 -272.453289) (xy 29.86278 -272.415)
			(xy 29.863267 -272.373898) (xy 29.870851 -272.292044) (xy 29.885956 -272.21124) (xy 29.908452 -272.132173)
			(xy 29.938148 -272.05552) (xy 29.974789 -271.981934) (xy 30.018064 -271.912042) (xy 30.067602 -271.846441)
			(xy 30.122983 -271.785691) (xy 30.183732 -271.73031) (xy 30.249332 -271.68077) (xy 30.319223 -271.637495)
			(xy 30.392809 -271.600853) (xy 30.469462 -271.571156) (xy 30.548528 -271.548659) (xy 30.629332 -271.533553)
			(xy 30.711186 -271.525967) (xy 30.752288 -271.525492) (xy 30.792698 -271.525921) (xy 30.873185 -271.533241)
			(xy 30.952677 -271.54783) (xy 31.030518 -271.569569) (xy 31.106066 -271.598278) (xy 31.1787 -271.633721)
			(xy 31.247819 -271.675605) (xy 31.280608 -271.699228) (xy 31.290081 -271.705525) (xy 31.312383 -271.709862)
			(xy 31.323534 -271.70761) (xy 31.35376 -271.699736) (xy 31.36468 -271.696408) (xy 31.382133 -271.681727)
			(xy 31.387288 -271.671542) (xy 31.397956 -271.648936) (xy 31.402441 -271.638495) (xy 31.40269 -271.615799)
			(xy 31.398464 -271.605248) (xy 31.38257 -271.570016) (xy 31.356251 -271.497337) (xy 31.336344 -271.422646)
			(xy 31.322999 -271.346509) (xy 31.316316 -271.269501) (xy 31.315914 -271.230852) (xy 31.316418 -271.188504)
			(xy 31.324469 -271.10419) (xy 31.340498 -271.021024) (xy 31.364359 -270.939757) (xy 31.395838 -270.861127)
			(xy 31.434649 -270.785846) (xy 31.480439 -270.714594) (xy 31.532795 -270.648018) (xy 31.591243 -270.58672)
			(xy 31.655253 -270.531255) (xy 31.724245 -270.482126) (xy 31.797595 -270.439777) (xy 31.874638 -270.404593)
			(xy 31.954677 -270.376891) (xy 32.036986 -270.356923) (xy 32.120821 -270.34487) (xy 32.205422 -270.34084)
			(xy 32.290023 -270.34487) (xy 32.373858 -270.356923) (xy 32.456167 -270.376891) (xy 32.536206 -270.404593)
			(xy 32.613249 -270.439777) (xy 32.686599 -270.482126) (xy 32.755591 -270.531255) (xy 32.819601 -270.58672)
			(xy 32.878049 -270.648018) (xy 32.930405 -270.714594) (xy 32.976195 -270.785846) (xy 33.015006 -270.861127)
			(xy 33.046485 -270.939757) (xy 33.070346 -271.021024) (xy 33.086375 -271.10419) (xy 33.094426 -271.188504)
			(xy 33.09493 -271.230852) (xy 33.094475 -271.271329) (xy 33.087121 -271.35195) (xy 33.072478 -271.431569)
			(xy 33.050667 -271.509531) (xy 33.021869 -271.585191) (xy 33.004506 -271.621758) (xy 33.000026 -271.632201)
			(xy 32.999776 -271.654895) (xy 33.003998 -271.665446) (xy 33.019887 -271.70068) (xy 33.046207 -271.773359)
			(xy 33.066116 -271.848048) (xy 33.071997 -271.8816) (xy 35.06978 -271.8816) (xy 35.070227 -271.843312)
			(xy 35.076845 -271.767022) (xy 35.089989 -271.691583) (xy 35.109562 -271.61755) (xy 35.122104 -271.581372)
			(xy 35.124746 -271.572934) (xy 35.124746 -271.555266) (xy 35.122104 -271.546828) (xy 35.109547 -271.510654)
			(xy 35.089951 -271.436624) (xy 35.0768 -271.361183) (xy 35.070191 -271.284889) (xy 35.06978 -271.2466)
			(xy 35.070284 -271.204252) (xy 35.078335 -271.119938) (xy 35.094364 -271.036772) (xy 35.118225 -270.955505)
			(xy 35.149704 -270.876875) (xy 35.188515 -270.801594) (xy 35.234305 -270.730342) (xy 35.286661 -270.663766)
			(xy 35.345109 -270.602468) (xy 35.409119 -270.547003) (xy 35.478111 -270.497874) (xy 35.551461 -270.455525)
			(xy 35.628504 -270.420341) (xy 35.708543 -270.392639) (xy 35.790852 -270.372671) (xy 35.874687 -270.360618)
			(xy 35.959288 -270.356588) (xy 36.043889 -270.360618) (xy 36.127724 -270.372671) (xy 36.210033 -270.392639)
			(xy 36.290072 -270.420341) (xy 36.367115 -270.455525) (xy 36.440465 -270.497874) (xy 36.509457 -270.547003)
			(xy 36.573467 -270.602468) (xy 36.631915 -270.663766) (xy 36.684271 -270.730342) (xy 36.730061 -270.801594)
			(xy 36.768872 -270.876875) (xy 36.800351 -270.955505) (xy 36.824212 -271.036772) (xy 36.840241 -271.119938)
			(xy 36.848292 -271.204252) (xy 36.848796 -271.2466) (xy 36.84835 -271.284888) (xy 36.841732 -271.361178)
			(xy 36.828588 -271.436618) (xy 36.809015 -271.51065) (xy 36.796472 -271.546828) (xy 36.793832 -271.555266)
			(xy 36.793832 -271.572934) (xy 36.796472 -271.581372) (xy 36.808091 -271.614764) (xy 36.826609 -271.683004)
			(xy 36.839642 -271.7525) (xy 36.843716 -271.78762) (xy 36.845359 -271.798125) (xy 36.856013 -271.816502)
			(xy 36.86429 -271.82318) (xy 36.897853 -271.848193) (xy 36.960558 -271.903652) (xy 37.017777 -271.964756)
			(xy 37.069003 -272.030964) (xy 37.113783 -272.101692) (xy 37.151722 -272.176313) (xy 37.182483 -272.254168)
			(xy 37.205796 -272.334568) (xy 37.221453 -272.416802) (xy 37.229316 -272.500144) (xy 37.229796 -272.542)
			(xy 37.22935 -272.580288) (xy 37.222732 -272.656578) (xy 37.209588 -272.732018) (xy 37.190015 -272.80605)
			(xy 37.177472 -272.842228) (xy 37.174832 -272.850666) (xy 37.174832 -272.868334) (xy 37.177472 -272.876772)
			(xy 37.190028 -272.912947) (xy 37.209625 -272.986976) (xy 37.222776 -273.062417) (xy 37.229385 -273.138711)
			(xy 37.229796 -273.177) (xy 37.22935 -273.215288) (xy 37.222732 -273.291578) (xy 37.209588 -273.367018)
			(xy 37.190015 -273.44105) (xy 37.177472 -273.477228) (xy 37.174832 -273.485666) (xy 37.174832 -273.503334)
			(xy 37.177472 -273.511772) (xy 37.190028 -273.547947) (xy 37.209625 -273.621976) (xy 37.222776 -273.697417)
			(xy 37.229385 -273.773711) (xy 37.229796 -273.812) (xy 37.229292 -273.854348) (xy 37.221241 -273.938662)
			(xy 37.205212 -274.021828) (xy 37.181351 -274.103095) (xy 37.149872 -274.181725) (xy 37.111061 -274.257006)
			(xy 37.065271 -274.328258) (xy 37.012915 -274.394834) (xy 36.954467 -274.456132) (xy 36.890457 -274.511597)
			(xy 36.821465 -274.560726) (xy 36.748115 -274.603075) (xy 36.671072 -274.638259) (xy 36.591033 -274.665961)
			(xy 36.508724 -274.685929) (xy 36.424889 -274.697982) (xy 36.340288 -274.702013) (xy 36.255687 -274.697982)
			(xy 36.171852 -274.685929) (xy 36.089543 -274.665961) (xy 36.009504 -274.638259) (xy 35.932461 -274.603075)
			(xy 35.859111 -274.560726) (xy 35.790119 -274.511597) (xy 35.726109 -274.456132) (xy 35.667661 -274.394834)
			(xy 35.615305 -274.328258) (xy 35.569515 -274.257006) (xy 35.530704 -274.181725) (xy 35.499225 -274.103095)
			(xy 35.475364 -274.021828) (xy 35.459335 -273.938662) (xy 35.451284 -273.854348) (xy 35.45078 -273.812)
			(xy 35.451227 -273.773712) (xy 35.457845 -273.697422) (xy 35.470989 -273.621983) (xy 35.490562 -273.54795)
			(xy 35.503104 -273.511772) (xy 35.505746 -273.503334) (xy 35.505746 -273.485666) (xy 35.503104 -273.477228)
			(xy 35.490547 -273.441054) (xy 35.470951 -273.367024) (xy 35.4578 -273.291583) (xy 35.451191 -273.215289)
			(xy 35.45078 -273.177) (xy 35.451227 -273.138712) (xy 35.457845 -273.062422) (xy 35.470989 -272.986983)
			(xy 35.490562 -272.91295) (xy 35.503104 -272.876772) (xy 35.505746 -272.868334) (xy 35.505746 -272.850666)
			(xy 35.503104 -272.842228) (xy 35.491488 -272.808835) (xy 35.472969 -272.740596) (xy 35.459934 -272.6711)
			(xy 35.45586 -272.63598) (xy 35.454191 -272.625481) (xy 35.443553 -272.607104) (xy 35.435286 -272.60042)
			(xy 35.40174 -272.575385) (xy 35.339032 -272.51993) (xy 35.281811 -272.45883) (xy 35.230582 -272.392625)
			(xy 35.1858 -272.3219) (xy 35.147859 -272.247281) (xy 35.117096 -272.169428) (xy 35.093782 -272.089029)
			(xy 35.078124 -272.006796) (xy 35.07026 -271.923455) (xy 35.06978 -271.8816) (xy 33.071997 -271.8816)
			(xy 33.079462 -271.924185) (xy 33.086146 -272.001193) (xy 33.086548 -272.039842) (xy 33.086073 -272.080944)
			(xy 33.078485 -272.162797) (xy 33.063377 -272.243601) (xy 33.040879 -272.322666) (xy 33.011181 -272.399318)
			(xy 32.974538 -272.472904) (xy 32.931262 -272.542794) (xy 32.881723 -272.608394) (xy 32.826342 -272.669143)
			(xy 32.765593 -272.724524) (xy 32.699993 -272.774063) (xy 32.630102 -272.817339) (xy 32.556517 -272.853982)
			(xy 32.479864 -272.883679) (xy 32.400799 -272.906178) (xy 32.319995 -272.921286) (xy 32.238142 -272.928874)
			(xy 32.19704 -272.92935) (xy 32.153823 -272.928845) (xy 32.067798 -272.920459) (xy 31.982991 -272.903772)
			(xy 31.900201 -272.87894) (xy 31.82021 -272.846198) (xy 31.78175 -272.82648) (xy 31.76905 -272.819622)
			(xy 31.740856 -272.8214) (xy 31.643066 -272.889726) (xy 31.631636 -272.915634) (xy 31.633668 -272.930112)
			(xy 31.637481 -272.959937) (xy 31.641548 -273.019933) (xy 31.641796 -273.05) (xy 31.64135 -273.088288)
			(xy 31.634732 -273.164578) (xy 31.621588 -273.240018) (xy 31.602015 -273.31405) (xy 31.589472 -273.350228)
			(xy 31.586832 -273.358666) (xy 31.586832 -273.376334) (xy 31.589472 -273.384772) (xy 31.602028 -273.420947)
			(xy 31.621625 -273.494976) (xy 31.634776 -273.570417) (xy 31.641385 -273.646711) (xy 31.641796 -273.685)
			(xy 31.641292 -273.727348) (xy 31.633241 -273.811662) (xy 31.617212 -273.894828) (xy 31.593351 -273.976095)
			(xy 31.561872 -274.054725) (xy 31.523061 -274.130006) (xy 31.477271 -274.201258) (xy 31.424915 -274.267834)
			(xy 31.366467 -274.329132) (xy 31.302457 -274.384597) (xy 31.233465 -274.433726) (xy 31.160115 -274.476075)
			(xy 31.083072 -274.511259) (xy 31.003033 -274.538961) (xy 30.920724 -274.558929) (xy 30.836889 -274.570982)
			(xy 30.752288 -274.575013) (xy 30.667687 -274.570982) (xy 30.583852 -274.558929) (xy 30.501543 -274.538961)
			(xy 30.421504 -274.511259) (xy 30.344461 -274.476075) (xy 30.271111 -274.433726) (xy 30.202119 -274.384597)
			(xy 30.138109 -274.329132) (xy 30.079661 -274.267834) (xy 30.027305 -274.201258) (xy 29.981515 -274.130006)
			(xy 29.942704 -274.054725) (xy 29.911225 -273.976095) (xy 29.887364 -273.894828) (xy 29.871335 -273.811662)
			(xy 29.863284 -273.727348) (xy 29.86278 -273.685) (xy 20.221779 -273.685) (xy 20.219017 -273.691032)
			(xy 20.218616 -273.714878) (xy 20.223226 -273.725894) (xy 20.240151 -273.762076) (xy 20.268231 -273.836864)
			(xy 20.289492 -273.913868) (xy 20.303762 -273.992468) (xy 20.310928 -274.072031) (xy 20.311364 -274.111974)
			(xy 20.31086 -274.154322) (xy 20.302809 -274.238636) (xy 20.28678 -274.321802) (xy 20.262919 -274.403069)
			(xy 20.23144 -274.481699) (xy 20.192629 -274.55698) (xy 20.146839 -274.628232) (xy 20.094483 -274.694808)
			(xy 20.036035 -274.756106) (xy 19.972025 -274.811571) (xy 19.903033 -274.8607) (xy 19.829683 -274.903049)
			(xy 19.75264 -274.938233) (xy 19.672601 -274.965935) (xy 19.590292 -274.985903) (xy 19.506457 -274.997956)
			(xy 19.421856 -275.001987) (xy 19.337255 -274.997956) (xy 19.25342 -274.985903) (xy 19.171111 -274.965935)
			(xy 19.091072 -274.938233) (xy 19.014029 -274.903049) (xy 18.940679 -274.8607) (xy 18.871687 -274.811571)
			(xy 18.807677 -274.756106) (xy 18.749229 -274.694808) (xy 18.696873 -274.628232) (xy 18.651083 -274.55698)
			(xy 18.612272 -274.481699) (xy 18.580793 -274.403069) (xy 18.556932 -274.321802) (xy 18.540903 -274.238636)
			(xy 18.532852 -274.154322) (xy 18.532348 -274.111974) (xy 18.532872 -274.068725) (xy 18.541276 -273.982637)
			(xy 18.558002 -273.897772) (xy 18.582892 -273.814933) (xy 18.61571 -273.734903) (xy 18.635472 -273.69643)
			(xy 18.640442 -273.685571) (xy 18.640846 -273.661725) (xy 18.636234 -273.65071) (xy 18.619271 -273.614545)
			(xy 18.5912 -273.539752) (xy 18.569947 -273.462744) (xy 18.555685 -273.38414) (xy 18.548528 -273.304574)
			(xy 18.548096 -273.26463) (xy 18.548573 -273.222266) (xy 18.556629 -273.137921) (xy 18.57267 -273.054724)
			(xy 18.596551 -272.973431) (xy 18.61185 -272.933922) (xy 18.615254 -272.924266) (xy 18.61486 -272.903816)
			(xy 18.611088 -272.894298) (xy 18.592259 -272.851088) (xy 18.562805 -272.761548) (xy 18.542971 -272.669398)
			(xy 18.532981 -272.575668) (xy 18.532348 -272.528538) (xy 18.532857 -272.485289) (xy 18.541264 -272.3992)
			(xy 18.557994 -272.314335) (xy 18.582887 -272.231496) (xy 18.615708 -272.151467) (xy 18.635472 -272.112994)
			(xy 18.640466 -272.102144) (xy 18.640854 -272.07829) (xy 18.636234 -272.067274) (xy 18.619294 -272.031098)
			(xy 18.591218 -271.956309) (xy 18.56996 -271.879303) (xy 18.555693 -271.800701) (xy 18.548531 -271.721137)
			(xy 18.548096 -271.681194) (xy 18.548541 -271.641387) (xy 18.555663 -271.562093) (xy 18.569842 -271.483753)
			(xy 18.590964 -271.406993) (xy 18.61886 -271.332426) (xy 18.653307 -271.260651) (xy 18.694028 -271.19224)
			(xy 18.717006 -271.159732) (xy 18.722848 -271.151604) (xy 18.72742 -271.133316) (xy 18.716498 -271.044924)
			(xy 18.707354 -271.028414) (xy 18.699734 -271.022064) (xy 18.666718 -270.993954) (xy 18.605754 -270.932283)
			(xy 18.55108 -270.864972) (xy 18.503216 -270.792661) (xy 18.462615 -270.716035) (xy 18.429663 -270.635822)
			(xy 18.404673 -270.552784) (xy 18.387882 -270.467707) (xy 18.379449 -270.381401) (xy 18.378932 -270.338042)
			(xy 16.39022 -270.338042) (xy 16.38283 -270.417822) (xy 16.367727 -270.49863) (xy 16.345232 -270.5777)
			(xy 16.315537 -270.654356) (xy 16.278896 -270.727945) (xy 16.23562 -270.79784) (xy 16.18608 -270.863443)
			(xy 16.130698 -270.924195) (xy 16.069946 -270.979578) (xy 16.004343 -271.029118) (xy 15.934449 -271.072394)
			(xy 15.86086 -271.109036) (xy 15.784203 -271.138731) (xy 15.705134 -271.161226) (xy 15.624326 -271.176329)
			(xy 15.54247 -271.183911) (xy 15.501366 -271.18437) (xy 15.457873 -271.183869) (xy 15.3713 -271.175403)
			(xy 15.285967 -271.158524) (xy 15.20269 -271.133396) (xy 15.162276 -271.117314) (xy 15.149322 -271.111726)
			(xy 15.122144 -271.11579) (xy 15.030704 -271.18945) (xy 15.021052 -271.215104) (xy 15.023592 -271.229074)
			(xy 15.030139 -271.267986) (xy 15.037135 -271.346589) (xy 15.037562 -271.386046) (xy 15.037068 -271.428635)
			(xy 15.028908 -271.513422) (xy 15.012678 -271.597041) (xy 14.988526 -271.678723) (xy 14.956673 -271.757722)
			(xy 14.937486 -271.795748) (xy 14.932467 -271.806966) (xy 14.932485 -271.83151) (xy 14.937486 -271.842738)
			(xy 14.956684 -271.880757) (xy 14.98852 -271.959762) (xy 15.012661 -272.041447) (xy 15.028888 -272.125065)
			(xy 15.037051 -272.209851) (xy 15.037562 -272.25244) (xy 15.037079 -272.294984) (xy 15.028956 -272.379684)
			(xy 15.012777 -272.463219) (xy 14.988692 -272.544828) (xy 14.95692 -272.623761) (xy 14.917752 -272.699299)
			(xy 14.895068 -272.735294) (xy 14.890221 -272.743747) (xy 14.88654 -272.76286) (xy 14.890192 -272.781979)
			(xy 14.895068 -272.790412) (xy 14.917726 -272.82639) (xy 14.956814 -272.901905) (xy 14.98852 -272.980804)
			(xy 15.012557 -273.062368) (xy 15.028703 -273.145852) (xy 15.036813 -273.230496) (xy 15.037308 -273.273012)
			(xy 15.036805 -273.315601) (xy 15.028649 -273.400388) (xy 15.012421 -273.484006) (xy 14.98827 -273.565689)
			(xy 14.956418 -273.644688) (xy 14.937232 -273.682714) (xy 14.932239 -273.69394) (xy 14.932243 -273.718475)
			(xy 14.937232 -273.729704) (xy 14.956413 -273.767732) (xy 14.988253 -273.846734) (xy 15.012398 -273.928417)
			(xy 15.028628 -274.012033) (xy 15.036795 -274.096818) (xy 15.037308 -274.139406) (xy 15.036804 -274.181754)
			(xy 15.028753 -274.266068) (xy 15.012724 -274.349234) (xy 14.988863 -274.430501) (xy 14.957384 -274.509131)
			(xy 14.918573 -274.584412) (xy 14.872783 -274.655664) (xy 14.820427 -274.72224) (xy 14.761979 -274.783538)
			(xy 14.697969 -274.839003) (xy 14.628977 -274.888132) (xy 14.555627 -274.930481) (xy 14.478584 -274.965665)
			(xy 14.398545 -274.993367) (xy 14.316236 -275.013335) (xy 14.232401 -275.025388) (xy 14.1478 -275.029419)
			(xy 14.063199 -275.025388) (xy 13.979364 -275.013335) (xy 13.897055 -274.993367) (xy 13.817016 -274.965665)
			(xy 13.739973 -274.930481) (xy 13.666623 -274.888132) (xy 13.597631 -274.839003) (xy 13.533621 -274.783538)
			(xy 13.475173 -274.72224) (xy 13.422817 -274.655664) (xy 13.377027 -274.584412) (xy 13.338216 -274.509131)
			(xy 13.306737 -274.430501) (xy 13.282876 -274.349234) (xy 13.266847 -274.266068) (xy 13.258796 -274.181754)
			(xy 13.258292 -274.139406) (xy 1.651254 -274.139406) (xy 1.651254 -276.980904) (xy 1.652778 -277.03145)
			(xy 1.651254 -277.081996) (xy 1.651254 -277.895304) (xy 13.241782 -277.895304) (xy 13.242292 -277.852715)
			(xy 13.250447 -277.767928) (xy 13.266674 -277.68431) (xy 13.290823 -277.602627) (xy 13.322673 -277.523628)
			(xy 13.341858 -277.485602) (xy 13.347048 -277.474419) (xy 13.347051 -277.449793) (xy 13.341858 -277.438612)
			(xy 13.322682 -277.400582) (xy 13.290842 -277.32158) (xy 13.266695 -277.239898) (xy 13.250464 -277.156282)
			(xy 13.242296 -277.071498) (xy 13.241782 -277.02891) (xy 13.242286 -276.986562) (xy 13.250337 -276.902248)
			(xy 13.266366 -276.819082) (xy 13.290227 -276.737815) (xy 13.321706 -276.659185) (xy 13.360517 -276.583904)
			(xy 13.406307 -276.512652) (xy 13.458663 -276.446076) (xy 13.517111 -276.384778) (xy 13.581121 -276.329313)
			(xy 13.650113 -276.280184) (xy 13.723463 -276.237835) (xy 13.800506 -276.202651) (xy 13.880545 -276.174949)
			(xy 13.962854 -276.154981) (xy 14.046689 -276.142928) (xy 14.13129 -276.138898) (xy 14.215891 -276.142928)
			(xy 14.299726 -276.154981) (xy 14.382035 -276.174949) (xy 14.462074 -276.202651) (xy 14.539117 -276.237835)
			(xy 14.612467 -276.280184) (xy 14.681459 -276.329313) (xy 14.745469 -276.384778) (xy 14.803917 -276.446076)
			(xy 14.856273 -276.512652) (xy 14.902063 -276.583904) (xy 14.940874 -276.659185) (xy 14.972353 -276.737815)
			(xy 14.996214 -276.819082) (xy 15.012243 -276.902248) (xy 15.020294 -276.986562) (xy 15.020798 -277.02891)
			(xy 15.020296 -277.071499) (xy 15.012139 -277.156286) (xy 14.995911 -277.239904) (xy 14.97176 -277.321587)
			(xy 14.939908 -277.400586) (xy 14.920722 -277.438612) (xy 14.915731 -277.449839) (xy 14.915734 -277.474373)
			(xy 14.920722 -277.485602) (xy 14.939901 -277.523631) (xy 14.971741 -277.602632) (xy 14.995887 -277.684315)
			(xy 15.012118 -277.767931) (xy 15.020285 -277.852716) (xy 15.020798 -277.895304) (xy 15.020294 -277.937652)
			(xy 15.012478 -278.01951) (xy 18.523966 -278.01951) (xy 18.524503 -277.976262) (xy 18.532904 -277.890174)
			(xy 18.549626 -277.805309) (xy 18.574513 -277.72247) (xy 18.607329 -277.642439) (xy 18.62709 -277.603966)
			(xy 18.632036 -277.593098) (xy 18.632454 -277.569261) (xy 18.627852 -277.558246) (xy 18.610904 -277.522074)
			(xy 18.582829 -277.447283) (xy 18.561573 -277.370277) (xy 18.547308 -277.291674) (xy 18.540148 -277.212109)
			(xy 18.539714 -277.172166) (xy 18.540218 -277.129818) (xy 18.548269 -277.045504) (xy 18.564298 -276.962338)
			(xy 18.588159 -276.881071) (xy 18.619638 -276.802441) (xy 18.658449 -276.72716) (xy 18.704239 -276.655908)
			(xy 18.756595 -276.589332) (xy 18.815043 -276.528034) (xy 18.879053 -276.472569) (xy 18.948045 -276.42344)
			(xy 19.021395 -276.381091) (xy 19.098438 -276.345907) (xy 19.178477 -276.318205) (xy 19.260786 -276.298237)
			(xy 19.344621 -276.286184) (xy 19.429222 -276.282154) (xy 19.513823 -276.286184) (xy 19.597658 -276.298237)
			(xy 19.679967 -276.318205) (xy 19.760006 -276.345907) (xy 19.837049 -276.381091) (xy 19.910399 -276.42344)
			(xy 19.979391 -276.472569) (xy 20.043401 -276.528034) (xy 20.101849 -276.589332) (xy 20.154205 -276.655908)
			(xy 20.199995 -276.72716) (xy 20.238806 -276.802441) (xy 20.270285 -276.881071) (xy 20.294146 -276.962338)
			(xy 20.310175 -277.045504) (xy 20.318226 -277.129818) (xy 20.31873 -277.172166) (xy 20.318225 -277.215415)
			(xy 20.309817 -277.301504) (xy 20.293087 -277.386369) (xy 20.268193 -277.469208) (xy 20.23537 -277.549237)
			(xy 20.215606 -277.58771) (xy 20.210611 -277.59856) (xy 20.210224 -277.622414) (xy 20.214844 -277.63343)
			(xy 20.231783 -277.669606) (xy 20.25986 -277.744395) (xy 20.281118 -277.821401) (xy 20.295385 -277.900003)
			(xy 20.302547 -277.979567) (xy 20.302982 -278.01951) (xy 20.302478 -278.061858) (xy 20.294427 -278.146172)
			(xy 20.278398 -278.229338) (xy 20.254537 -278.310605) (xy 20.223058 -278.389235) (xy 20.184247 -278.464516)
			(xy 20.138457 -278.535768) (xy 20.086101 -278.602344) (xy 20.052103 -278.638) (xy 29.86278 -278.638)
			(xy 29.863227 -278.599712) (xy 29.869845 -278.523422) (xy 29.882989 -278.447983) (xy 29.902562 -278.37395)
			(xy 29.915104 -278.337772) (xy 29.917746 -278.329334) (xy 29.917746 -278.311666) (xy 29.915104 -278.303228)
			(xy 29.902547 -278.267054) (xy 29.882951 -278.193024) (xy 29.8698 -278.117583) (xy 29.863191 -278.041289)
			(xy 29.86278 -278.003) (xy 29.863227 -277.964712) (xy 29.869845 -277.888422) (xy 29.882989 -277.812983)
			(xy 29.902562 -277.73895) (xy 29.915104 -277.702772) (xy 29.917746 -277.694334) (xy 29.917746 -277.676666)
			(xy 29.915104 -277.668228) (xy 29.902547 -277.632054) (xy 29.882951 -277.558024) (xy 29.8698 -277.482583)
			(xy 29.863191 -277.406289) (xy 29.86278 -277.368) (xy 29.863284 -277.325652) (xy 29.871335 -277.241338)
			(xy 29.887364 -277.158172) (xy 29.911225 -277.076905) (xy 29.942704 -276.998275) (xy 29.981515 -276.922994)
			(xy 30.027305 -276.851742) (xy 30.079661 -276.785166) (xy 30.138109 -276.723868) (xy 30.202119 -276.668403)
			(xy 30.271111 -276.619274) (xy 30.344461 -276.576925) (xy 30.421504 -276.541741) (xy 30.501543 -276.514039)
			(xy 30.583852 -276.494071) (xy 30.667687 -276.482018) (xy 30.752288 -276.477988) (xy 30.836889 -276.482018)
			(xy 30.920724 -276.494071) (xy 31.003033 -276.514039) (xy 31.083072 -276.541741) (xy 31.160115 -276.576925)
			(xy 31.233465 -276.619274) (xy 31.302457 -276.668403) (xy 31.366467 -276.723868) (xy 31.424915 -276.785166)
			(xy 31.477271 -276.851742) (xy 31.523061 -276.922994) (xy 31.561872 -276.998275) (xy 31.593351 -277.076905)
			(xy 31.617212 -277.158172) (xy 31.633241 -277.241338) (xy 31.641292 -277.325652) (xy 31.641796 -277.368)
			(xy 31.64135 -277.406288) (xy 31.634732 -277.482578) (xy 31.621588 -277.558018) (xy 31.602015 -277.63205)
			(xy 31.589472 -277.668228) (xy 31.586832 -277.676666) (xy 31.586832 -277.694334) (xy 31.589472 -277.702772)
			(xy 31.602028 -277.738947) (xy 31.621625 -277.812976) (xy 31.634776 -277.888417) (xy 31.641385 -277.964711)
			(xy 31.641796 -278.003) (xy 31.64135 -278.041288) (xy 31.634732 -278.117578) (xy 31.621588 -278.193018)
			(xy 31.602015 -278.26705) (xy 31.589472 -278.303228) (xy 31.586832 -278.311666) (xy 31.586832 -278.329334)
			(xy 31.589472 -278.337772) (xy 31.602028 -278.373947) (xy 31.621625 -278.447976) (xy 31.634776 -278.523417)
			(xy 31.641385 -278.599711) (xy 31.641796 -278.638) (xy 31.641292 -278.680348) (xy 31.633241 -278.764662)
			(xy 31.633176 -278.765) (xy 35.45078 -278.765) (xy 35.451227 -278.726712) (xy 35.457845 -278.650422)
			(xy 35.470989 -278.574983) (xy 35.490562 -278.50095) (xy 35.503104 -278.464772) (xy 35.505746 -278.456334)
			(xy 35.505746 -278.438666) (xy 35.503104 -278.430228) (xy 35.490547 -278.394054) (xy 35.470951 -278.320024)
			(xy 35.4578 -278.244583) (xy 35.451191 -278.168289) (xy 35.45078 -278.13) (xy 35.451227 -278.091712)
			(xy 35.457845 -278.015422) (xy 35.470989 -277.939983) (xy 35.490562 -277.86595) (xy 35.503104 -277.829772)
			(xy 35.505746 -277.821334) (xy 35.505746 -277.803666) (xy 35.503104 -277.795228) (xy 35.490547 -277.759054)
			(xy 35.470951 -277.685024) (xy 35.4578 -277.609583) (xy 35.451191 -277.533289) (xy 35.45078 -277.495)
			(xy 35.451284 -277.452652) (xy 35.459335 -277.368338) (xy 35.475364 -277.285172) (xy 35.499225 -277.203905)
			(xy 35.530704 -277.125275) (xy 35.569515 -277.049994) (xy 35.615305 -276.978742) (xy 35.667661 -276.912166)
			(xy 35.726109 -276.850868) (xy 35.790119 -276.795403) (xy 35.859111 -276.746274) (xy 35.932461 -276.703925)
			(xy 36.009504 -276.668741) (xy 36.089543 -276.641039) (xy 36.171852 -276.621071) (xy 36.255687 -276.609018)
			(xy 36.340288 -276.604988) (xy 36.424889 -276.609018) (xy 36.508724 -276.621071) (xy 36.591033 -276.641039)
			(xy 36.671072 -276.668741) (xy 36.748115 -276.703925) (xy 36.821465 -276.746274) (xy 36.890457 -276.795403)
			(xy 36.954467 -276.850868) (xy 37.012915 -276.912166) (xy 37.065271 -276.978742) (xy 37.111061 -277.049994)
			(xy 37.149872 -277.125275) (xy 37.181351 -277.203905) (xy 37.205212 -277.285172) (xy 37.221241 -277.368338)
			(xy 37.229292 -277.452652) (xy 37.229796 -277.495) (xy 37.22935 -277.533288) (xy 37.222732 -277.609578)
			(xy 37.209588 -277.685018) (xy 37.190015 -277.75905) (xy 37.177472 -277.795228) (xy 37.174832 -277.803666)
			(xy 37.174832 -277.821334) (xy 37.177472 -277.829772) (xy 37.190028 -277.865947) (xy 37.209625 -277.939976)
			(xy 37.222776 -278.015417) (xy 37.229385 -278.091711) (xy 37.229796 -278.13) (xy 37.22935 -278.168288)
			(xy 37.222732 -278.244578) (xy 37.209588 -278.320018) (xy 37.190015 -278.39405) (xy 37.177472 -278.430228)
			(xy 37.174832 -278.438666) (xy 37.174832 -278.456334) (xy 37.177472 -278.464772) (xy 37.190028 -278.500947)
			(xy 37.209625 -278.574976) (xy 37.222776 -278.650417) (xy 37.229385 -278.726711) (xy 37.229796 -278.765)
			(xy 37.229292 -278.807348) (xy 37.221241 -278.891662) (xy 37.205212 -278.974828) (xy 37.181351 -279.056095)
			(xy 37.149872 -279.134725) (xy 37.111061 -279.210006) (xy 37.065271 -279.281258) (xy 37.012915 -279.347834)
			(xy 36.954467 -279.409132) (xy 36.890457 -279.464597) (xy 36.821465 -279.513726) (xy 36.748115 -279.556075)
			(xy 36.671072 -279.591259) (xy 36.591033 -279.618961) (xy 36.508724 -279.638929) (xy 36.424889 -279.650982)
			(xy 36.340288 -279.655013) (xy 36.255687 -279.650982) (xy 36.171852 -279.638929) (xy 36.089543 -279.618961)
			(xy 36.009504 -279.591259) (xy 35.932461 -279.556075) (xy 35.859111 -279.513726) (xy 35.790119 -279.464597)
			(xy 35.726109 -279.409132) (xy 35.667661 -279.347834) (xy 35.615305 -279.281258) (xy 35.569515 -279.210006)
			(xy 35.530704 -279.134725) (xy 35.499225 -279.056095) (xy 35.475364 -278.974828) (xy 35.459335 -278.891662)
			(xy 35.451284 -278.807348) (xy 35.45078 -278.765) (xy 31.633176 -278.765) (xy 31.617212 -278.847828)
			(xy 31.593351 -278.929095) (xy 31.561872 -279.007725) (xy 31.523061 -279.083006) (xy 31.477271 -279.154258)
			(xy 31.424915 -279.220834) (xy 31.366467 -279.282132) (xy 31.302457 -279.337597) (xy 31.233465 -279.386726)
			(xy 31.160115 -279.429075) (xy 31.083072 -279.464259) (xy 31.003033 -279.491961) (xy 30.920724 -279.511929)
			(xy 30.836889 -279.523982) (xy 30.752288 -279.528013) (xy 30.667687 -279.523982) (xy 30.583852 -279.511929)
			(xy 30.501543 -279.491961) (xy 30.421504 -279.464259) (xy 30.344461 -279.429075) (xy 30.271111 -279.386726)
			(xy 30.202119 -279.337597) (xy 30.138109 -279.282132) (xy 30.079661 -279.220834) (xy 30.027305 -279.154258)
			(xy 29.981515 -279.083006) (xy 29.942704 -279.007725) (xy 29.911225 -278.929095) (xy 29.887364 -278.847828)
			(xy 29.871335 -278.764662) (xy 29.863284 -278.680348) (xy 29.86278 -278.638) (xy 20.052103 -278.638)
			(xy 20.027653 -278.663642) (xy 19.963643 -278.719107) (xy 19.894651 -278.768236) (xy 19.821301 -278.810585)
			(xy 19.744258 -278.845769) (xy 19.664219 -278.873471) (xy 19.58191 -278.893439) (xy 19.498075 -278.905492)
			(xy 19.413474 -278.909523) (xy 19.328873 -278.905492) (xy 19.245038 -278.893439) (xy 19.162729 -278.873471)
			(xy 19.08269 -278.845769) (xy 19.005647 -278.810585) (xy 18.932297 -278.768236) (xy 18.863305 -278.719107)
			(xy 18.799295 -278.663642) (xy 18.740847 -278.602344) (xy 18.688491 -278.535768) (xy 18.642701 -278.464516)
			(xy 18.60389 -278.389235) (xy 18.572411 -278.310605) (xy 18.54855 -278.229338) (xy 18.532521 -278.146172)
			(xy 18.52447 -278.061858) (xy 18.523966 -278.01951) (xy 15.012478 -278.01951) (xy 15.012243 -278.021966)
			(xy 14.996214 -278.105132) (xy 14.972353 -278.186399) (xy 14.940874 -278.265029) (xy 14.902063 -278.34031)
			(xy 14.856273 -278.411562) (xy 14.803917 -278.478138) (xy 14.745469 -278.539436) (xy 14.681459 -278.594901)
			(xy 14.612467 -278.64403) (xy 14.539117 -278.686379) (xy 14.462074 -278.721563) (xy 14.382035 -278.749265)
			(xy 14.299726 -278.769233) (xy 14.215891 -278.781286) (xy 14.13129 -278.785317) (xy 14.046689 -278.781286)
			(xy 13.962854 -278.769233) (xy 13.880545 -278.749265) (xy 13.800506 -278.721563) (xy 13.723463 -278.686379)
			(xy 13.650113 -278.64403) (xy 13.581121 -278.594901) (xy 13.517111 -278.539436) (xy 13.458663 -278.478138)
			(xy 13.406307 -278.411562) (xy 13.360517 -278.34031) (xy 13.321706 -278.265029) (xy 13.290227 -278.186399)
			(xy 13.266366 -278.105132) (xy 13.250337 -278.021966) (xy 13.242286 -277.937652) (xy 13.241782 -277.895304)
			(xy 1.651254 -277.895304) (xy 1.651254 -281.2542) (xy 3.936492 -281.2542) (xy 3.937075 -281.207804)
			(xy 3.94672 -281.115516) (xy 3.965916 -281.024732) (xy 3.994454 -280.936439) (xy 4.012692 -280.893774)
			(xy 4.016597 -280.883852) (xy 4.016597 -280.862548) (xy 4.012692 -280.852626) (xy 3.994447 -280.809964)
			(xy 3.965903 -280.721671) (xy 3.94671 -280.630886) (xy 3.937077 -280.538596) (xy 3.936492 -280.4922)
			(xy 3.936967 -280.451098) (xy 3.944552 -280.369243) (xy 3.959657 -280.288438) (xy 3.982153 -280.209371)
			(xy 4.011849 -280.132717) (xy 4.048491 -280.05913) (xy 4.091766 -279.989238) (xy 4.141306 -279.923637)
			(xy 4.196687 -279.862887) (xy 4.257437 -279.807506) (xy 4.323038 -279.757966) (xy 4.39293 -279.714691)
			(xy 4.466517 -279.678049) (xy 4.543171 -279.648353) (xy 4.622238 -279.625857) (xy 4.703043 -279.610752)
			(xy 4.784898 -279.603167) (xy 4.826 -279.602692) (xy 4.872396 -279.603275) (xy 4.964684 -279.61292)
			(xy 5.055468 -279.632116) (xy 5.143761 -279.660654) (xy 5.186426 -279.678892) (xy 5.196366 -279.682712)
			(xy 5.217634 -279.682712) (xy 5.227574 -279.678892) (xy 5.270236 -279.660647) (xy 5.358529 -279.632103)
			(xy 5.449314 -279.61291) (xy 5.541604 -279.603277) (xy 5.588 -279.602692) (xy 5.634396 -279.603275)
			(xy 5.726684 -279.61292) (xy 5.817468 -279.632116) (xy 5.905761 -279.660654) (xy 5.948426 -279.678892)
			(xy 5.958366 -279.682712) (xy 5.979634 -279.682712) (xy 5.989574 -279.678892) (xy 6.032236 -279.660647)
			(xy 6.120529 -279.632103) (xy 6.211314 -279.61291) (xy 6.303604 -279.603277) (xy 6.35 -279.602692)
			(xy 6.391102 -279.603167) (xy 6.472957 -279.610752) (xy 6.553762 -279.625857) (xy 6.632829 -279.648353)
			(xy 6.709483 -279.678049) (xy 6.78307 -279.714691) (xy 6.852962 -279.757966) (xy 6.918563 -279.807506)
			(xy 6.979313 -279.862887) (xy 7.034694 -279.923637) (xy 7.084234 -279.989238) (xy 7.127509 -280.05913)
			(xy 7.164151 -280.132717) (xy 7.193847 -280.209371) (xy 7.216343 -280.288438) (xy 7.231448 -280.369243)
			(xy 7.239033 -280.451098) (xy 7.239508 -280.4922) (xy 7.238925 -280.538596) (xy 7.22928 -280.630884)
			(xy 7.210084 -280.721668) (xy 7.181546 -280.809961) (xy 7.163308 -280.852626) (xy 7.159403 -280.862548)
			(xy 7.159403 -280.883852) (xy 7.163308 -280.893774) (xy 7.181553 -280.936436) (xy 7.210097 -281.024729)
			(xy 7.22435 -281.092148) (xy 44.946824 -281.092148) (xy 44.947421 -281.045753) (xy 44.957062 -280.953465)
			(xy 44.976253 -280.862681) (xy 45.004788 -280.774387) (xy 45.023024 -280.731722) (xy 45.026815 -280.721773)
			(xy 45.026834 -280.700513) (xy 45.023024 -280.690574) (xy 45.004797 -280.647904) (xy 44.976248 -280.559615)
			(xy 44.95705 -280.468832) (xy 44.947411 -280.376543) (xy 44.946824 -280.330148) (xy 44.947298 -280.289045)
			(xy 44.954879 -280.207188) (xy 44.969981 -280.126381) (xy 44.992475 -280.047312) (xy 45.022169 -279.970655)
			(xy 45.058809 -279.897066) (xy 45.102084 -279.827172) (xy 45.151623 -279.761568) (xy 45.207005 -279.700816)
			(xy 45.267756 -279.645434) (xy 45.333358 -279.595893) (xy 45.403252 -279.552617) (xy 45.476841 -279.515975)
			(xy 45.553496 -279.48628) (xy 45.632565 -279.463785) (xy 45.713373 -279.448681) (xy 45.795229 -279.441099)
			(xy 45.836332 -279.44064) (xy 45.882727 -279.441243) (xy 45.975015 -279.450881) (xy 46.065799 -279.470071)
			(xy 46.154093 -279.498605) (xy 46.196758 -279.51684) (xy 46.206698 -279.52066) (xy 46.227966 -279.52066)
			(xy 46.237906 -279.51684) (xy 46.280565 -279.498588) (xy 46.368858 -279.470045) (xy 46.459645 -279.450854)
			(xy 46.551936 -279.441223) (xy 46.598332 -279.44064) (xy 46.644727 -279.441243) (xy 46.737015 -279.450881)
			(xy 46.827799 -279.470071) (xy 46.916093 -279.498605) (xy 46.958758 -279.51684) (xy 46.968698 -279.52066)
			(xy 46.989966 -279.52066) (xy 46.999906 -279.51684) (xy 47.042565 -279.498588) (xy 47.130858 -279.470045)
			(xy 47.221645 -279.450854) (xy 47.313936 -279.441223) (xy 47.360332 -279.44064) (xy 47.401437 -279.441022)
			(xy 47.483296 -279.44861) (xy 47.564106 -279.463719) (xy 47.643177 -279.48622) (xy 47.719835 -279.515921)
			(xy 47.793425 -279.552568) (xy 47.86332 -279.595849) (xy 47.928923 -279.645395) (xy 47.989674 -279.700782)
			(xy 48.045056 -279.761539) (xy 48.094596 -279.827146) (xy 48.137871 -279.897045) (xy 48.174511 -279.970638)
			(xy 48.204205 -280.047299) (xy 48.226699 -280.126372) (xy 48.241801 -280.207183) (xy 48.249382 -280.289043)
			(xy 48.24984 -280.330148) (xy 48.249245 -280.376543) (xy 48.239604 -280.468831) (xy 48.220412 -280.559615)
			(xy 48.191877 -280.647909) (xy 48.17364 -280.690574) (xy 48.169793 -280.700505) (xy 48.169812 -280.721781)
			(xy 48.17364 -280.731722) (xy 48.19187 -280.77439) (xy 48.220417 -280.862681) (xy 48.239614 -280.953464)
			(xy 48.249252 -281.045752) (xy 48.24984 -281.092148) (xy 48.249379 -281.13325) (xy 48.24179 -281.215104)
			(xy 48.226682 -281.295908) (xy 48.204182 -281.374974) (xy 48.174484 -281.451627) (xy 48.13784 -281.525212)
			(xy 48.094563 -281.595103) (xy 48.045023 -281.660703) (xy 47.989641 -281.721453) (xy 47.928891 -281.776833)
			(xy 47.86329 -281.826373) (xy 47.793398 -281.869648) (xy 47.719812 -281.906291) (xy 47.643159 -281.935987)
			(xy 47.564093 -281.958485) (xy 47.483288 -281.973593) (xy 47.401434 -281.98118) (xy 47.360332 -281.981656)
			(xy 47.313937 -281.981066) (xy 47.221648 -281.971424) (xy 47.130864 -281.95223) (xy 47.042571 -281.923693)
			(xy 46.999906 -281.905456) (xy 46.989966 -281.901636) (xy 46.968698 -281.901636) (xy 46.958758 -281.905456)
			(xy 46.91609 -281.923687) (xy 46.8278 -281.952235) (xy 46.737017 -281.971432) (xy 46.644728 -281.981069)
			(xy 46.598332 -281.981656) (xy 46.551937 -281.981066) (xy 46.459648 -281.971424) (xy 46.368864 -281.95223)
			(xy 46.280571 -281.923693) (xy 46.237906 -281.905456) (xy 46.227966 -281.901636) (xy 46.206698 -281.901636)
			(xy 46.196758 -281.905456) (xy 46.15409 -281.923687) (xy 46.0658 -281.952235) (xy 45.975017 -281.971432)
			(xy 45.882728 -281.981069) (xy 45.836332 -281.981656) (xy 45.795231 -281.981103) (xy 45.713381 -281.973521)
			(xy 45.632579 -281.95842) (xy 45.553515 -281.935928) (xy 45.476863 -281.906236) (xy 45.403278 -281.869599)
			(xy 45.333388 -281.826329) (xy 45.267788 -281.776795) (xy 45.207038 -281.721419) (xy 45.151657 -281.660674)
			(xy 45.102116 -281.595078) (xy 45.05884 -281.525192) (xy 45.022196 -281.45161) (xy 44.992498 -281.374961)
			(xy 44.969998 -281.295899) (xy 44.95489 -281.215099) (xy 44.947301 -281.133249) (xy 44.946824 -281.092148)
			(xy 7.22435 -281.092148) (xy 7.22929 -281.115514) (xy 7.238923 -281.207804) (xy 7.239508 -281.2542)
			(xy 7.239033 -281.295302) (xy 7.231448 -281.377157) (xy 7.216343 -281.457962) (xy 7.193847 -281.537029)
			(xy 7.164151 -281.613683) (xy 7.127509 -281.68727) (xy 7.084234 -281.757162) (xy 7.034694 -281.822763)
			(xy 6.979313 -281.883513) (xy 6.918563 -281.938894) (xy 6.852962 -281.988434) (xy 6.78307 -282.031709)
			(xy 6.709483 -282.068351) (xy 6.632829 -282.098047) (xy 6.553762 -282.120543) (xy 6.472957 -282.135648)
			(xy 6.391102 -282.143233) (xy 6.35 -282.143708) (xy 6.303604 -282.143125) (xy 6.211316 -282.13348)
			(xy 6.120532 -282.114284) (xy 6.032239 -282.085746) (xy 5.989574 -282.067508) (xy 5.979634 -282.063688)
			(xy 5.958366 -282.063688) (xy 5.948426 -282.067508) (xy 5.905764 -282.085753) (xy 5.817471 -282.114297)
			(xy 5.726686 -282.13349) (xy 5.634396 -282.143123) (xy 5.588 -282.143708) (xy 5.541604 -282.143125)
			(xy 5.449316 -282.13348) (xy 5.358532 -282.114284) (xy 5.270239 -282.085746) (xy 5.227574 -282.067508)
			(xy 5.217634 -282.063688) (xy 5.196366 -282.063688) (xy 5.186426 -282.067508) (xy 5.143764 -282.085753)
			(xy 5.055471 -282.114297) (xy 4.964686 -282.13349) (xy 4.872396 -282.143123) (xy 4.826 -282.143708)
			(xy 4.784898 -282.143233) (xy 4.703043 -282.135648) (xy 4.622238 -282.120543) (xy 4.543171 -282.098047)
			(xy 4.466517 -282.068351) (xy 4.39293 -282.031709) (xy 4.323038 -281.988434) (xy 4.257437 -281.938894)
			(xy 4.196687 -281.883513) (xy 4.141306 -281.822763) (xy 4.091766 -281.757162) (xy 4.048491 -281.68727)
			(xy 4.011849 -281.613683) (xy 3.982153 -281.537029) (xy 3.959657 -281.457962) (xy 3.944552 -281.377157)
			(xy 3.936967 -281.295302) (xy 3.936492 -281.2542) (xy 1.651254 -281.2542) (xy 1.651254 -282.060904)
			(xy 1.652778 -282.11145) (xy 1.651254 -282.161996) (xy 1.651254 -283.32042) (xy 15.42567 -283.32042)
			(xy 15.42567 -283.235724) (xy 15.433721 -283.15141) (xy 15.44975 -283.068244) (xy 15.473611 -282.986977)
			(xy 15.50509 -282.908347) (xy 15.543901 -282.833066) (xy 15.589691 -282.761814) (xy 15.642047 -282.695238)
			(xy 15.700495 -282.63394) (xy 15.764505 -282.578475) (xy 15.833497 -282.529346) (xy 15.906847 -282.486997)
			(xy 15.98389 -282.451813) (xy 16.063929 -282.424111) (xy 16.146238 -282.404143) (xy 16.230073 -282.39209)
			(xy 16.314674 -282.38806) (xy 16.399275 -282.39209) (xy 16.48311 -282.404143) (xy 16.565419 -282.424111)
			(xy 16.645458 -282.451813) (xy 16.722501 -282.486997) (xy 16.795851 -282.529346) (xy 16.864843 -282.578475)
			(xy 16.928853 -282.63394) (xy 16.987301 -282.695238) (xy 17.039657 -282.761814) (xy 17.085447 -282.833066)
			(xy 17.124258 -282.908347) (xy 17.155737 -282.986977) (xy 17.179598 -283.068244) (xy 17.195627 -283.15141)
			(xy 17.203678 -283.235724) (xy 17.204182 -283.278072) (xy 17.203678 -283.32042) (xy 17.195627 -283.404734)
			(xy 17.179598 -283.4879) (xy 17.155737 -283.569167) (xy 17.124258 -283.647797) (xy 17.085447 -283.723078)
			(xy 17.039657 -283.79433) (xy 17.001463 -283.842898) (xy 32.683446 -283.842898) (xy 32.683446 -283.758202)
			(xy 32.691497 -283.673888) (xy 32.707526 -283.590722) (xy 32.731387 -283.509455) (xy 32.762866 -283.430825)
			(xy 32.801677 -283.355544) (xy 32.847467 -283.284292) (xy 32.899823 -283.217716) (xy 32.958271 -283.156418)
			(xy 33.022281 -283.100953) (xy 33.091273 -283.051824) (xy 33.164623 -283.009475) (xy 33.241666 -282.974291)
			(xy 33.321705 -282.946589) (xy 33.404014 -282.926621) (xy 33.487849 -282.914568) (xy 33.57245 -282.910538)
			(xy 33.657051 -282.914568) (xy 33.740886 -282.926621) (xy 33.823195 -282.946589) (xy 33.903234 -282.974291)
			(xy 33.980277 -283.009475) (xy 34.053627 -283.051824) (xy 34.122619 -283.100953) (xy 34.186629 -283.156418)
			(xy 34.245077 -283.217716) (xy 34.297433 -283.284292) (xy 34.343223 -283.355544) (xy 34.382034 -283.430825)
			(xy 34.413513 -283.509455) (xy 34.437374 -283.590722) (xy 34.453403 -283.673888) (xy 34.461454 -283.758202)
			(xy 34.461958 -283.80055) (xy 34.461454 -283.842898) (xy 34.453403 -283.927212) (xy 34.437374 -284.010378)
			(xy 34.413513 -284.091645) (xy 34.382034 -284.170275) (xy 34.343223 -284.245556) (xy 34.297433 -284.316808)
			(xy 34.245077 -284.383384) (xy 34.186629 -284.444682) (xy 34.122619 -284.500147) (xy 34.053627 -284.549276)
			(xy 33.980277 -284.591625) (xy 33.903234 -284.626809) (xy 33.823195 -284.654511) (xy 33.740886 -284.674479)
			(xy 33.657051 -284.686532) (xy 33.57245 -284.690563) (xy 33.487849 -284.686532) (xy 33.404014 -284.674479)
			(xy 33.321705 -284.654511) (xy 33.241666 -284.626809) (xy 33.164623 -284.591625) (xy 33.091273 -284.549276)
			(xy 33.022281 -284.500147) (xy 32.958271 -284.444682) (xy 32.899823 -284.383384) (xy 32.847467 -284.316808)
			(xy 32.801677 -284.245556) (xy 32.762866 -284.170275) (xy 32.731387 -284.091645) (xy 32.707526 -284.010378)
			(xy 32.691497 -283.927212) (xy 32.683446 -283.842898) (xy 17.001463 -283.842898) (xy 16.987301 -283.860906)
			(xy 16.928853 -283.922204) (xy 16.864843 -283.977669) (xy 16.795851 -284.026798) (xy 16.722501 -284.069147)
			(xy 16.645458 -284.104331) (xy 16.565419 -284.132033) (xy 16.48311 -284.152001) (xy 16.399275 -284.164054)
			(xy 16.314674 -284.168085) (xy 16.230073 -284.164054) (xy 16.146238 -284.152001) (xy 16.063929 -284.132033)
			(xy 15.98389 -284.104331) (xy 15.906847 -284.069147) (xy 15.833497 -284.026798) (xy 15.764505 -283.977669)
			(xy 15.700495 -283.922204) (xy 15.642047 -283.860906) (xy 15.589691 -283.79433) (xy 15.543901 -283.723078)
			(xy 15.50509 -283.647797) (xy 15.473611 -283.569167) (xy 15.44975 -283.4879) (xy 15.433721 -283.404734)
			(xy 15.42567 -283.32042) (xy 1.651254 -283.32042) (xy 1.651254 -287.140904) (xy 1.652778 -287.19145)
			(xy 1.651254 -287.241996) (xy 1.651254 -292.220904) (xy 1.652778 -292.27145) (xy 1.651254 -292.321996)
			(xy 1.651254 -297.300904) (xy 1.652778 -297.35145) (xy 1.651254 -297.401996) (xy 1.651254 -302.380904)
			(xy 1.652778 -302.43145) (xy 1.651254 -302.481996) (xy 1.651254 -303.310036) (xy 5.378704 -303.310036)
			(xy 5.3792 -303.258545) (xy 5.387216 -303.155875) (xy 5.403199 -303.05414) (xy 5.427052 -302.953958)
			(xy 5.45863 -302.855937) (xy 5.497742 -302.76067) (xy 5.544151 -302.668738) (xy 5.597574 -302.580696)
			(xy 5.657688 -302.497079) (xy 5.724128 -302.418395) (xy 5.759958 -302.381412) (xy 5.767324 -302.3743)
			(xy 5.77469 -302.356012) (xy 5.77469 -302.264064) (xy 5.767324 -302.245776) (xy 5.759958 -302.238664)
			(xy 5.724127 -302.201681) (xy 5.657687 -302.122997) (xy 5.597573 -302.039381) (xy 5.54415 -301.951339)
			(xy 5.497742 -301.859406) (xy 5.45863 -301.76414) (xy 5.427051 -301.666118) (xy 5.403198 -301.565936)
			(xy 5.387216 -301.464201) (xy 5.3792 -301.361531) (xy 5.3792 -301.258549) (xy 5.387216 -301.155879)
			(xy 5.403198 -301.054144) (xy 5.427051 -300.953962) (xy 5.45863 -300.85594) (xy 5.497742 -300.760674)
			(xy 5.54415 -300.668741) (xy 5.597573 -300.580699) (xy 5.657687 -300.497083) (xy 5.724127 -300.418399)
			(xy 5.759958 -300.381416) (xy 5.767324 -300.374304) (xy 5.77469 -300.356016) (xy 5.77469 -300.264068)
			(xy 5.767324 -300.24578) (xy 5.759958 -300.238668) (xy 5.724127 -300.201685) (xy 5.657687 -300.123001)
			(xy 5.597573 -300.039385) (xy 5.54415 -299.951343) (xy 5.497741 -299.85941) (xy 5.458629 -299.764144)
			(xy 5.427051 -299.666122) (xy 5.403198 -299.56594) (xy 5.387215 -299.464205) (xy 5.379199 -299.361535)
			(xy 5.379199 -299.258553) (xy 5.387215 -299.155883) (xy 5.403198 -299.054148) (xy 5.427051 -298.953966)
			(xy 5.458629 -298.855944) (xy 5.497741 -298.760678) (xy 5.54415 -298.668745) (xy 5.597573 -298.580703)
			(xy 5.657687 -298.497087) (xy 5.724127 -298.418403) (xy 5.759958 -298.38142) (xy 5.767324 -298.374308)
			(xy 5.77469 -298.35602) (xy 5.77469 -298.264072) (xy 5.767324 -298.245784) (xy 5.759958 -298.238672)
			(xy 5.724125 -298.201691) (xy 5.657685 -298.123007) (xy 5.597571 -298.03939) (xy 5.544148 -297.951348)
			(xy 5.49774 -297.859415) (xy 5.458628 -297.764149) (xy 5.42705 -297.666127) (xy 5.403197 -297.565945)
			(xy 5.387214 -297.46421) (xy 5.379198 -297.36154) (xy 5.379199 -297.258557) (xy 5.387214 -297.155887)
			(xy 5.403197 -297.054152) (xy 5.42705 -296.95397) (xy 5.458629 -296.855949) (xy 5.497741 -296.760682)
			(xy 5.54415 -296.668749) (xy 5.597573 -296.580707) (xy 5.657687 -296.497091) (xy 5.724127 -296.418407)
			(xy 5.759958 -296.381424) (xy 5.767324 -296.374312) (xy 5.77469 -296.356024) (xy 5.77469 -296.264076)
			(xy 5.767324 -296.245788) (xy 5.759958 -296.238676) (xy 5.724129 -296.201691) (xy 5.657689 -296.123007)
			(xy 5.597575 -296.039391) (xy 5.544152 -295.951349) (xy 5.497743 -295.859417) (xy 5.458631 -295.764151)
			(xy 5.427053 -295.666129) (xy 5.4032 -295.565947) (xy 5.387217 -295.464213) (xy 5.379201 -295.361543)
			(xy 5.379201 -295.25856) (xy 5.387217 -295.15589) (xy 5.4032 -295.054156) (xy 5.427052 -294.953974)
			(xy 5.45863 -294.855952) (xy 5.497742 -294.760686) (xy 5.544151 -294.668753) (xy 5.597574 -294.580711)
			(xy 5.657688 -294.497095) (xy 5.724128 -294.418411) (xy 5.759958 -294.381428) (xy 5.767324 -294.374316)
			(xy 5.77469 -294.356028) (xy 5.77469 -294.26408) (xy 5.767324 -294.245792) (xy 5.759958 -294.23868)
			(xy 5.724127 -294.201697) (xy 5.657687 -294.123013) (xy 5.597573 -294.039397) (xy 5.54415 -293.951355)
			(xy 5.497741 -293.859422) (xy 5.458629 -293.764156) (xy 5.427051 -293.666134) (xy 5.403198 -293.565952)
			(xy 5.387215 -293.464217) (xy 5.379199 -293.361547) (xy 5.379199 -293.258565) (xy 5.387215 -293.155895)
			(xy 5.403198 -293.05416) (xy 5.427051 -292.953978) (xy 5.458629 -292.855956) (xy 5.497741 -292.76069)
			(xy 5.54415 -292.668757) (xy 5.597573 -292.580715) (xy 5.657687 -292.497099) (xy 5.724127 -292.418415)
			(xy 5.759958 -292.381432) (xy 5.767324 -292.37432) (xy 5.77469 -292.356032) (xy 5.77469 -292.264084)
			(xy 5.767324 -292.245796) (xy 5.759958 -292.238684) (xy 5.724127 -292.201701) (xy 5.657687 -292.123017)
			(xy 5.597573 -292.039401) (xy 5.54415 -291.951359) (xy 5.497742 -291.859426) (xy 5.45863 -291.76416)
			(xy 5.427051 -291.666138) (xy 5.403198 -291.565956) (xy 5.387216 -291.464221) (xy 5.3792 -291.361551)
			(xy 5.3792 -291.258569) (xy 5.387216 -291.155899) (xy 5.403198 -291.054164) (xy 5.427051 -290.953982)
			(xy 5.45863 -290.85596) (xy 5.497742 -290.760694) (xy 5.54415 -290.668761) (xy 5.597573 -290.580719)
			(xy 5.657687 -290.497103) (xy 5.724127 -290.418419) (xy 5.759958 -290.381436) (xy 5.767324 -290.374324)
			(xy 5.77469 -290.356036) (xy 5.77469 -290.264088) (xy 5.767324 -290.2458) (xy 5.759958 -290.238688)
			(xy 5.724126 -290.201706) (xy 5.657686 -290.123022) (xy 5.597571 -290.039406) (xy 5.544147 -289.951364)
			(xy 5.497738 -289.859431) (xy 5.458626 -289.764165) (xy 5.427048 -289.666143) (xy 5.403195 -289.565961)
			(xy 5.387212 -289.464226) (xy 5.379197 -289.361555) (xy 5.378704 -289.310064) (xy 5.37921 -289.259245)
			(xy 5.387014 -289.157908) (xy 5.402583 -289.057469) (xy 5.425823 -288.958524) (xy 5.456596 -288.861658)
			(xy 5.494722 -288.767442) (xy 5.539975 -288.676434) (xy 5.592087 -288.589173) (xy 5.65075 -288.506174)
			(xy 5.715617 -288.427927) (xy 5.786304 -288.354896) (xy 5.862394 -288.287513) (xy 5.943437 -288.226176)
			(xy 6.028953 -288.171247) (xy 6.118437 -288.123051) (xy 6.21136 -288.081874) (xy 6.307172 -288.047958)
			(xy 6.405306 -288.021505) (xy 6.455156 -288.011616) (xy 6.466586 -288.009584) (xy 6.484874 -287.996376)
			(xy 6.533642 -287.907476) (xy 6.535166 -287.88487) (xy 6.530848 -287.874202) (xy 6.512841 -287.827521)
			(xy 6.483432 -287.731878) (xy 6.461716 -287.634201) (xy 6.447829 -287.535107) (xy 6.441858 -287.435223)
			(xy 6.443843 -287.33518) (xy 6.453771 -287.235612) (xy 6.471577 -287.137147) (xy 6.497151 -287.040408)
			(xy 6.53033 -286.946006) (xy 6.570905 -286.85454) (xy 6.618619 -286.766586) (xy 6.67317 -286.682701)
			(xy 6.734213 -286.603416) (xy 6.801363 -286.529231) (xy 6.874194 -286.460616) (xy 6.952248 -286.398005)
			(xy 7.035028 -286.341793) (xy 7.122014 -286.292336) (xy 7.212654 -286.249947) (xy 7.306375 -286.214893)
			(xy 7.402585 -286.187396) (xy 7.500676 -286.16763) (xy 7.600027 -286.155721) (xy 7.70001 -286.151743)
			(xy 7.799993 -286.155721) (xy 7.899344 -286.16763) (xy 7.997435 -286.187396) (xy 8.093645 -286.214893)
			(xy 8.187366 -286.249947) (xy 8.278006 -286.292336) (xy 8.364992 -286.341793) (xy 8.447772 -286.398005)
			(xy 8.525826 -286.460616) (xy 8.598657 -286.529231) (xy 8.665807 -286.603416) (xy 8.72685 -286.682701)
			(xy 8.750747 -286.719448) (xy 16.520918 -286.719448) (xy 16.520918 -286.634752) (xy 16.528969 -286.550438)
			(xy 16.544998 -286.467272) (xy 16.568859 -286.386005) (xy 16.600338 -286.307375) (xy 16.639149 -286.232094)
			(xy 16.684939 -286.160842) (xy 16.737295 -286.094266) (xy 16.795743 -286.032968) (xy 16.859753 -285.977503)
			(xy 16.928745 -285.928374) (xy 17.002095 -285.886025) (xy 17.079138 -285.850841) (xy 17.159177 -285.823139)
			(xy 17.241486 -285.803171) (xy 17.325321 -285.791118) (xy 17.409922 -285.787088) (xy 17.494523 -285.791118)
			(xy 17.578358 -285.803171) (xy 17.660667 -285.823139) (xy 17.740706 -285.850841) (xy 17.817749 -285.886025)
			(xy 17.891099 -285.928374) (xy 17.960091 -285.977503) (xy 18.024101 -286.032968) (xy 18.082549 -286.094266)
			(xy 18.134905 -286.160842) (xy 18.180695 -286.232094) (xy 18.219506 -286.307375) (xy 18.250985 -286.386005)
			(xy 18.274846 -286.467272) (xy 18.290875 -286.550438) (xy 18.298926 -286.634752) (xy 18.29943 -286.6771)
			(xy 18.298926 -286.719448) (xy 18.290875 -286.803762) (xy 18.274846 -286.886928) (xy 18.250985 -286.968195)
			(xy 18.219506 -287.046825) (xy 18.180695 -287.122106) (xy 18.134905 -287.193358) (xy 18.082549 -287.259934)
			(xy 18.024101 -287.321232) (xy 17.960091 -287.376697) (xy 17.891099 -287.425826) (xy 17.817749 -287.468175)
			(xy 17.740706 -287.503359) (xy 17.660667 -287.531061) (xy 17.578358 -287.551029) (xy 17.494523 -287.563082)
			(xy 17.409922 -287.567113) (xy 17.325321 -287.563082) (xy 17.241486 -287.551029) (xy 17.159177 -287.531061)
			(xy 17.079138 -287.503359) (xy 17.002095 -287.468175) (xy 16.928745 -287.425826) (xy 16.859753 -287.376697)
			(xy 16.795743 -287.321232) (xy 16.737295 -287.259934) (xy 16.684939 -287.193358) (xy 16.639149 -287.122106)
			(xy 16.600338 -287.046825) (xy 16.568859 -286.968195) (xy 16.544998 -286.886928) (xy 16.528969 -286.803762)
			(xy 16.520918 -286.719448) (xy 8.750747 -286.719448) (xy 8.781401 -286.766586) (xy 8.829115 -286.85454)
			(xy 8.86969 -286.946006) (xy 8.902869 -287.040408) (xy 8.928443 -287.137147) (xy 8.946249 -287.235612)
			(xy 8.956177 -287.33518) (xy 8.958162 -287.435223) (xy 8.952191 -287.535107) (xy 8.938304 -287.634201)
			(xy 8.916588 -287.731878) (xy 8.887179 -287.827521) (xy 8.869172 -287.874202) (xy 8.864854 -287.88487)
			(xy 8.866378 -287.907476) (xy 8.915146 -287.996376) (xy 8.933434 -288.009584) (xy 8.944864 -288.011616)
			(xy 8.994714 -288.021501) (xy 9.092848 -288.047958) (xy 9.188659 -288.081876) (xy 9.281581 -288.123056)
			(xy 9.371064 -288.171253) (xy 9.45658 -288.226183) (xy 9.537622 -288.287521) (xy 9.613712 -288.354904)
			(xy 9.6844 -288.427935) (xy 9.749268 -288.506181) (xy 9.807932 -288.589179) (xy 9.860046 -288.67644)
			(xy 9.905301 -288.767446) (xy 9.94343 -288.861661) (xy 9.974207 -288.958526) (xy 9.997452 -289.057471)
			(xy 10.013025 -289.157908) (xy 10.020835 -289.259245) (xy 10.021316 -289.310064) (xy 10.020782 -289.361554)
			(xy 10.012769 -289.464223) (xy 9.99972 -289.5473) (xy 14.912832 -289.5473) (xy 14.916862 -289.462697)
			(xy 14.928916 -289.378861) (xy 14.948885 -289.296549) (xy 14.976587 -289.216509) (xy 15.011772 -289.139464)
			(xy 15.054122 -289.066113) (xy 15.103252 -288.99712) (xy 15.158718 -288.933109) (xy 15.220017 -288.87466)
			(xy 15.286595 -288.822303) (xy 15.357848 -288.776512) (xy 15.433132 -288.737701) (xy 15.511763 -288.706222)
			(xy 15.593031 -288.68236) (xy 15.676199 -288.666331) (xy 15.760515 -288.65828) (xy 15.802864 -288.657792)
			(xy 15.846636 -288.658276) (xy 15.933755 -288.666891) (xy 16.019607 -288.684021) (xy 16.103361 -288.709501)
			(xy 16.184207 -288.743084) (xy 16.261364 -288.784445) (xy 16.334085 -288.833186) (xy 16.401667 -288.888833)
			(xy 16.463456 -288.950849) (xy 16.518856 -289.018634) (xy 16.543528 -289.054794) (xy 16.55064 -289.065462)
			(xy 16.572738 -289.0774) (xy 16.68272 -289.078162) (xy 16.704818 -289.066478) (xy 16.712184 -289.056064)
			(xy 16.736966 -289.020693) (xy 16.792397 -288.954455) (xy 16.853989 -288.893903) (xy 16.921162 -288.83961)
			(xy 16.993284 -288.792085) (xy 17.069673 -288.751778) (xy 17.149611 -288.719067) (xy 17.232345 -288.694262)
			(xy 17.317093 -288.677595) (xy 17.403058 -288.669225) (xy 17.446244 -288.668714) (xy 17.488592 -288.669214)
			(xy 17.572906 -288.677265) (xy 17.656072 -288.693294) (xy 17.737338 -288.717157) (xy 17.815968 -288.748636)
			(xy 17.89125 -288.787446) (xy 17.962501 -288.833237) (xy 18.029077 -288.885593) (xy 18.090375 -288.944041)
			(xy 18.14584 -289.008051) (xy 18.194969 -289.077043) (xy 18.237317 -289.150393) (xy 18.272501 -289.227436)
			(xy 18.300203 -289.307475) (xy 18.320171 -289.389784) (xy 18.332224 -289.473619) (xy 18.336255 -289.55822)
			(xy 18.332224 -289.642821) (xy 18.320171 -289.726656) (xy 18.300203 -289.808965) (xy 18.272501 -289.889004)
			(xy 18.237317 -289.966047) (xy 18.194969 -290.039397) (xy 18.14584 -290.108389) (xy 18.090375 -290.172399)
			(xy 18.029077 -290.230847) (xy 18.026212 -290.2331) (xy 18.800064 -290.2331) (xy 18.800598 -290.188982)
			(xy 18.809329 -290.101179) (xy 18.826716 -290.014672) (xy 18.852587 -289.930314) (xy 18.886687 -289.848933)
			(xy 18.928682 -289.771331) (xy 18.952972 -289.734498) (xy 18.958223 -289.725852) (xy 18.96221 -289.706042)
			(xy 18.958255 -289.686225) (xy 18.952972 -289.677602) (xy 18.928679 -289.640771) (xy 18.886693 -289.563165)
			(xy 18.852599 -289.481783) (xy 18.82673 -289.397425) (xy 18.809342 -289.31092) (xy 18.800605 -289.223118)
			(xy 18.800064 -289.179) (xy 18.800578 -289.136699) (xy 18.808618 -289.052478) (xy 18.824615 -288.969401)
			(xy 18.848426 -288.888218) (xy 18.879835 -288.809661) (xy 18.918558 -288.73444) (xy 18.964246 -288.663234)
			(xy 19.016487 -288.596687) (xy 19.074808 -288.535398) (xy 19.138683 -288.479921) (xy 19.207535 -288.430758)
			(xy 19.280744 -288.388352) (xy 19.318986 -288.370264) (xy 19.327207 -288.366024) (xy 19.340156 -288.352838)
			(xy 19.347604 -288.335923) (xy 19.34859 -288.317468) (xy 19.346164 -288.308542) (xy 19.332593 -288.264404)
			(xy 19.313603 -288.174029) (xy 19.304068 -288.082174) (xy 19.303492 -288.036) (xy 19.304051 -287.991773)
			(xy 19.312833 -287.903756) (xy 19.330309 -287.817046) (xy 19.356308 -287.7325) (xy 19.390573 -287.650952)
			(xy 19.411188 -287.61182) (xy 19.416014 -287.602676) (xy 19.418046 -287.582356) (xy 19.389852 -287.492948)
			(xy 19.376644 -287.4772) (xy 19.367246 -287.472628) (xy 19.330744 -287.453879) (xy 19.261051 -287.410546)
			(xy 19.195645 -287.360979) (xy 19.135082 -287.305599) (xy 19.079876 -287.244876) (xy 19.030498 -287.179327)
			(xy 18.987367 -287.109508) (xy 18.95085 -287.036014) (xy 18.921256 -286.95947) (xy 18.898838 -286.880525)
			(xy 18.883786 -286.799851) (xy 18.876227 -286.718133) (xy 18.875756 -286.6771) (xy 18.87626 -286.634752)
			(xy 18.884311 -286.550438) (xy 18.90034 -286.467272) (xy 18.924201 -286.386005) (xy 18.95568 -286.307375)
			(xy 18.994491 -286.232094) (xy 19.040281 -286.160842) (xy 19.092637 -286.094266) (xy 19.151085 -286.032968)
			(xy 19.215095 -285.977503) (xy 19.284087 -285.928374) (xy 19.357437 -285.886025) (xy 19.43448 -285.850841)
			(xy 19.514519 -285.823139) (xy 19.596828 -285.803171) (xy 19.680663 -285.791118) (xy 19.765264 -285.787088)
			(xy 19.849865 -285.791118) (xy 19.9337 -285.803171) (xy 20.016009 -285.823139) (xy 20.096048 -285.850841)
			(xy 20.173091 -285.886025) (xy 20.246441 -285.928374) (xy 20.315433 -285.977503) (xy 20.379443 -286.032968)
			(xy 20.437891 -286.094266) (xy 20.490247 -286.160842) (xy 20.536037 -286.232094) (xy 20.574848 -286.307375)
			(xy 20.606327 -286.386005) (xy 20.630188 -286.467272) (xy 20.646217 -286.550438) (xy 20.654268 -286.634752)
			(xy 20.654596 -286.662298) (xy 27.050996 -286.662298) (xy 27.050996 -286.577602) (xy 27.059047 -286.493288)
			(xy 27.075076 -286.410122) (xy 27.098937 -286.328855) (xy 27.130416 -286.250225) (xy 27.169227 -286.174944)
			(xy 27.215017 -286.103692) (xy 27.267373 -286.037116) (xy 27.325821 -285.975818) (xy 27.389831 -285.920353)
			(xy 27.458823 -285.871224) (xy 27.532173 -285.828875) (xy 27.609216 -285.793691) (xy 27.689255 -285.765989)
			(xy 27.771564 -285.746021) (xy 27.855399 -285.733968) (xy 27.94 -285.729938) (xy 28.024601 -285.733968)
			(xy 28.108436 -285.746021) (xy 28.190745 -285.765989) (xy 28.270784 -285.793691) (xy 28.347827 -285.828875)
			(xy 28.421177 -285.871224) (xy 28.490169 -285.920353) (xy 28.554179 -285.975818) (xy 28.612627 -286.037116)
			(xy 28.664983 -286.103692) (xy 28.710773 -286.174944) (xy 28.749584 -286.250225) (xy 28.781063 -286.328855)
			(xy 28.804924 -286.410122) (xy 28.820953 -286.493288) (xy 28.829004 -286.577602) (xy 28.829508 -286.61995)
			(xy 28.829004 -286.662298) (xy 28.820953 -286.746612) (xy 28.804924 -286.829778) (xy 28.781063 -286.911045)
			(xy 28.749584 -286.989675) (xy 28.710773 -287.064956) (xy 28.664983 -287.136208) (xy 28.612627 -287.202784)
			(xy 28.554179 -287.264082) (xy 28.490169 -287.319547) (xy 28.421177 -287.368676) (xy 28.347827 -287.411025)
			(xy 28.270784 -287.446209) (xy 28.190745 -287.473911) (xy 28.108436 -287.493879) (xy 28.024601 -287.505932)
			(xy 27.94 -287.509963) (xy 27.855399 -287.505932) (xy 27.771564 -287.493879) (xy 27.689255 -287.473911)
			(xy 27.609216 -287.446209) (xy 27.532173 -287.411025) (xy 27.458823 -287.368676) (xy 27.389831 -287.319547)
			(xy 27.325821 -287.264082) (xy 27.267373 -287.202784) (xy 27.215017 -287.136208) (xy 27.169227 -287.064956)
			(xy 27.130416 -286.989675) (xy 27.098937 -286.911045) (xy 27.075076 -286.829778) (xy 27.059047 -286.746612)
			(xy 27.050996 -286.662298) (xy 20.654596 -286.662298) (xy 20.654772 -286.6771) (xy 20.654205 -286.721327)
			(xy 20.645424 -286.809343) (xy 20.627949 -286.896053) (xy 20.601952 -286.980599) (xy 20.56769 -287.062147)
			(xy 20.547076 -287.10128) (xy 20.54225 -287.110424) (xy 20.540218 -287.130744) (xy 20.568412 -287.220152)
			(xy 20.58162 -287.2359) (xy 20.591018 -287.240472) (xy 20.627511 -287.259237) (xy 20.697206 -287.302567)
			(xy 20.762613 -287.352132) (xy 20.823177 -287.407511) (xy 20.878383 -287.468232) (xy 20.927762 -287.533779)
			(xy 20.970894 -287.603596) (xy 21.007413 -287.677089) (xy 21.037007 -287.753633) (xy 21.059426 -287.832577)
			(xy 21.074478 -287.91325) (xy 21.082037 -287.994967) (xy 21.082508 -288.036) (xy 21.081952 -288.0783)
			(xy 21.073913 -288.162518) (xy 21.057917 -288.245592) (xy 21.034109 -288.326774) (xy 21.002703 -288.405329)
			(xy 20.963983 -288.480549) (xy 20.918299 -288.551754) (xy 20.866063 -288.618302) (xy 20.807747 -288.679592)
			(xy 20.743876 -288.73507) (xy 20.675029 -288.784236) (xy 20.601826 -288.826646) (xy 20.563586 -288.844736)
			(xy 20.555378 -288.849) (xy 20.54242 -288.862174) (xy 20.534965 -288.879082) (xy 20.53398 -288.897535)
			(xy 20.536408 -288.906458) (xy 20.549978 -288.950597) (xy 20.568968 -289.040971) (xy 20.578504 -289.132826)
			(xy 20.57908 -289.179) (xy 20.578538 -289.223118) (xy 20.569808 -289.310921) (xy 20.552422 -289.397427)
			(xy 20.528526 -289.475348) (xy 26.923996 -289.475348) (xy 26.923996 -289.390652) (xy 26.932047 -289.306338)
			(xy 26.948076 -289.223172) (xy 26.971937 -289.141905) (xy 27.003416 -289.063275) (xy 27.042227 -288.987994)
			(xy 27.088017 -288.916742) (xy 27.140373 -288.850166) (xy 27.198821 -288.788868) (xy 27.262831 -288.733403)
			(xy 27.331823 -288.684274) (xy 27.405173 -288.641925) (xy 27.482216 -288.606741) (xy 27.562255 -288.579039)
			(xy 27.644564 -288.559071) (xy 27.728399 -288.547018) (xy 27.813 -288.542988) (xy 27.897601 -288.547018)
			(xy 27.981436 -288.559071) (xy 28.063745 -288.579039) (xy 28.143784 -288.606741) (xy 28.220827 -288.641925)
			(xy 28.294177 -288.684274) (xy 28.363169 -288.733403) (xy 28.427179 -288.788868) (xy 28.485627 -288.850166)
			(xy 28.537983 -288.916742) (xy 28.583773 -288.987994) (xy 28.622584 -289.063275) (xy 28.654063 -289.141905)
			(xy 28.677924 -289.223172) (xy 28.693953 -289.306338) (xy 28.702004 -289.390652) (xy 28.702508 -289.433)
			(xy 28.702004 -289.475348) (xy 28.693953 -289.559662) (xy 28.677924 -289.642828) (xy 28.654063 -289.724095)
			(xy 28.622584 -289.802725) (xy 28.583773 -289.878006) (xy 28.537983 -289.949258) (xy 28.485627 -290.015834)
			(xy 28.427179 -290.077132) (xy 28.363169 -290.132597) (xy 28.294177 -290.181726) (xy 28.220827 -290.224075)
			(xy 28.143784 -290.259259) (xy 28.063745 -290.286961) (xy 27.981436 -290.306929) (xy 27.897601 -290.318982)
			(xy 27.813 -290.323013) (xy 27.728399 -290.318982) (xy 27.644564 -290.306929) (xy 27.562255 -290.286961)
			(xy 27.482216 -290.259259) (xy 27.405173 -290.224075) (xy 27.331823 -290.181726) (xy 27.262831 -290.132597)
			(xy 27.198821 -290.077132) (xy 27.140373 -290.015834) (xy 27.088017 -289.949258) (xy 27.042227 -289.878006)
			(xy 27.003416 -289.802725) (xy 26.971937 -289.724095) (xy 26.948076 -289.642828) (xy 26.932047 -289.559662)
			(xy 26.923996 -289.475348) (xy 20.528526 -289.475348) (xy 20.526552 -289.481785) (xy 20.492453 -289.563166)
			(xy 20.450461 -289.640768) (xy 20.426172 -289.677602) (xy 20.420833 -289.686203) (xy 20.41687 -289.706042)
			(xy 20.420866 -289.725875) (xy 20.426172 -289.734498) (xy 20.45047 -289.771325) (xy 20.492454 -289.848933)
			(xy 20.526548 -289.930316) (xy 20.552415 -290.014674) (xy 20.569803 -290.10118) (xy 20.578539 -290.188982)
			(xy 20.57908 -290.2331) (xy 20.578586 -290.275225) (xy 20.570589 -290.359094) (xy 20.554703 -290.441832)
			(xy 20.53107 -290.522699) (xy 20.499903 -290.600972) (xy 20.46148 -290.67595) (xy 20.416145 -290.746962)
			(xy 20.390612 -290.78047) (xy 20.385326 -290.787901) (xy 20.379876 -290.80529) (xy 20.380847 -290.823487)
			(xy 20.388114 -290.840199) (xy 20.394168 -290.847018) (xy 20.423496 -290.878067) (xy 20.476663 -290.944919)
			(xy 20.523178 -291.016558) (xy 20.562614 -291.092326) (xy 20.589549 -291.159003) (xy 27.797084 -291.159003)
			(xy 27.799715 -291.075192) (xy 27.810223 -290.992002) (xy 27.828512 -290.910169) (xy 27.854421 -290.830421)
			(xy 27.887721 -290.753465) (xy 27.928114 -290.679984) (xy 27.975244 -290.610631) (xy 28.028691 -290.546021)
			(xy 28.087981 -290.486727) (xy 28.152588 -290.433276) (xy 28.221938 -290.386142) (xy 28.295417 -290.345744)
			(xy 28.372371 -290.31244) (xy 28.452117 -290.286526) (xy 28.533949 -290.268232) (xy 28.617139 -290.25772)
			(xy 28.700948 -290.255083) (xy 28.784635 -290.260345) (xy 28.867454 -290.273459) (xy 28.948672 -290.294309)
			(xy 29.027567 -290.32271) (xy 29.10344 -290.358409) (xy 29.175616 -290.40109) (xy 29.243455 -290.450374)
			(xy 29.306355 -290.505824) (xy 29.363758 -290.566947) (xy 29.415154 -290.6332) (xy 29.460087 -290.703996)
			(xy 29.498158 -290.778707) (xy 29.529029 -290.856669) (xy 29.552426 -290.93719) (xy 29.568142 -291.019555)
			(xy 29.576037 -291.103034) (xy 29.576522 -291.14496) (xy 29.576059 -291.186778) (xy 29.568205 -291.270044)
			(xy 29.552561 -291.352203) (xy 29.529268 -291.432529) (xy 29.498529 -291.510311) (xy 29.480002 -291.547804)
			(xy 29.472636 -291.562282) (xy 29.477208 -291.594032) (xy 29.5656 -291.686996) (xy 29.596842 -291.693346)
			(xy 29.611828 -291.686742) (xy 29.65446 -291.668508) (xy 29.742691 -291.639981) (xy 29.833411 -291.620788)
			(xy 29.925636 -291.61114) (xy 29.972 -291.610542) (xy 30.012539 -291.610965) (xy 30.09328 -291.618349)
			(xy 30.173015 -291.633048) (xy 30.251082 -291.654939) (xy 30.326833 -291.683841) (xy 30.399642 -291.719514)
			(xy 30.468904 -291.761662) (xy 30.534044 -291.809936) (xy 30.564582 -291.836602) (xy 30.576012 -291.846762)
			(xy 30.60573 -291.851334) (xy 30.717998 -291.799264) (xy 30.734 -291.773864) (xy 30.733746 -291.75837)
			(xy 30.733492 -291.73805) (xy 30.733972 -291.696082) (xy 30.741893 -291.612519) (xy 30.757649 -291.530074)
			(xy 30.781101 -291.44948) (xy 30.81204 -291.371453) (xy 30.850191 -291.296687) (xy 30.895215 -291.225847)
			(xy 30.946712 -291.159563) (xy 31.004223 -291.098424) (xy 31.067237 -291.042975) (xy 31.135194 -290.993707)
			(xy 31.20749 -290.95106) (xy 31.283481 -290.915412) (xy 31.362492 -290.88708) (xy 31.403036 -290.876228)
			(xy 31.414466 -290.87318) (xy 31.431992 -290.858448) (xy 31.474156 -290.764468) (xy 31.473648 -290.741608)
			(xy 31.46806 -290.73094) (xy 31.448959 -290.692971) (xy 31.417264 -290.614101) (xy 31.393236 -290.532567)
			(xy 31.377095 -290.449113) (xy 31.368987 -290.3645) (xy 31.368492 -290.322) (xy 31.369099 -290.275048)
			(xy 31.378953 -290.181664) (xy 31.398593 -290.089839) (xy 31.4278 -290.000594) (xy 31.44647 -289.95751)
			(xy 31.451804 -289.945826) (xy 31.450026 -289.920426) (xy 31.39059 -289.826954) (xy 31.368238 -289.814508)
			(xy 31.355538 -289.814508) (xy 31.312299 -289.813324) (xy 31.226341 -289.803607) (xy 31.141733 -289.785594)
			(xy 31.059272 -289.759454) (xy 30.979738 -289.725434) (xy 30.903881 -289.683855) (xy 30.832417 -289.635111)
			(xy 30.766022 -289.57966) (xy 30.705321 -289.518028) (xy 30.65089 -289.450795) (xy 30.60324 -289.378597)
			(xy 30.562823 -289.302114) (xy 30.530019 -289.222071) (xy 30.505139 -289.139221) (xy 30.488417 -289.054348)
			(xy 30.480012 -288.968252) (xy 30.479492 -288.925) (xy 30.479975 -288.882789) (xy 30.487962 -288.798745)
			(xy 30.503873 -288.715835) (xy 30.527565 -288.634805) (xy 30.558826 -288.556383) (xy 30.597374 -288.481275)
			(xy 30.6197 -288.445448) (xy 30.626558 -288.43478) (xy 30.628844 -288.410142) (xy 30.586172 -288.309558)
			(xy 30.567122 -288.29381) (xy 30.554676 -288.29127) (xy 30.512213 -288.281991) (xy 30.429188 -288.256253)
			(xy 30.34907 -288.222538) (xy 30.272623 -288.181168) (xy 30.200577 -288.132538) (xy 30.133619 -288.077111)
			(xy 30.072387 -288.015416) (xy 30.017466 -287.948042) (xy 29.969379 -287.875632) (xy 29.928586 -287.798876)
			(xy 29.895476 -287.718506) (xy 29.870364 -287.63529) (xy 29.85349 -287.55002) (xy 29.845015 -287.463511)
			(xy 29.844492 -287.42005) (xy 29.844925 -287.380951) (xy 29.851812 -287.303056) (xy 29.865503 -287.226065)
			(xy 29.885893 -287.150571) (xy 29.912824 -287.077155) (xy 29.929074 -287.04159) (xy 29.93331 -287.031203)
			(xy 29.93331 -287.008797) (xy 29.929074 -286.99841) (xy 29.912794 -286.962857) (xy 29.885844 -286.889445)
			(xy 29.86545 -286.813949) (xy 29.85177 -286.736952) (xy 29.84491 -286.659051) (xy 29.844492 -286.61995)
			(xy 29.844919 -286.578847) (xy 29.852508 -286.496991) (xy 29.867618 -286.416185) (xy 29.890118 -286.337117)
			(xy 29.919818 -286.260463) (xy 29.956464 -286.186876) (xy 29.999742 -286.116984) (xy 30.049285 -286.051384)
			(xy 30.104669 -285.990634) (xy 30.165422 -285.935253) (xy 30.231026 -285.885714) (xy 30.30092 -285.842439)
			(xy 30.374509 -285.805798) (xy 30.451165 -285.776102) (xy 30.530234 -285.753606) (xy 30.611041 -285.738501)
			(xy 30.692897 -285.730917) (xy 30.734 -285.730442) (xy 30.778069 -285.731015) (xy 30.865774 -285.739738)
			(xy 30.952187 -285.757088) (xy 31.036461 -285.782895) (xy 31.117771 -285.816908) (xy 31.195321 -285.858792)
			(xy 31.268351 -285.908136) (xy 31.336145 -285.964459) (xy 31.398038 -286.027208) (xy 31.42615 -286.06115)
			(xy 31.4325 -286.069278) (xy 31.45028 -286.07893) (xy 31.542228 -286.088328) (xy 31.561532 -286.08274)
			(xy 31.569406 -286.076136) (xy 31.603425 -286.049147) (xy 31.675798 -286.00115) (xy 31.752503 -285.960434)
			(xy 31.832811 -285.927386) (xy 31.915957 -285.902321) (xy 32.00115 -285.885477) (xy 32.087579 -285.877015)
			(xy 32.131 -285.876492) (xy 32.173348 -285.876996) (xy 32.257662 -285.885047) (xy 32.340828 -285.901076)
			(xy 32.422095 -285.924937) (xy 32.500725 -285.956416) (xy 32.576006 -285.995227) (xy 32.647258 -286.041017)
			(xy 32.713834 -286.093373) (xy 32.775132 -286.151821) (xy 32.830597 -286.215831) (xy 32.879726 -286.284823)
			(xy 32.922075 -286.358173) (xy 32.957259 -286.435216) (xy 32.984961 -286.515255) (xy 33.004929 -286.597564)
			(xy 33.016982 -286.681399) (xy 33.021013 -286.766) (xy 33.016982 -286.850601) (xy 33.004929 -286.934436)
			(xy 32.984961 -287.016745) (xy 32.957259 -287.096784) (xy 32.922075 -287.173827) (xy 32.879726 -287.247177)
			(xy 32.830597 -287.316169) (xy 32.775132 -287.380179) (xy 32.767221 -287.387722) (xy 35.201348 -287.387722)
			(xy 35.201348 -287.303026) (xy 35.209399 -287.218712) (xy 35.225428 -287.135546) (xy 35.249289 -287.054279)
			(xy 35.280768 -286.975649) (xy 35.319579 -286.900368) (xy 35.365369 -286.829116) (xy 35.417725 -286.76254)
			(xy 35.476173 -286.701242) (xy 35.540183 -286.645777) (xy 35.609175 -286.596648) (xy 35.682525 -286.554299)
			(xy 35.759568 -286.519115) (xy 35.839607 -286.491413) (xy 35.921916 -286.471445) (xy 36.005751 -286.459392)
			(xy 36.090352 -286.455362) (xy 36.174953 -286.459392) (xy 36.258788 -286.471445) (xy 36.341097 -286.491413)
			(xy 36.421136 -286.519115) (xy 36.498179 -286.554299) (xy 36.571529 -286.596648) (xy 36.640521 -286.645777)
			(xy 36.704531 -286.701242) (xy 36.762979 -286.76254) (xy 36.815335 -286.829116) (xy 36.861125 -286.900368)
			(xy 36.899936 -286.975649) (xy 36.931415 -287.054279) (xy 36.955276 -287.135546) (xy 36.971305 -287.218712)
			(xy 36.979356 -287.303026) (xy 36.97986 -287.345374) (xy 36.979356 -287.387722) (xy 36.971305 -287.472036)
			(xy 36.955276 -287.555202) (xy 36.931415 -287.636469) (xy 36.899936 -287.715099) (xy 36.861125 -287.79038)
			(xy 36.815335 -287.861632) (xy 36.762979 -287.928208) (xy 36.704531 -287.989506) (xy 36.640521 -288.044971)
			(xy 36.571529 -288.0941) (xy 36.498179 -288.136449) (xy 36.421136 -288.171633) (xy 36.341097 -288.199335)
			(xy 36.258788 -288.219303) (xy 36.174953 -288.231356) (xy 36.090352 -288.235387) (xy 36.005751 -288.231356)
			(xy 35.921916 -288.219303) (xy 35.839607 -288.199335) (xy 35.759568 -288.171633) (xy 35.682525 -288.136449)
			(xy 35.609175 -288.0941) (xy 35.540183 -288.044971) (xy 35.476173 -287.989506) (xy 35.417725 -287.928208)
			(xy 35.365369 -287.861632) (xy 35.319579 -287.79038) (xy 35.280768 -287.715099) (xy 35.249289 -287.636469)
			(xy 35.225428 -287.555202) (xy 35.209399 -287.472036) (xy 35.201348 -287.387722) (xy 32.767221 -287.387722)
			(xy 32.713834 -287.438627) (xy 32.647258 -287.490983) (xy 32.576006 -287.536773) (xy 32.500725 -287.575584)
			(xy 32.422095 -287.607063) (xy 32.340828 -287.630924) (xy 32.257662 -287.646953) (xy 32.173348 -287.655004)
			(xy 32.131 -287.655508) (xy 32.090604 -287.655061) (xy 32.010147 -287.647713) (xy 31.930687 -287.633104)
			(xy 31.852877 -287.611356) (xy 31.777359 -287.582647) (xy 31.740856 -287.565338) (xy 31.730442 -287.560258)
			(xy 31.707582 -287.560258) (xy 31.615126 -287.603438) (xy 31.600648 -287.621218) (xy 31.597854 -287.632394)
			(xy 31.585604 -287.679518) (xy 31.552181 -287.770972) (xy 31.508981 -287.858235) (xy 31.4833 -287.899602)
			(xy 31.476442 -287.91027) (xy 31.474156 -287.934908) (xy 31.516828 -288.035492) (xy 31.535878 -288.05124)
			(xy 31.548324 -288.05378) (xy 31.590776 -288.063106) (xy 31.673798 -288.088842) (xy 31.753914 -288.122554)
			(xy 31.830359 -288.163921) (xy 31.902404 -288.212548) (xy 31.969362 -288.267972) (xy 32.030594 -288.329662)
			(xy 32.085516 -288.397032) (xy 32.133603 -288.469439) (xy 32.174398 -288.546191) (xy 32.207511 -288.626556)
			(xy 32.232626 -288.709769) (xy 32.249503 -288.795035) (xy 32.257983 -288.88154) (xy 32.258508 -288.925)
			(xy 32.257901 -288.971952) (xy 32.248047 -289.065336) (xy 32.228407 -289.157161) (xy 32.1992 -289.246406)
			(xy 32.18053 -289.28949) (xy 32.175196 -289.301174) (xy 32.176974 -289.326574) (xy 32.23641 -289.420046)
			(xy 32.258762 -289.432492) (xy 32.271462 -289.432492) (xy 32.314701 -289.433676) (xy 32.400659 -289.443393)
			(xy 32.485267 -289.461406) (xy 32.567728 -289.487546) (xy 32.647262 -289.521566) (xy 32.723119 -289.563145)
			(xy 32.794583 -289.611889) (xy 32.860978 -289.66734) (xy 32.921679 -289.728972) (xy 32.97611 -289.796205)
			(xy 33.02376 -289.868403) (xy 33.064177 -289.944886) (xy 33.096981 -290.024929) (xy 33.121861 -290.107779)
			(xy 33.138583 -290.192652) (xy 33.146988 -290.278748) (xy 33.147508 -290.322) (xy 33.146981 -290.363968)
			(xy 33.140346 -290.434014) (xy 33.527492 -290.434014) (xy 33.527975 -290.393079) (xy 33.535497 -290.311555)
			(xy 33.550479 -290.231068) (xy 33.572794 -290.152298) (xy 33.602253 -290.075911) (xy 33.638607 -290.002555)
			(xy 33.681548 -289.932851) (xy 33.730713 -289.867387) (xy 33.785686 -289.806718) (xy 33.815528 -289.778694)
			(xy 33.822894 -289.77209) (xy 33.831276 -289.754056) (xy 33.836356 -289.663378) (xy 33.829752 -289.644582)
			(xy 33.823148 -289.637216) (xy 33.797216 -289.606859) (xy 33.750298 -289.542252) (xy 33.709361 -289.473699)
			(xy 33.674735 -289.401752) (xy 33.646699 -289.326991) (xy 33.625479 -289.250016) (xy 33.611246 -289.171449)
			(xy 33.604114 -289.091923) (xy 33.603692 -289.052) (xy 33.604196 -289.009652) (xy 33.612247 -288.925338)
			(xy 33.628276 -288.842172) (xy 33.652137 -288.760905) (xy 33.683616 -288.682275) (xy 33.722427 -288.606994)
			(xy 33.768217 -288.535742) (xy 33.820573 -288.469166) (xy 33.879021 -288.407868) (xy 33.943031 -288.352403)
			(xy 34.012023 -288.303274) (xy 34.085373 -288.260925) (xy 34.162416 -288.225741) (xy 34.242455 -288.198039)
			(xy 34.324764 -288.178071) (xy 34.408599 -288.166018) (xy 34.4932 -288.161988) (xy 34.577801 -288.166018)
			(xy 34.661636 -288.178071) (xy 34.743945 -288.198039) (xy 34.823984 -288.225741) (xy 34.901027 -288.260925)
			(xy 34.974377 -288.303274) (xy 35.043369 -288.352403) (xy 35.107379 -288.407868) (xy 35.165827 -288.469166)
			(xy 35.218183 -288.535742) (xy 35.263973 -288.606994) (xy 35.302784 -288.682275) (xy 35.334263 -288.760905)
			(xy 35.358124 -288.842172) (xy 35.374153 -288.925338) (xy 35.382204 -289.009652) (xy 35.382708 -289.052)
			(xy 35.3822 -289.079178) (xy 35.381946 -289.093148) (xy 35.395154 -289.117278) (xy 35.494976 -289.176968)
			(xy 35.522662 -289.177222) (xy 35.5346 -289.170364) (xy 35.568407 -289.151383) (xy 35.638698 -289.118653)
			(xy 35.711571 -289.092164) (xy 35.786472 -289.072119) (xy 35.862834 -289.058668) (xy 35.940077 -289.051915)
			(xy 35.978846 -289.051492) (xy 36.021195 -289.05198) (xy 36.105511 -289.060031) (xy 36.188679 -289.07606)
			(xy 36.269947 -289.099922) (xy 36.348578 -289.131401) (xy 36.423862 -289.170212) (xy 36.495115 -289.216003)
			(xy 36.561693 -289.26836) (xy 36.622992 -289.326809) (xy 36.678458 -289.39082) (xy 36.727588 -289.459813)
			(xy 36.769938 -289.533164) (xy 36.805123 -289.610209) (xy 36.832825 -289.690249) (xy 36.852794 -289.772561)
			(xy 36.864848 -289.856397) (xy 36.868878 -289.941) (xy 36.864848 -290.025603) (xy 36.852794 -290.109439)
			(xy 36.832825 -290.191751) (xy 36.805123 -290.271791) (xy 36.769938 -290.348836) (xy 36.727588 -290.422187)
			(xy 36.678458 -290.49118) (xy 36.622992 -290.555191) (xy 36.561693 -290.61364) (xy 36.495115 -290.665997)
			(xy 36.423862 -290.711788) (xy 36.348578 -290.750599) (xy 36.269947 -290.782078) (xy 36.188679 -290.80594)
			(xy 36.105511 -290.821969) (xy 36.021195 -290.83002) (xy 35.978846 -290.830508) (xy 35.936471 -290.830003)
			(xy 35.852106 -290.82194) (xy 35.768889 -290.805893) (xy 35.687575 -290.782008) (xy 35.6089 -290.7505)
			(xy 35.533577 -290.711654) (xy 35.462289 -290.665824) (xy 35.428682 -290.640008) (xy 35.418776 -290.632134)
			(xy 35.394138 -290.627816) (xy 35.289998 -290.660582) (xy 35.272218 -290.678616) (xy 35.268662 -290.690554)
			(xy 35.255581 -290.732077) (xy 35.222427 -290.812581) (xy 35.181566 -290.88946) (xy 35.157918 -290.926012)
			(xy 35.150298 -290.937696) (xy 35.148774 -290.965128) (xy 35.202622 -291.06876) (xy 35.22599 -291.083492)
			(xy 35.23996 -291.083746) (xy 35.282372 -291.085332) (xy 35.36663 -291.095569) (xy 35.44953 -291.113787)
			(xy 35.530317 -291.139821) (xy 35.608256 -291.173433) (xy 35.682637 -291.214318) (xy 35.752786 -291.262104)
			(xy 35.818062 -291.316355) (xy 35.877872 -291.37658) (xy 35.931673 -291.442228) (xy 35.955732 -291.477192)
			(xy 35.962119 -291.485725) (xy 35.980144 -291.497055) (xy 36.001214 -291.500111) (xy 36.011612 -291.497766)
			(xy 36.050906 -291.487188) (xy 36.130928 -291.472384) (xy 36.211968 -291.464949) (xy 36.252658 -291.464492)
			(xy 36.295007 -291.46498) (xy 36.379322 -291.473031) (xy 36.46249 -291.48906) (xy 36.543758 -291.512922)
			(xy 36.62239 -291.544401) (xy 36.697673 -291.583212) (xy 36.768926 -291.629004) (xy 36.835504 -291.681361)
			(xy 36.896803 -291.73981) (xy 36.952269 -291.803821) (xy 37.001399 -291.872814) (xy 37.043748 -291.946165)
			(xy 37.078933 -292.02321) (xy 37.106636 -292.10325) (xy 37.126604 -292.185561) (xy 37.138658 -292.269397)
			(xy 37.142688 -292.354) (xy 37.138658 -292.438603) (xy 37.126604 -292.522439) (xy 37.106636 -292.60475)
			(xy 37.078933 -292.68479) (xy 37.043748 -292.761835) (xy 37.001399 -292.835186) (xy 36.952269 -292.904179)
			(xy 36.896803 -292.96819) (xy 36.835504 -293.026639) (xy 36.768926 -293.078996) (xy 36.697673 -293.124788)
			(xy 36.62239 -293.163599) (xy 36.543758 -293.195078) (xy 36.46249 -293.21894) (xy 36.379322 -293.234969)
			(xy 36.295007 -293.24302) (xy 36.252658 -293.243508) (xy 36.209078 -293.242978) (xy 36.122337 -293.234451)
			(xy 36.036846 -293.217485) (xy 35.953422 -293.192241) (xy 35.872867 -293.158961) (xy 35.795952 -293.117964)
			(xy 35.723414 -293.069643) (xy 35.655948 -293.014461) (xy 35.594201 -292.952946) (xy 35.538764 -292.88569)
			(xy 35.514026 -292.849808) (xy 35.50767 -292.841248) (xy 35.489629 -292.829924) (xy 35.468547 -292.82688)
			(xy 35.458146 -292.829234) (xy 35.418854 -292.839821) (xy 35.338831 -292.854621) (xy 35.25779 -292.862053)
			(xy 35.2171 -292.862508) (xy 35.175998 -292.862033) (xy 35.094143 -292.854448) (xy 35.013338 -292.839343)
			(xy 34.934271 -292.816847) (xy 34.857617 -292.787151) (xy 34.78403 -292.750509) (xy 34.714138 -292.707234)
			(xy 34.648537 -292.657694) (xy 34.587787 -292.602313) (xy 34.532406 -292.541563) (xy 34.482866 -292.475962)
			(xy 34.439591 -292.40607) (xy 34.402949 -292.332483) (xy 34.373253 -292.255829) (xy 34.350757 -292.176762)
			(xy 34.335652 -292.095957) (xy 34.328067 -292.014102) (xy 34.327592 -291.973) (xy 34.328131 -291.929543)
			(xy 34.336621 -291.843044) (xy 34.35351 -291.757786) (xy 34.378637 -291.674583) (xy 34.411763 -291.594228)
			(xy 34.45257 -291.517489) (xy 34.476182 -291.481002) (xy 34.483802 -291.469318) (xy 34.485326 -291.441886)
			(xy 34.431478 -291.338254) (xy 34.40811 -291.323522) (xy 34.39414 -291.323268) (xy 34.351208 -291.321686)
			(xy 34.265932 -291.311198) (xy 34.182066 -291.292538) (xy 34.100388 -291.265878) (xy 34.021662 -291.231469)
			(xy 33.94662 -291.18963) (xy 33.875961 -291.14075) (xy 33.810343 -291.085287) (xy 33.750379 -291.023755)
			(xy 33.696626 -290.956729) (xy 33.649586 -290.884833) (xy 33.609696 -290.808736) (xy 33.577329 -290.729148)
			(xy 33.552786 -290.646811) (xy 33.536295 -290.56249) (xy 33.52801 -290.476973) (xy 33.527492 -290.434014)
			(xy 33.140346 -290.434014) (xy 33.139066 -290.447529) (xy 33.123314 -290.529973) (xy 33.099866 -290.610566)
			(xy 33.068931 -290.688593) (xy 33.030784 -290.763359) (xy 32.985764 -290.834199) (xy 32.934271 -290.900483)
			(xy 32.876763 -290.961622) (xy 32.813752 -291.017072) (xy 32.745798 -291.06634) (xy 32.673505 -291.108988)
			(xy 32.597516 -291.144637) (xy 32.518507 -291.17297) (xy 32.477964 -291.183822) (xy 32.466534 -291.18687)
			(xy 32.449008 -291.201602) (xy 32.406844 -291.295582) (xy 32.407352 -291.318442) (xy 32.41294 -291.32911)
			(xy 32.432022 -291.367088) (xy 32.463721 -291.445956) (xy 32.487753 -291.527487) (xy 32.503898 -291.610939)
			(xy 32.51201 -291.69555) (xy 32.512508 -291.73805) (xy 32.512081 -291.779153) (xy 32.504492 -291.861009)
			(xy 32.489382 -291.941815) (xy 32.466882 -292.020883) (xy 32.437182 -292.097537) (xy 32.400536 -292.171124)
			(xy 32.357258 -292.241016) (xy 32.307715 -292.306616) (xy 32.252331 -292.367366) (xy 32.191578 -292.422747)
			(xy 32.125974 -292.472286) (xy 32.05608 -292.515561) (xy 31.982491 -292.552202) (xy 31.905835 -292.581898)
			(xy 31.826766 -292.604394) (xy 31.745959 -292.619499) (xy 31.664103 -292.627083) (xy 31.623 -292.627558)
			(xy 31.582461 -292.627135) (xy 31.50172 -292.619751) (xy 31.421985 -292.605052) (xy 31.343918 -292.583161)
			(xy 31.268167 -292.554259) (xy 31.195358 -292.518586) (xy 31.126096 -292.476438) (xy 31.060956 -292.428164)
			(xy 31.030418 -292.401498) (xy 31.018988 -292.391338) (xy 30.98927 -292.386766) (xy 30.877002 -292.438836)
			(xy 30.861 -292.464236) (xy 30.861254 -292.47973) (xy 30.861508 -292.50005) (xy 30.861004 -292.542398)
			(xy 30.852953 -292.626712) (xy 30.836924 -292.709878) (xy 30.813063 -292.791145) (xy 30.781584 -292.869775)
			(xy 30.742773 -292.945056) (xy 30.696983 -293.016308) (xy 30.644627 -293.082884) (xy 30.586179 -293.144182)
			(xy 30.522169 -293.199647) (xy 30.453177 -293.248776) (xy 30.379827 -293.291125) (xy 30.302784 -293.326309)
			(xy 30.222745 -293.354011) (xy 30.140436 -293.373979) (xy 30.056601 -293.386032) (xy 29.972 -293.390063)
			(xy 29.887399 -293.386032) (xy 29.803564 -293.373979) (xy 29.721255 -293.354011) (xy 29.641216 -293.326309)
			(xy 29.564173 -293.291125) (xy 29.490823 -293.248776) (xy 29.421831 -293.199647) (xy 29.357821 -293.144182)
			(xy 29.299373 -293.082884) (xy 29.247017 -293.016308) (xy 29.201227 -292.945056) (xy 29.162416 -292.869775)
			(xy 29.130937 -292.791145) (xy 29.107076 -292.709878) (xy 29.091047 -292.626712) (xy 29.082996 -292.542398)
			(xy 29.082492 -292.50005) (xy 29.082957 -292.458232) (xy 29.090811 -292.374966) (xy 29.106454 -292.292807)
			(xy 29.129747 -292.212481) (xy 29.160485 -292.134699) (xy 29.179012 -292.097206) (xy 29.186378 -292.082728)
			(xy 29.181806 -292.050978) (xy 29.093414 -291.958014) (xy 29.062172 -291.951664) (xy 29.047186 -291.958268)
			(xy 29.004552 -291.976498) (xy 28.916322 -292.005026) (xy 28.825602 -292.02422) (xy 28.733378 -292.033869)
			(xy 28.687014 -292.034468) (xy 28.645088 -292.034039) (xy 28.561609 -292.026149) (xy 28.479242 -292.010439)
			(xy 28.39872 -291.987046) (xy 28.320756 -291.95618) (xy 28.246043 -291.918113) (xy 28.175244 -291.873185)
			(xy 28.108988 -291.821793) (xy 28.047861 -291.764394) (xy 27.992408 -291.701497) (xy 27.94312 -291.633661)
			(xy 27.900435 -291.561488) (xy 27.864731 -291.485617) (xy 27.836325 -291.406724) (xy 27.81547 -291.325507)
			(xy 27.802351 -291.242688) (xy 27.797084 -291.159003) (xy 20.589549 -291.159003) (xy 20.594607 -291.171523)
			(xy 20.618863 -291.253423) (xy 20.635159 -291.337269) (xy 20.643345 -291.422292) (xy 20.64385 -291.465)
			(xy 20.643346 -291.507348) (xy 20.635295 -291.591662) (xy 20.619266 -291.674828) (xy 20.595405 -291.756095)
			(xy 20.563926 -291.834725) (xy 20.525115 -291.910006) (xy 20.479325 -291.981258) (xy 20.426969 -292.047834)
			(xy 20.368521 -292.109132) (xy 20.304511 -292.164597) (xy 20.235519 -292.213726) (xy 20.162169 -292.256075)
			(xy 20.085126 -292.291259) (xy 20.005087 -292.318961) (xy 19.922778 -292.338929) (xy 19.838943 -292.350982)
			(xy 19.754342 -292.355013) (xy 19.669741 -292.350982) (xy 19.585906 -292.338929) (xy 19.503597 -292.318961)
			(xy 19.423558 -292.291259) (xy 19.346515 -292.256075) (xy 19.273165 -292.213726) (xy 19.204173 -292.164597)
			(xy 19.140163 -292.109132) (xy 19.081715 -292.047834) (xy 19.029359 -291.981258) (xy 18.983569 -291.910006)
			(xy 18.944758 -291.834725) (xy 18.913279 -291.756095) (xy 18.889418 -291.674828) (xy 18.873389 -291.591662)
			(xy 18.865338 -291.507348) (xy 18.864834 -291.465) (xy 18.865325 -291.422875) (xy 18.873323 -291.339006)
			(xy 18.889209 -291.256268) (xy 18.912842 -291.1754) (xy 18.944009 -291.097128) (xy 18.982433 -291.02215)
			(xy 19.027769 -290.951138) (xy 19.053302 -290.91763) (xy 19.058587 -290.910198) (xy 19.064034 -290.892809)
			(xy 19.063064 -290.874613) (xy 19.055799 -290.857902) (xy 19.049746 -290.851082) (xy 19.020421 -290.82003)
			(xy 18.967253 -290.753179) (xy 18.920738 -290.68154) (xy 18.881301 -290.605774) (xy 18.849308 -290.526576)
			(xy 18.825051 -290.444677) (xy 18.808755 -290.36083) (xy 18.800569 -290.275808) (xy 18.800064 -290.2331)
			(xy 18.026212 -290.2331) (xy 17.962501 -290.283203) (xy 17.89125 -290.328994) (xy 17.815968 -290.367804)
			(xy 17.737338 -290.399283) (xy 17.656072 -290.423146) (xy 17.572906 -290.439175) (xy 17.488592 -290.447226)
			(xy 17.446244 -290.44773) (xy 17.402473 -290.44723) (xy 17.315354 -290.438616) (xy 17.229503 -290.421487)
			(xy 17.14575 -290.396009) (xy 17.064904 -290.362427) (xy 16.987747 -290.321068) (xy 16.915026 -290.272329)
			(xy 16.847444 -290.216684) (xy 16.785654 -290.15467) (xy 16.730253 -290.086887) (xy 16.70558 -290.050728)
			(xy 16.698468 -290.04006) (xy 16.67637 -290.028122) (xy 16.566388 -290.02736) (xy 16.54429 -290.039044)
			(xy 16.536924 -290.049458) (xy 16.512144 -290.084831) (xy 16.456713 -290.151068) (xy 16.395119 -290.211618)
			(xy 16.327946 -290.265912) (xy 16.255824 -290.313436) (xy 16.179434 -290.353743) (xy 16.099496 -290.386453)
			(xy 16.016763 -290.411259) (xy 15.932015 -290.427926) (xy 15.84605 -290.436297) (xy 15.802864 -290.436808)
			(xy 15.760515 -290.43632) (xy 15.676199 -290.428269) (xy 15.593031 -290.41224) (xy 15.511763 -290.388378)
			(xy 15.433132 -290.356899) (xy 15.357848 -290.318088) (xy 15.286595 -290.272297) (xy 15.220017 -290.21994)
			(xy 15.158718 -290.161491) (xy 15.103252 -290.09748) (xy 15.054122 -290.028487) (xy 15.011772 -289.955136)
			(xy 14.976587 -289.878091) (xy 14.948885 -289.798051) (xy 14.928916 -289.715739) (xy 14.916862 -289.631903)
			(xy 14.912832 -289.5473) (xy 9.99972 -289.5473) (xy 9.99679 -289.565957) (xy 9.972941 -289.666138)
			(xy 9.941366 -289.764159) (xy 9.902258 -289.859425) (xy 9.855854 -289.951358) (xy 9.802435 -290.039401)
			(xy 9.742326 -290.123018) (xy 9.67589 -290.201704) (xy 9.640062 -290.238688) (xy 9.632696 -290.2458)
			(xy 9.62533 -290.264088) (xy 9.62533 -290.356036) (xy 9.632696 -290.374324) (xy 9.640062 -290.381436)
			(xy 9.675893 -290.418419) (xy 9.742333 -290.497103) (xy 9.802447 -290.580719) (xy 9.85587 -290.668761)
			(xy 9.902278 -290.760694) (xy 9.94139 -290.85596) (xy 9.972969 -290.953982) (xy 9.996822 -291.054164)
			(xy 10.012804 -291.155899) (xy 10.02082 -291.258569) (xy 10.02082 -291.361551) (xy 10.012804 -291.464221)
			(xy 10.000044 -291.545448) (xy 16.641568 -291.545448) (xy 16.641568 -291.460752) (xy 16.649619 -291.376438)
			(xy 16.665648 -291.293272) (xy 16.689509 -291.212005) (xy 16.720988 -291.133375) (xy 16.759799 -291.058094)
			(xy 16.805589 -290.986842) (xy 16.857945 -290.920266) (xy 16.916393 -290.858968) (xy 16.980403 -290.803503)
			(xy 17.049395 -290.754374) (xy 17.122745 -290.712025) (xy 17.199788 -290.676841) (xy 17.279827 -290.649139)
			(xy 17.362136 -290.629171) (xy 17.445971 -290.617118) (xy 17.530572 -290.613088) (xy 17.615173 -290.617118)
			(xy 17.699008 -290.629171) (xy 17.781317 -290.649139) (xy 17.861356 -290.676841) (xy 17.938399 -290.712025)
			(xy 18.011749 -290.754374) (xy 18.080741 -290.803503) (xy 18.144751 -290.858968) (xy 18.203199 -290.920266)
			(xy 18.255555 -290.986842) (xy 18.301345 -291.058094) (xy 18.340156 -291.133375) (xy 18.371635 -291.212005)
			(xy 18.395496 -291.293272) (xy 18.411525 -291.376438) (xy 18.419576 -291.460752) (xy 18.42008 -291.5031)
			(xy 18.419576 -291.545448) (xy 18.411525 -291.629762) (xy 18.395496 -291.712928) (xy 18.371635 -291.794195)
			(xy 18.340156 -291.872825) (xy 18.301345 -291.948106) (xy 18.255555 -292.019358) (xy 18.203199 -292.085934)
			(xy 18.144751 -292.147232) (xy 18.080741 -292.202697) (xy 18.011749 -292.251826) (xy 17.938399 -292.294175)
			(xy 17.861356 -292.329359) (xy 17.781317 -292.357061) (xy 17.699008 -292.377029) (xy 17.615173 -292.389082)
			(xy 17.530572 -292.393113) (xy 17.445971 -292.389082) (xy 17.362136 -292.377029) (xy 17.279827 -292.357061)
			(xy 17.199788 -292.329359) (xy 17.122745 -292.294175) (xy 17.049395 -292.251826) (xy 16.980403 -292.202697)
			(xy 16.916393 -292.147232) (xy 16.857945 -292.085934) (xy 16.805589 -292.019358) (xy 16.759799 -291.948106)
			(xy 16.720988 -291.872825) (xy 16.689509 -291.794195) (xy 16.665648 -291.712928) (xy 16.649619 -291.629762)
			(xy 16.641568 -291.545448) (xy 10.000044 -291.545448) (xy 9.996822 -291.565956) (xy 9.972969 -291.666138)
			(xy 9.94139 -291.76416) (xy 9.902278 -291.859426) (xy 9.85587 -291.951359) (xy 9.802447 -292.039401)
			(xy 9.742333 -292.123017) (xy 9.675893 -292.201701) (xy 9.640062 -292.238684) (xy 9.632696 -292.245796)
			(xy 9.62533 -292.264084) (xy 9.62533 -292.356032) (xy 9.632696 -292.37432) (xy 9.640062 -292.381432)
			(xy 9.675889 -292.418419) (xy 9.742329 -292.497103) (xy 9.802443 -292.580719) (xy 9.844694 -292.650348)
			(xy 14.471646 -292.650348) (xy 14.471646 -292.565652) (xy 14.479697 -292.481338) (xy 14.495726 -292.398172)
			(xy 14.519587 -292.316905) (xy 14.551066 -292.238275) (xy 14.589877 -292.162994) (xy 14.635667 -292.091742)
			(xy 14.688023 -292.025166) (xy 14.746471 -291.963868) (xy 14.810481 -291.908403) (xy 14.879473 -291.859274)
			(xy 14.952823 -291.816925) (xy 15.029866 -291.781741) (xy 15.109905 -291.754039) (xy 15.192214 -291.734071)
			(xy 15.276049 -291.722018) (xy 15.36065 -291.717988) (xy 15.445251 -291.722018) (xy 15.529086 -291.734071)
			(xy 15.611395 -291.754039) (xy 15.691434 -291.781741) (xy 15.768477 -291.816925) (xy 15.841827 -291.859274)
			(xy 15.910819 -291.908403) (xy 15.974829 -291.963868) (xy 16.033277 -292.025166) (xy 16.085633 -292.091742)
			(xy 16.131423 -292.162994) (xy 16.170234 -292.238275) (xy 16.201713 -292.316905) (xy 16.225574 -292.398172)
			(xy 16.241603 -292.481338) (xy 16.249654 -292.565652) (xy 16.250158 -292.608) (xy 16.249654 -292.650348)
			(xy 16.241603 -292.734662) (xy 16.225574 -292.817828) (xy 16.201713 -292.899095) (xy 16.170234 -292.977725)
			(xy 16.131423 -293.053006) (xy 16.085633 -293.124258) (xy 16.033277 -293.190834) (xy 15.974829 -293.252132)
			(xy 15.910819 -293.307597) (xy 15.841827 -293.356726) (xy 15.768477 -293.399075) (xy 15.691434 -293.434259)
			(xy 15.611395 -293.461961) (xy 15.529086 -293.481929) (xy 15.445251 -293.493982) (xy 15.36065 -293.498013)
			(xy 15.276049 -293.493982) (xy 15.192214 -293.481929) (xy 15.109905 -293.461961) (xy 15.029866 -293.434259)
			(xy 14.952823 -293.399075) (xy 14.879473 -293.356726) (xy 14.810481 -293.307597) (xy 14.746471 -293.252132)
			(xy 14.688023 -293.190834) (xy 14.635667 -293.124258) (xy 14.589877 -293.053006) (xy 14.551066 -292.977725)
			(xy 14.519587 -292.899095) (xy 14.495726 -292.817828) (xy 14.479697 -292.734662) (xy 14.471646 -292.650348)
			(xy 9.844694 -292.650348) (xy 9.855866 -292.66876) (xy 9.902275 -292.760693) (xy 9.941387 -292.855959)
			(xy 9.972965 -292.95398) (xy 9.996818 -293.054162) (xy 10.012801 -293.155896) (xy 10.020817 -293.258566)
			(xy 10.020817 -293.361548) (xy 10.012802 -293.464218) (xy 9.996819 -293.565953) (xy 9.972967 -293.666135)
			(xy 9.941389 -293.764156) (xy 9.902277 -293.859422) (xy 9.855869 -293.951355) (xy 9.802446 -294.039397)
			(xy 9.742332 -294.123013) (xy 9.675892 -294.201697) (xy 9.640062 -294.23868) (xy 9.632696 -294.245792)
			(xy 9.62533 -294.26408) (xy 9.62533 -294.356028) (xy 9.632696 -294.374316) (xy 9.640062 -294.381428)
			(xy 9.673434 -294.415801) (xy 9.735657 -294.48866) (xy 9.792437 -294.565835) (xy 9.839118 -294.64)
			(xy 14.731492 -294.64) (xy 14.731996 -294.597652) (xy 14.740047 -294.513338) (xy 14.756076 -294.430172)
			(xy 14.779937 -294.348905) (xy 14.811416 -294.270275) (xy 14.850227 -294.194994) (xy 14.896017 -294.123742)
			(xy 14.948373 -294.057166) (xy 15.006821 -293.995868) (xy 15.070831 -293.940403) (xy 15.139823 -293.891274)
			(xy 15.213173 -293.848925) (xy 15.290216 -293.813741) (xy 15.370255 -293.786039) (xy 15.452564 -293.766071)
			(xy 15.536399 -293.754018) (xy 15.621 -293.749988) (xy 15.705601 -293.754018) (xy 15.789436 -293.766071)
			(xy 15.871745 -293.786039) (xy 15.951784 -293.813741) (xy 16.028827 -293.848925) (xy 16.102177 -293.891274)
			(xy 16.171169 -293.940403) (xy 16.235179 -293.995868) (xy 16.293627 -294.057166) (xy 16.345983 -294.123742)
			(xy 16.391773 -294.194994) (xy 16.430584 -294.270275) (xy 16.462063 -294.348905) (xy 16.485924 -294.430172)
			(xy 16.501953 -294.513338) (xy 16.510004 -294.597652) (xy 16.510508 -294.64) (xy 16.510087 -294.678761)
			(xy 16.503361 -294.755992) (xy 16.489932 -294.832342) (xy 16.469904 -294.907233) (xy 16.443428 -294.980095)
			(xy 16.42745 -295.015412) (xy 16.42237 -295.026334) (xy 16.422878 -295.049956) (xy 16.472408 -295.14292)
			(xy 16.491712 -295.156636) (xy 16.50365 -295.158414) (xy 16.546568 -295.165811) (xy 16.63083 -295.187837)
			(xy 16.712537 -295.21799) (xy 16.790908 -295.255982) (xy 16.865191 -295.301449) (xy 16.934677 -295.353957)
			(xy 16.9987 -295.413002) (xy 17.056649 -295.478019) (xy 17.107967 -295.548388) (xy 17.130522 -295.585642)
			(xy 17.135289 -295.593062) (xy 17.148841 -295.604333) (xy 17.165399 -295.610372) (xy 17.17421 -295.610788)
			(xy 17.26184 -295.610788) (xy 17.270658 -295.610405) (xy 17.287234 -295.604383) (xy 17.300766 -295.593074)
			(xy 17.305528 -295.585642) (xy 17.327214 -295.549664) (xy 17.376486 -295.481617) (xy 17.431955 -295.418519)
			(xy 17.493125 -295.360932) (xy 17.559451 -295.309368) (xy 17.630344 -295.264287) (xy 17.705171 -295.22609)
			(xy 17.783267 -295.195118) (xy 17.863934 -295.171647) (xy 17.946455 -295.155886) (xy 18.030094 -295.147975)
			(xy 18.0721 -295.147492) (xy 18.118739 -295.148062) (xy 18.211509 -295.157794) (xy 18.30275 -295.177183)
			(xy 18.39146 -295.206015) (xy 18.434304 -295.224454) (xy 18.444464 -295.229026) (xy 18.466562 -295.228772)
			(xy 18.556478 -295.186608) (xy 18.570702 -295.16959) (xy 18.573496 -295.158922) (xy 18.585278 -295.118178)
			(xy 18.615526 -295.038933) (xy 18.65318 -294.962928) (xy 18.697898 -294.890852) (xy 18.749274 -294.82336)
			(xy 18.806841 -294.761065) (xy 18.870076 -294.704533) (xy 18.938406 -294.654277) (xy 19.011209 -294.610753)
			(xy 19.087824 -294.574357) (xy 19.167556 -294.54542) (xy 19.208496 -294.534336) (xy 19.219672 -294.531542)
			(xy 19.237198 -294.51681) (xy 19.279362 -294.423338) (xy 19.278854 -294.400224) (xy 19.27352 -294.38981)
			(xy 19.254888 -294.352243) (xy 19.223991 -294.274278) (xy 19.200579 -294.193749) (xy 19.184859 -294.111373)
			(xy 19.17697 -294.027882) (xy 19.176492 -293.98595) (xy 19.176996 -293.943602) (xy 19.185047 -293.859288)
			(xy 19.201076 -293.776122) (xy 19.224937 -293.694855) (xy 19.256416 -293.616225) (xy 19.295227 -293.540944)
			(xy 19.341017 -293.469692) (xy 19.393373 -293.403116) (xy 19.451821 -293.341818) (xy 19.515831 -293.286353)
			(xy 19.584823 -293.237224) (xy 19.658173 -293.194875) (xy 19.735216 -293.159691) (xy 19.815255 -293.131989)
			(xy 19.897564 -293.112021) (xy 19.981399 -293.099968) (xy 20.066 -293.095938) (xy 20.150601 -293.099968)
			(xy 20.234436 -293.112021) (xy 20.316745 -293.131989) (xy 20.396784 -293.159691) (xy 20.473827 -293.194875)
			(xy 20.547177 -293.237224) (xy 20.616169 -293.286353) (xy 20.680179 -293.341818) (xy 20.738627 -293.403116)
			(xy 20.790983 -293.469692) (xy 20.836773 -293.540944) (xy 20.875584 -293.616225) (xy 20.907063 -293.694855)
			(xy 20.930924 -293.776122) (xy 20.946953 -293.859288) (xy 20.949346 -293.88435) (xy 31.367988 -293.88435)
			(xy 31.372018 -293.799749) (xy 31.384071 -293.715914) (xy 31.404039 -293.633605) (xy 31.431741 -293.553566)
			(xy 31.466925 -293.476523) (xy 31.509274 -293.403173) (xy 31.558403 -293.334181) (xy 31.613868 -293.270171)
			(xy 31.675166 -293.211723) (xy 31.741742 -293.159367) (xy 31.812994 -293.113577) (xy 31.888275 -293.074766)
			(xy 31.966905 -293.043287) (xy 32.048172 -293.019426) (xy 32.131338 -293.003397) (xy 32.215652 -292.995346)
			(xy 32.258 -292.994842) (xy 32.302723 -292.995359) (xy 32.391716 -293.004346) (xy 32.479359 -293.022218)
			(xy 32.564765 -293.048795) (xy 32.647073 -293.083809) (xy 32.725452 -293.126906) (xy 32.79911 -293.177651)
			(xy 32.833564 -293.20617) (xy 32.84093 -293.21252) (xy 32.859218 -293.218616) (xy 32.948372 -293.21379)
			(xy 32.966152 -293.205916) (xy 32.972756 -293.198804) (xy 33.000687 -293.170131) (xy 33.060875 -293.117349)
			(xy 33.125562 -293.07019) (xy 33.194226 -293.029036) (xy 33.266311 -292.994219) (xy 33.341233 -292.966021)
			(xy 33.418385 -292.94467) (xy 33.497145 -292.93034) (xy 33.576874 -292.923145) (xy 33.6169 -292.922706)
			(xy 33.659249 -292.923182) (xy 33.743564 -292.931233) (xy 33.826732 -292.947262) (xy 33.907999 -292.971124)
			(xy 33.98663 -293.002603) (xy 34.061913 -293.041414) (xy 34.133166 -293.087206) (xy 34.199743 -293.139563)
			(xy 34.261042 -293.198011) (xy 34.316508 -293.262022) (xy 34.365638 -293.331015) (xy 34.407987 -293.404366)
			(xy 34.443172 -293.481411) (xy 34.470874 -293.561451) (xy 34.490843 -293.643761) (xy 34.502896 -293.727598)
			(xy 34.506927 -293.8122) (xy 34.502896 -293.896802) (xy 34.490843 -293.980639) (xy 34.470874 -294.062949)
			(xy 34.443172 -294.142989) (xy 34.407987 -294.220034) (xy 34.365638 -294.293385) (xy 34.316508 -294.362378)
			(xy 34.261042 -294.426389) (xy 34.199743 -294.484837) (xy 34.133166 -294.537194) (xy 34.061913 -294.582986)
			(xy 33.98663 -294.621797) (xy 33.907999 -294.653276) (xy 33.826732 -294.677138) (xy 33.743564 -294.693167)
			(xy 33.659249 -294.701218) (xy 33.6169 -294.701722) (xy 33.572178 -294.701189) (xy 33.483185 -294.692204)
			(xy 33.395544 -294.674333) (xy 33.310138 -294.647758) (xy 33.22783 -294.612747) (xy 33.149451 -294.569653)
			(xy 33.075791 -294.518911) (xy 33.041336 -294.490394) (xy 33.03397 -294.484044) (xy 33.015682 -294.477948)
			(xy 32.926528 -294.482774) (xy 32.908748 -294.490648) (xy 32.902144 -294.49776) (xy 32.874206 -294.526426)
			(xy 32.81402 -294.579209) (xy 32.749334 -294.626369) (xy 32.680671 -294.667525) (xy 32.608587 -294.702343)
			(xy 32.533666 -294.730542) (xy 32.456514 -294.751893) (xy 32.377754 -294.766224) (xy 32.298026 -294.773419)
			(xy 32.258 -294.773858) (xy 32.215652 -294.773354) (xy 32.131338 -294.765303) (xy 32.048172 -294.749274)
			(xy 31.966905 -294.725413) (xy 31.888275 -294.693934) (xy 31.812994 -294.655123) (xy 31.741742 -294.609333)
			(xy 31.675166 -294.556977) (xy 31.613868 -294.498529) (xy 31.558403 -294.434519) (xy 31.509274 -294.365527)
			(xy 31.466925 -294.292177) (xy 31.431741 -294.215134) (xy 31.404039 -294.135095) (xy 31.384071 -294.052786)
			(xy 31.372018 -293.968951) (xy 31.367988 -293.88435) (xy 20.949346 -293.88435) (xy 20.955004 -293.943602)
			(xy 20.955508 -293.98595) (xy 20.955045 -294.027832) (xy 20.947184 -294.111226) (xy 20.931516 -294.193511)
			(xy 20.908182 -294.273959) (xy 20.877387 -294.351856) (xy 20.839405 -294.426513) (xy 20.794572 -294.497268)
			(xy 20.743285 -294.563495) (xy 20.685999 -294.624606) (xy 20.62322 -294.680061) (xy 20.555506 -294.729367)
			(xy 20.483456 -294.772089) (xy 20.407709 -294.807847) (xy 20.328935 -294.836325) (xy 20.288504 -294.847264)
			(xy 20.277328 -294.850058) (xy 20.259802 -294.86479) (xy 20.217638 -294.958262) (xy 20.218146 -294.981376)
			(xy 20.22348 -294.99179) (xy 20.242112 -295.029357) (xy 20.273009 -295.107322) (xy 20.296421 -295.187851)
			(xy 20.312141 -295.270227) (xy 20.32003 -295.353718) (xy 20.320508 -295.39565) (xy 20.320081 -295.436753)
			(xy 20.312492 -295.518609) (xy 20.297382 -295.599415) (xy 20.274882 -295.678483) (xy 20.245182 -295.755137)
			(xy 20.208536 -295.828724) (xy 20.165258 -295.898616) (xy 20.115715 -295.964216) (xy 20.060331 -296.024966)
			(xy 19.999578 -296.080347) (xy 19.933974 -296.129886) (xy 19.86408 -296.173161) (xy 19.797428 -296.206348)
			(xy 31.368996 -296.206348) (xy 31.368996 -296.121652) (xy 31.377047 -296.037338) (xy 31.393076 -295.954172)
			(xy 31.416937 -295.872905) (xy 31.448416 -295.794275) (xy 31.487227 -295.718994) (xy 31.533017 -295.647742)
			(xy 31.585373 -295.581166) (xy 31.643821 -295.519868) (xy 31.707831 -295.464403) (xy 31.776823 -295.415274)
			(xy 31.850173 -295.372925) (xy 31.927216 -295.337741) (xy 32.007255 -295.310039) (xy 32.089564 -295.290071)
			(xy 32.173399 -295.278018) (xy 32.258 -295.273988) (xy 32.342601 -295.278018) (xy 32.426436 -295.290071)
			(xy 32.508745 -295.310039) (xy 32.588784 -295.337741) (xy 32.665827 -295.372925) (xy 32.739177 -295.415274)
			(xy 32.808169 -295.464403) (xy 32.872179 -295.519868) (xy 32.930627 -295.581166) (xy 32.982983 -295.647742)
			(xy 33.028773 -295.718994) (xy 33.067584 -295.794275) (xy 33.099063 -295.872905) (xy 33.122924 -295.954172)
			(xy 33.138888 -296.037) (xy 34.327592 -296.037) (xy 34.32803 -295.993687) (xy 34.336441 -295.907472)
			(xy 34.353194 -295.822482) (xy 34.37813 -295.739524) (xy 34.411013 -295.659382) (xy 34.45153 -295.582817)
			(xy 34.499299 -295.510553) (xy 34.553867 -295.443276) (xy 34.614716 -295.381622) (xy 34.681271 -295.326175)
			(xy 34.752901 -295.277461) (xy 34.828928 -295.235941) (xy 34.90863 -295.202009) (xy 34.991254 -295.175985)
			(xy 35.076016 -295.158117) (xy 35.162114 -295.148574) (xy 35.205416 -295.147492) (xy 35.218841 -295.1469)
			(xy 35.244688 -295.13958) (xy 35.26773 -295.125771) (xy 35.286369 -295.106427) (xy 35.299316 -295.08289)
			(xy 35.305673 -295.05679) (xy 35.305746 -295.043352) (xy 35.305492 -295.021) (xy 35.305996 -294.978652)
			(xy 35.314047 -294.894338) (xy 35.330076 -294.811172) (xy 35.353937 -294.729905) (xy 35.385416 -294.651275)
			(xy 35.424227 -294.575994) (xy 35.470017 -294.504742) (xy 35.522373 -294.438166) (xy 35.580821 -294.376868)
			(xy 35.644831 -294.321403) (xy 35.713823 -294.272274) (xy 35.787173 -294.229925) (xy 35.864216 -294.194741)
			(xy 35.944255 -294.167039) (xy 36.026564 -294.147071) (xy 36.110399 -294.135018) (xy 36.195 -294.130988)
			(xy 36.279601 -294.135018) (xy 36.363436 -294.147071) (xy 36.445745 -294.167039) (xy 36.525784 -294.194741)
			(xy 36.602827 -294.229925) (xy 36.676177 -294.272274) (xy 36.745169 -294.321403) (xy 36.809179 -294.376868)
			(xy 36.867627 -294.438166) (xy 36.919983 -294.504742) (xy 36.965773 -294.575994) (xy 37.004584 -294.651275)
			(xy 37.036063 -294.729905) (xy 37.059924 -294.811172) (xy 37.075953 -294.894338) (xy 37.084004 -294.978652)
			(xy 37.084508 -295.021) (xy 37.08407 -295.064313) (xy 37.075659 -295.150528) (xy 37.058906 -295.235518)
			(xy 37.03397 -295.318476) (xy 37.001087 -295.398618) (xy 36.96057 -295.475183) (xy 36.912801 -295.547447)
			(xy 36.858233 -295.614724) (xy 36.797384 -295.676378) (xy 36.730829 -295.731825) (xy 36.659199 -295.780539)
			(xy 36.583172 -295.822059) (xy 36.50347 -295.855991) (xy 36.420846 -295.882015) (xy 36.336084 -295.899883)
			(xy 36.249986 -295.909426) (xy 36.206684 -295.910508) (xy 36.193259 -295.9111) (xy 36.167412 -295.91842)
			(xy 36.14437 -295.932229) (xy 36.125731 -295.951573) (xy 36.112784 -295.97511) (xy 36.106427 -296.00121)
			(xy 36.106354 -296.014648) (xy 36.106608 -296.037) (xy 36.106104 -296.079348) (xy 36.098053 -296.163662)
			(xy 36.082024 -296.246828) (xy 36.058163 -296.328095) (xy 36.026684 -296.406725) (xy 35.987873 -296.482006)
			(xy 35.942083 -296.553258) (xy 35.889727 -296.619834) (xy 35.831279 -296.681132) (xy 35.767269 -296.736597)
			(xy 35.698277 -296.785726) (xy 35.624927 -296.828075) (xy 35.547884 -296.863259) (xy 35.467845 -296.890961)
			(xy 35.385536 -296.910929) (xy 35.301701 -296.922982) (xy 35.2171 -296.927013) (xy 35.132499 -296.922982)
			(xy 35.048664 -296.910929) (xy 34.966355 -296.890961) (xy 34.886316 -296.863259) (xy 34.809273 -296.828075)
			(xy 34.735923 -296.785726) (xy 34.666931 -296.736597) (xy 34.602921 -296.681132) (xy 34.544473 -296.619834)
			(xy 34.492117 -296.553258) (xy 34.446327 -296.482006) (xy 34.407516 -296.406725) (xy 34.376037 -296.328095)
			(xy 34.352176 -296.246828) (xy 34.336147 -296.163662) (xy 34.328096 -296.079348) (xy 34.327592 -296.037)
			(xy 33.138888 -296.037) (xy 33.138953 -296.037338) (xy 33.147004 -296.121652) (xy 33.147508 -296.164)
			(xy 33.147004 -296.206348) (xy 33.138953 -296.290662) (xy 33.122924 -296.373828) (xy 33.099063 -296.455095)
			(xy 33.067584 -296.533725) (xy 33.028773 -296.609006) (xy 32.982983 -296.680258) (xy 32.930627 -296.746834)
			(xy 32.872179 -296.808132) (xy 32.808169 -296.863597) (xy 32.739177 -296.912726) (xy 32.665827 -296.955075)
			(xy 32.588784 -296.990259) (xy 32.508745 -297.017961) (xy 32.426436 -297.037929) (xy 32.342601 -297.049982)
			(xy 32.258 -297.054013) (xy 32.173399 -297.049982) (xy 32.089564 -297.037929) (xy 32.007255 -297.017961)
			(xy 31.927216 -296.990259) (xy 31.850173 -296.955075) (xy 31.776823 -296.912726) (xy 31.707831 -296.863597)
			(xy 31.643821 -296.808132) (xy 31.585373 -296.746834) (xy 31.533017 -296.680258) (xy 31.487227 -296.609006)
			(xy 31.448416 -296.533725) (xy 31.416937 -296.455095) (xy 31.393076 -296.373828) (xy 31.377047 -296.290662)
			(xy 31.368996 -296.206348) (xy 19.797428 -296.206348) (xy 19.790491 -296.209802) (xy 19.713835 -296.239498)
			(xy 19.634766 -296.261994) (xy 19.553959 -296.277099) (xy 19.472103 -296.284683) (xy 19.431 -296.285158)
			(xy 19.384361 -296.284584) (xy 19.291592 -296.274853) (xy 19.200351 -296.255465) (xy 19.11164 -296.226634)
			(xy 19.068796 -296.208196) (xy 19.058636 -296.203624) (xy 19.036538 -296.203878) (xy 18.946622 -296.246042)
			(xy 18.932398 -296.26306) (xy 18.929604 -296.273728) (xy 18.918117 -296.313455) (xy 18.88879 -296.390785)
			(xy 18.852414 -296.46506) (xy 18.809301 -296.535637) (xy 18.759825 -296.60191) (xy 18.704411 -296.663304)
			(xy 18.643539 -296.719291) (xy 18.577734 -296.769388) (xy 18.507564 -296.81316) (xy 18.433634 -296.850232)
			(xy 18.356583 -296.880283) (xy 18.277076 -296.903054) (xy 18.195798 -296.918347) (xy 18.113452 -296.926032)
			(xy 18.0721 -296.926508) (xy 18.030098 -296.92598) (xy 17.946467 -296.918054) (xy 17.863957 -296.902281)
			(xy 17.783299 -296.878803) (xy 17.705214 -296.847828) (xy 17.630395 -296.809631) (xy 17.559509 -296.764554)
			(xy 17.493186 -296.712997) (xy 17.432018 -296.655418) (xy 17.376548 -296.592332) (xy 17.327271 -296.524298)
			(xy 17.305528 -296.488358) (xy 17.30073 -296.480961) (xy 17.287193 -296.469686) (xy 17.270646 -296.463636)
			(xy 17.26184 -296.463212) (xy 17.17421 -296.463212) (xy 17.165395 -296.463629) (xy 17.14882 -296.469635)
			(xy 17.135286 -296.480932) (xy 17.130522 -296.488358) (xy 17.108801 -296.524314) (xy 17.059532 -296.59236)
			(xy 17.004067 -296.655458) (xy 16.942901 -296.713047) (xy 16.876578 -296.764612) (xy 16.805688 -296.809695)
			(xy 16.730865 -296.847893) (xy 16.652773 -296.878868) (xy 16.572109 -296.902343) (xy 16.489592 -296.918108)
			(xy 16.405955 -296.926023) (xy 16.36395 -296.926508) (xy 16.322847 -296.926081) (xy 16.240991 -296.918492)
			(xy 16.160185 -296.903382) (xy 16.081117 -296.880882) (xy 16.004463 -296.851182) (xy 15.930876 -296.814536)
			(xy 15.860984 -296.771258) (xy 15.795384 -296.721715) (xy 15.734634 -296.666331) (xy 15.679253 -296.605578)
			(xy 15.629714 -296.539974) (xy 15.586439 -296.47008) (xy 15.549798 -296.396491) (xy 15.520102 -296.319835)
			(xy 15.497606 -296.240766) (xy 15.482501 -296.159959) (xy 15.474917 -296.078103) (xy 15.474442 -296.037)
			(xy 15.474867 -295.998239) (xy 15.481594 -295.921009) (xy 15.495021 -295.844658) (xy 15.515048 -295.769767)
			(xy 15.541522 -295.696905) (xy 15.5575 -295.661588) (xy 15.56258 -295.650666) (xy 15.562072 -295.627044)
			(xy 15.512542 -295.53408) (xy 15.493238 -295.520364) (xy 15.4813 -295.518586) (xy 15.439988 -295.511511)
			(xy 15.358814 -295.490618) (xy 15.279964 -295.462181) (xy 15.20414 -295.426452) (xy 15.132013 -295.383749)
			(xy 15.064223 -295.33445) (xy 15.001372 -295.278992) (xy 14.944017 -295.217868) (xy 14.892666 -295.151619)
			(xy 14.847775 -295.080833) (xy 14.809742 -295.006137) (xy 14.778905 -294.928195) (xy 14.755538 -294.847698)
			(xy 14.739846 -294.76536) (xy 14.73197 -294.68191) (xy 14.731492 -294.64) (xy 9.839118 -294.64) (xy 9.843475 -294.646922)
			(xy 9.888504 -294.731495) (xy 9.908286 -294.775128) (xy 9.912462 -294.783675) (xy 9.925899 -294.79712)
			(xy 9.934448 -294.80129) (xy 9.96188 -294.813228) (xy 9.970725 -294.816622) (xy 9.989648 -294.817263)
			(xy 9.99871 -294.814498) (xy 10.045232 -294.799276) (xy 10.14076 -294.77791) (xy 10.238056 -294.767162)
			(xy 10.287 -294.766492) (xy 10.329348 -294.766996) (xy 10.413662 -294.775047) (xy 10.496828 -294.791076)
			(xy 10.578095 -294.814937) (xy 10.656725 -294.846416) (xy 10.732006 -294.885227) (xy 10.803258 -294.931017)
			(xy 10.869834 -294.983373) (xy 10.931132 -295.041821) (xy 10.986597 -295.105831) (xy 11.035726 -295.174823)
			(xy 11.078075 -295.248173) (xy 11.113259 -295.325216) (xy 11.140961 -295.405255) (xy 11.160929 -295.487564)
			(xy 11.172982 -295.571399) (xy 11.177013 -295.656) (xy 11.172982 -295.740601) (xy 11.160929 -295.824436)
			(xy 11.140961 -295.906745) (xy 11.113259 -295.986784) (xy 11.078075 -296.063827) (xy 11.035726 -296.137177)
			(xy 10.986597 -296.206169) (xy 10.931132 -296.270179) (xy 10.869834 -296.328627) (xy 10.803258 -296.380983)
			(xy 10.732006 -296.426773) (xy 10.656725 -296.465584) (xy 10.578095 -296.497063) (xy 10.496828 -296.520924)
			(xy 10.413662 -296.536953) (xy 10.329348 -296.545004) (xy 10.287 -296.545508) (xy 10.244707 -296.545017)
			(xy 10.160502 -296.536988) (xy 10.077438 -296.52101) (xy 9.996262 -296.49723) (xy 9.9568 -296.482008)
			(xy 9.94156 -296.475912) (xy 9.910064 -296.483786) (xy 9.826244 -296.582084) (xy 9.823704 -296.614596)
			(xy 9.832086 -296.628566) (xy 9.858034 -296.672646) (xy 9.903837 -296.764115) (xy 9.942435 -296.858851)
			(xy 9.973595 -296.956286) (xy 9.997132 -297.055837) (xy 10.012905 -297.15691) (xy 10.02082 -297.2589)
			(xy 10.021316 -297.310048) (xy 10.020838 -297.36154) (xy 10.012818 -297.46421) (xy 9.996833 -297.565945)
			(xy 9.972977 -297.666127) (xy 9.941397 -297.764148) (xy 9.903131 -297.857348) (xy 14.604996 -297.857348)
			(xy 14.604996 -297.772652) (xy 14.613047 -297.688338) (xy 14.629076 -297.605172) (xy 14.652937 -297.523905)
			(xy 14.684416 -297.445275) (xy 14.723227 -297.369994) (xy 14.769017 -297.298742) (xy 14.821373 -297.232166)
			(xy 14.879821 -297.170868) (xy 14.943831 -297.115403) (xy 15.012823 -297.066274) (xy 15.086173 -297.023925)
			(xy 15.163216 -296.988741) (xy 15.243255 -296.961039) (xy 15.325564 -296.941071) (xy 15.409399 -296.929018)
			(xy 15.494 -296.924988) (xy 15.578601 -296.929018) (xy 15.662436 -296.941071) (xy 15.744745 -296.961039)
			(xy 15.824784 -296.988741) (xy 15.901827 -297.023925) (xy 15.975177 -297.066274) (xy 16.044169 -297.115403)
			(xy 16.108179 -297.170868) (xy 16.166627 -297.232166) (xy 16.218983 -297.298742) (xy 16.264773 -297.369994)
			(xy 16.303584 -297.445275) (xy 16.335063 -297.523905) (xy 16.358924 -297.605172) (xy 16.374953 -297.688338)
			(xy 16.383004 -297.772652) (xy 16.383508 -297.815) (xy 16.383004 -297.857348) (xy 16.374953 -297.941662)
			(xy 16.358924 -298.024828) (xy 16.335063 -298.106095) (xy 16.303584 -298.184725) (xy 16.264773 -298.260006)
			(xy 16.218983 -298.331258) (xy 16.166627 -298.397834) (xy 16.108179 -298.459132) (xy 16.044169 -298.514597)
			(xy 15.975177 -298.563726) (xy 15.901827 -298.606075) (xy 15.824784 -298.641259) (xy 15.744745 -298.668961)
			(xy 15.662436 -298.688929) (xy 15.578601 -298.700982) (xy 15.494 -298.705013) (xy 15.409399 -298.700982)
			(xy 15.325564 -298.688929) (xy 15.243255 -298.668961) (xy 15.163216 -298.641259) (xy 15.086173 -298.606075)
			(xy 15.012823 -298.563726) (xy 14.943831 -298.514597) (xy 14.879821 -298.459132) (xy 14.821373 -298.397834)
			(xy 14.769017 -298.331258) (xy 14.723227 -298.260006) (xy 14.684416 -298.184725) (xy 14.652937 -298.106095)
			(xy 14.629076 -298.024828) (xy 14.613047 -297.941662) (xy 14.604996 -297.857348) (xy 9.903131 -297.857348)
			(xy 9.902283 -297.859414) (xy 9.855873 -297.951347) (xy 9.802448 -298.039388) (xy 9.742333 -298.123005)
			(xy 9.675893 -298.201689) (xy 9.640062 -298.238672) (xy 9.632696 -298.245784) (xy 9.62533 -298.264072)
			(xy 9.62533 -298.35602) (xy 9.632696 -298.374308) (xy 9.640062 -298.38142) (xy 9.675897 -298.4184)
			(xy 9.742337 -298.497084) (xy 9.802451 -298.5807) (xy 9.855874 -298.668742) (xy 9.902282 -298.760676)
			(xy 9.941394 -298.855942) (xy 9.972972 -298.953964) (xy 9.996825 -299.054146) (xy 10.012807 -299.155881)
			(xy 10.020823 -299.258551) (xy 10.020823 -299.361534) (xy 10.012807 -299.464205) (xy 9.996824 -299.565939)
			(xy 9.972971 -299.666122) (xy 9.941392 -299.764143) (xy 9.90228 -299.85941) (xy 9.855871 -299.951343)
			(xy 9.816425 -300.016348) (xy 13.715996 -300.016348) (xy 13.715996 -299.931652) (xy 13.724047 -299.847338)
			(xy 13.740076 -299.764172) (xy 13.763937 -299.682905) (xy 13.795416 -299.604275) (xy 13.834227 -299.528994)
			(xy 13.880017 -299.457742) (xy 13.932373 -299.391166) (xy 13.990821 -299.329868) (xy 14.054831 -299.274403)
			(xy 14.123823 -299.225274) (xy 14.197173 -299.182925) (xy 14.274216 -299.147741) (xy 14.354255 -299.120039)
			(xy 14.436564 -299.100071) (xy 14.520399 -299.088018) (xy 14.605 -299.083988) (xy 14.689601 -299.088018)
			(xy 14.773436 -299.100071) (xy 14.855745 -299.120039) (xy 14.935784 -299.147741) (xy 15.012827 -299.182925)
			(xy 15.086177 -299.225274) (xy 15.155169 -299.274403) (xy 15.219179 -299.329868) (xy 15.277627 -299.391166)
			(xy 15.329983 -299.457742) (xy 15.362505 -299.508348) (xy 15.582896 -299.508348) (xy 15.582896 -299.423652)
			(xy 15.590947 -299.339338) (xy 15.606976 -299.256172) (xy 15.630837 -299.174905) (xy 15.662316 -299.096275)
			(xy 15.701127 -299.020994) (xy 15.746917 -298.949742) (xy 15.799273 -298.883166) (xy 15.857721 -298.821868)
			(xy 15.921731 -298.766403) (xy 15.990723 -298.717274) (xy 16.064073 -298.674925) (xy 16.141116 -298.639741)
			(xy 16.221155 -298.612039) (xy 16.303464 -298.592071) (xy 16.387299 -298.580018) (xy 16.4719 -298.575988)
			(xy 16.556501 -298.580018) (xy 16.640336 -298.592071) (xy 16.722645 -298.612039) (xy 16.802684 -298.639741)
			(xy 16.879727 -298.674925) (xy 16.953077 -298.717274) (xy 17.022069 -298.766403) (xy 17.086079 -298.821868)
			(xy 17.144527 -298.883166) (xy 17.196883 -298.949742) (xy 17.242673 -299.020994) (xy 17.281484 -299.096275)
			(xy 17.312963 -299.174905) (xy 17.336824 -299.256172) (xy 17.352853 -299.339338) (xy 17.354253 -299.354)
			(xy 17.985458 -299.354) (xy 17.989488 -299.269396) (xy 18.001542 -299.185558) (xy 18.021511 -299.103246)
			(xy 18.049214 -299.023204) (xy 18.084399 -298.946159) (xy 18.126749 -298.872806) (xy 18.17588 -298.803812)
			(xy 18.231347 -298.7398) (xy 18.292647 -298.68135) (xy 18.359226 -298.628992) (xy 18.43048 -298.5832)
			(xy 18.505765 -298.544389) (xy 18.584397 -298.512909) (xy 18.665666 -298.489046) (xy 18.748836 -298.473017)
			(xy 18.833152 -298.464966) (xy 18.875502 -298.464478) (xy 18.915684 -298.4649) (xy 18.995722 -298.472138)
			(xy 19.074779 -298.486575) (xy 19.15221 -298.508091) (xy 19.189954 -298.521882) (xy 19.199124 -298.524979)
			(xy 19.21846 -298.524711) (xy 19.227546 -298.521374) (xy 19.274282 -298.50207) (xy 19.275806 -298.498768)
			(xy 19.279749 -298.488181) (xy 19.278942 -298.465628) (xy 19.274282 -298.455334) (xy 19.255534 -298.417634)
			(xy 19.224394 -298.339401) (xy 19.200793 -298.258574) (xy 19.184942 -298.175877) (xy 19.176983 -298.092051)
			(xy 19.176492 -298.04995) (xy 19.176996 -298.007602) (xy 19.185047 -297.923288) (xy 19.201076 -297.840122)
			(xy 19.224937 -297.758855) (xy 19.256416 -297.680225) (xy 19.295227 -297.604944) (xy 19.341017 -297.533692)
			(xy 19.393373 -297.467116) (xy 19.451821 -297.405818) (xy 19.515831 -297.350353) (xy 19.584823 -297.301224)
			(xy 19.658173 -297.258875) (xy 19.735216 -297.223691) (xy 19.815255 -297.195989) (xy 19.897564 -297.176021)
			(xy 19.981399 -297.163968) (xy 20.066 -297.159938) (xy 20.150601 -297.163968) (xy 20.234436 -297.176021)
			(xy 20.316745 -297.195989) (xy 20.396784 -297.223691) (xy 20.473827 -297.258875) (xy 20.547177 -297.301224)
			(xy 20.616169 -297.350353) (xy 20.680179 -297.405818) (xy 20.738627 -297.467116) (xy 20.790983 -297.533692)
			(xy 20.836773 -297.604944) (xy 20.875584 -297.680225) (xy 20.907063 -297.758855) (xy 20.930924 -297.840122)
			(xy 20.946953 -297.923288) (xy 20.955004 -298.007602) (xy 20.955508 -298.04995) (xy 20.954963 -298.095104)
			(xy 20.945792 -298.184944) (xy 20.927561 -298.273392) (xy 20.900456 -298.359536) (xy 20.883118 -298.401232)
			(xy 20.879173 -298.411819) (xy 20.879981 -298.434372) (xy 20.884642 -298.444666) (xy 20.908518 -298.495212)
			(xy 20.912848 -298.504112) (xy 20.927016 -298.517909) (xy 20.945363 -298.525291) (xy 20.955254 -298.525692)
			(xy 20.98167 -298.525692) (xy 20.99154 -298.525188) (xy 21.009842 -298.5178) (xy 21.024012 -298.50406)
			(xy 21.028406 -298.495212) (xy 21.046013 -298.455959) (xy 21.08778 -298.380742) (xy 21.136616 -298.309909)
			(xy 21.192064 -298.244124) (xy 21.253607 -298.184002) (xy 21.320668 -298.130104) (xy 21.392621 -298.082936)
			(xy 21.468794 -298.042937) (xy 21.548473 -298.010481) (xy 21.630915 -297.985873) (xy 21.715347 -297.969341)
			(xy 21.800982 -297.961042) (xy 21.844 -297.960542) (xy 21.888044 -297.961061) (xy 21.975703 -297.969735)
			(xy 22.062075 -297.987038) (xy 22.10435 -297.999404) (xy 22.115018 -298.002706) (xy 22.136608 -297.999912)
			(xy 22.220936 -297.946826) (xy 22.23262 -297.928538) (xy 22.234398 -297.917362) (xy 22.241159 -297.875758)
			(xy 22.261557 -297.793968) (xy 22.289601 -297.714475) (xy 22.325039 -297.637991) (xy 22.367553 -297.565203)
			(xy 22.416763 -297.496763) (xy 22.472226 -297.433285) (xy 22.533446 -297.375339) (xy 22.599872 -297.323444)
			(xy 22.670911 -297.278065) (xy 22.745923 -297.239611) (xy 22.824237 -297.208425) (xy 22.90515 -297.184787)
			(xy 22.987936 -297.16891) (xy 23.071853 -297.160936) (xy 23.114 -297.160442) (xy 23.156077 -297.16092)
			(xy 23.239855 -297.168869) (xy 23.322508 -297.184695) (xy 23.403297 -297.208257) (xy 23.481499 -297.239345)
			(xy 23.556415 -297.27768) (xy 23.627375 -297.322919) (xy 23.660862 -297.348402) (xy 23.668247 -297.35369)
			(xy 23.685556 -297.359157) (xy 23.703686 -297.35825) (xy 23.71217 -297.355006) (xy 23.753665 -297.337916)
			(xy 23.839331 -297.311168) (xy 23.927257 -297.293195) (xy 24.016547 -297.284178) (xy 24.06142 -297.283632)
			(xy 24.103768 -297.284136) (xy 24.188082 -297.292187) (xy 24.271248 -297.308216) (xy 24.352515 -297.332077)
			(xy 24.431145 -297.363556) (xy 24.506426 -297.402367) (xy 24.577678 -297.448157) (xy 24.644254 -297.500513)
			(xy 24.705552 -297.558961) (xy 24.707319 -297.561) (xy 40.765988 -297.561) (xy 40.770018 -297.476399)
			(xy 40.782071 -297.392564) (xy 40.802039 -297.310255) (xy 40.829741 -297.230216) (xy 40.864925 -297.153173)
			(xy 40.907274 -297.079823) (xy 40.956403 -297.010831) (xy 41.011868 -296.946821) (xy 41.073166 -296.888373)
			(xy 41.139742 -296.836017) (xy 41.210994 -296.790227) (xy 41.286275 -296.751416) (xy 41.364905 -296.719937)
			(xy 41.446172 -296.696076) (xy 41.529338 -296.680047) (xy 41.613652 -296.671996) (xy 41.656 -296.671492)
			(xy 41.691782 -296.671816) (xy 41.763117 -296.677542) (xy 41.798494 -296.682922) (xy 41.808785 -296.684071)
			(xy 41.828856 -296.679073) (xy 41.845312 -296.666544) (xy 41.850818 -296.657776) (xy 41.879946 -296.6077)
			(xy 41.945733 -296.512334) (xy 42.019605 -296.423084) (xy 42.05986 -296.381424) (xy 42.067226 -296.374312)
			(xy 42.074592 -296.356024) (xy 42.074592 -296.264076) (xy 42.067226 -296.245788) (xy 42.05986 -296.238676)
			(xy 42.024031 -296.201691) (xy 41.957591 -296.123007) (xy 41.897477 -296.039391) (xy 41.844054 -295.951349)
			(xy 41.797645 -295.859417) (xy 41.758533 -295.764151) (xy 41.726955 -295.666129) (xy 41.703102 -295.565947)
			(xy 41.687119 -295.464213) (xy 41.679103 -295.361543) (xy 41.679103 -295.25856) (xy 41.687118 -295.15589)
			(xy 41.703101 -295.054155) (xy 41.726954 -294.953974) (xy 41.758532 -294.855952) (xy 41.797644 -294.760686)
			(xy 41.844052 -294.668753) (xy 41.897476 -294.580711) (xy 41.95759 -294.497095) (xy 42.024029 -294.418411)
			(xy 42.05986 -294.381428) (xy 42.067226 -294.374316) (xy 42.074592 -294.356028) (xy 42.074592 -294.26408)
			(xy 42.067226 -294.245792) (xy 42.05986 -294.23868) (xy 42.024025 -294.201701) (xy 41.957585 -294.123017)
			(xy 41.897471 -294.0394) (xy 41.844048 -293.951358) (xy 41.797639 -293.859425) (xy 41.758528 -293.764158)
			(xy 41.726949 -293.666136) (xy 41.703097 -293.565954) (xy 41.687114 -293.464219) (xy 41.679098 -293.361549)
			(xy 41.679099 -293.258566) (xy 41.687115 -293.155895) (xy 41.703098 -293.05416) (xy 41.726951 -292.953978)
			(xy 41.758529 -292.855957) (xy 41.797642 -292.76069) (xy 41.844051 -292.668757) (xy 41.897474 -292.580715)
			(xy 41.957589 -292.497099) (xy 42.024029 -292.418415) (xy 42.05986 -292.381432) (xy 42.067226 -292.37432)
			(xy 42.074592 -292.356032) (xy 42.074592 -292.264084) (xy 42.067226 -292.245796) (xy 42.05986 -292.238684)
			(xy 42.024029 -292.201701) (xy 41.957589 -292.123017) (xy 41.897475 -292.039401) (xy 41.844052 -291.951359)
			(xy 41.797643 -291.859426) (xy 41.758531 -291.76416) (xy 41.726953 -291.666138) (xy 41.7031 -291.565956)
			(xy 41.687117 -291.464221) (xy 41.679101 -291.361551) (xy 41.679101 -291.258569) (xy 41.687117 -291.155899)
			(xy 41.7031 -291.054164) (xy 41.726953 -290.953982) (xy 41.758531 -290.85596) (xy 41.797643 -290.760694)
			(xy 41.844052 -290.668761) (xy 41.897475 -290.580719) (xy 41.957589 -290.497103) (xy 42.024029 -290.418419)
			(xy 42.05986 -290.381436) (xy 42.067226 -290.374324) (xy 42.074592 -290.356036) (xy 42.074592 -290.264088)
			(xy 42.067226 -290.2458) (xy 42.05986 -290.238688) (xy 42.024004 -290.201728) (xy 41.957566 -290.123041)
			(xy 41.897454 -290.039422) (xy 41.844033 -289.951377) (xy 41.797626 -289.859441) (xy 41.758517 -289.764173)
			(xy 41.726941 -289.666149) (xy 41.703091 -289.565964) (xy 41.687111 -289.464228) (xy 41.679098 -289.361556)
			(xy 41.678606 -289.310064) (xy 41.679067 -289.258169) (xy 41.687213 -289.154699) (xy 41.703452 -289.052187)
			(xy 41.727684 -288.951265) (xy 41.759759 -288.852555) (xy 41.79948 -288.756666) (xy 41.846602 -288.664189)
			(xy 41.900834 -288.575694) (xy 41.961843 -288.491728) (xy 42.029251 -288.412806) (xy 42.102643 -288.339417)
			(xy 42.181567 -288.272012) (xy 42.265536 -288.211007) (xy 42.354033 -288.156778) (xy 42.446511 -288.109659)
			(xy 42.542402 -288.069942) (xy 42.641113 -288.03787) (xy 42.742036 -288.013642) (xy 42.844548 -287.997407)
			(xy 42.948019 -287.989265) (xy 42.999914 -287.988756) (xy 43.051406 -287.989236) (xy 43.154076 -287.997253)
			(xy 43.255812 -288.013237) (xy 43.355994 -288.037092) (xy 43.454016 -288.068672) (xy 43.549282 -288.107785)
			(xy 43.641215 -288.154196) (xy 43.729256 -288.207621) (xy 43.812872 -288.267737) (xy 43.891555 -288.334178)
			(xy 43.928538 -288.37001) (xy 43.93565 -288.377376) (xy 43.953938 -288.384742) (xy 44.045886 -288.384742)
			(xy 44.064174 -288.377376) (xy 44.071286 -288.37001) (xy 44.108267 -288.334177) (xy 44.18695 -288.267736)
			(xy 44.270567 -288.207621) (xy 44.358609 -288.154198) (xy 44.450542 -288.107789) (xy 44.545809 -288.068677)
			(xy 44.64383 -288.037099) (xy 44.744013 -288.013246) (xy 44.845748 -287.997264) (xy 44.948419 -287.989249)
			(xy 44.99991 -287.988756) (xy 45.051804 -287.989292) (xy 45.155271 -287.997436) (xy 45.25778 -288.013672)
			(xy 45.358699 -288.037901) (xy 45.457407 -288.069973) (xy 45.553294 -288.10969) (xy 45.645769 -288.156808)
			(xy 45.734262 -288.211037) (xy 45.818228 -288.272041) (xy 45.897149 -288.339444) (xy 45.970538 -288.412832)
			(xy 46.037943 -288.491752) (xy 46.098949 -288.575716) (xy 46.153179 -288.664209) (xy 46.200299 -288.756683)
			(xy 46.240018 -288.852569) (xy 46.272092 -288.951276) (xy 46.296323 -289.052195) (xy 46.312561 -289.154703)
			(xy 46.320707 -289.25817) (xy 46.321218 -289.310064) (xy 46.320683 -289.361554) (xy 46.312671 -289.464223)
			(xy 46.296691 -289.565957) (xy 46.272842 -289.666138) (xy 46.241268 -289.764159) (xy 46.20216 -289.859425)
			(xy 46.155756 -289.951358) (xy 46.102337 -290.039401) (xy 46.042228 -290.123018) (xy 45.975792 -290.201704)
			(xy 45.939964 -290.238688) (xy 45.932598 -290.2458) (xy 45.925232 -290.264088) (xy 45.925232 -290.356036)
			(xy 45.932598 -290.374324) (xy 45.939964 -290.381436) (xy 45.975795 -290.418419) (xy 46.042234 -290.497103)
			(xy 46.102348 -290.58072) (xy 46.155772 -290.668761) (xy 46.20218 -290.760694) (xy 46.241292 -290.85596)
			(xy 46.27287 -290.953982) (xy 46.296723 -291.054164) (xy 46.312706 -291.155899) (xy 46.320721 -291.258569)
			(xy 46.320721 -291.361551) (xy 46.312706 -291.464221) (xy 46.296723 -291.565956) (xy 46.27287 -291.666138)
			(xy 46.241292 -291.76416) (xy 46.20218 -291.859426) (xy 46.155772 -291.951359) (xy 46.102348 -292.0394)
			(xy 46.042234 -292.123017) (xy 45.975795 -292.201701) (xy 45.939964 -292.238684) (xy 45.932598 -292.245796)
			(xy 45.925232 -292.264084) (xy 45.925232 -292.356032) (xy 45.932598 -292.37432) (xy 45.939964 -292.381432)
			(xy 45.975791 -292.418419) (xy 46.04223 -292.497103) (xy 46.102344 -292.580719) (xy 46.155768 -292.66876)
			(xy 46.202176 -292.760693) (xy 46.241288 -292.855959) (xy 46.272867 -292.95398) (xy 46.29672 -293.054162)
			(xy 46.312703 -293.155896) (xy 46.320719 -293.258566) (xy 46.320719 -293.361548) (xy 46.312703 -293.464218)
			(xy 46.296721 -293.565953) (xy 46.272868 -293.666135) (xy 46.24129 -293.764156) (xy 46.202179 -293.859422)
			(xy 46.155771 -293.951355) (xy 46.102348 -294.039397) (xy 46.042234 -294.123013) (xy 45.975794 -294.201697)
			(xy 45.939964 -294.23868) (xy 45.932598 -294.245792) (xy 45.925232 -294.26408) (xy 45.925232 -294.356028)
			(xy 45.932598 -294.374316) (xy 45.939964 -294.381428) (xy 45.975797 -294.418409) (xy 46.042236 -294.497093)
			(xy 46.10235 -294.58071) (xy 46.155774 -294.668752) (xy 46.202182 -294.760685) (xy 46.241294 -294.855951)
			(xy 46.272872 -294.953973) (xy 46.296725 -295.054155) (xy 46.312707 -295.15589) (xy 46.320723 -295.25856)
			(xy 46.320723 -295.361543) (xy 46.312707 -295.464213) (xy 46.296724 -295.565948) (xy 46.272871 -295.66613)
			(xy 46.241293 -295.764151) (xy 46.202181 -295.859418) (xy 46.155772 -295.951351) (xy 46.102349 -296.039392)
			(xy 46.042235 -296.123009) (xy 45.975795 -296.201693) (xy 45.939964 -296.238676) (xy 45.932598 -296.245788)
			(xy 45.925232 -296.264076) (xy 45.925232 -296.356024) (xy 45.932598 -296.374312) (xy 45.939964 -296.381424)
			(xy 45.975793 -296.418409) (xy 46.042232 -296.497093) (xy 46.102346 -296.580709) (xy 46.15577 -296.668751)
			(xy 46.202178 -296.760684) (xy 46.24129 -296.85595) (xy 46.272868 -296.953971) (xy 46.296721 -297.054153)
			(xy 46.312704 -297.155887) (xy 46.32072 -297.258557) (xy 46.32072 -297.36154) (xy 46.312705 -297.46421)
			(xy 46.296722 -297.565944) (xy 46.272869 -297.666126) (xy 46.241291 -297.764148) (xy 46.202179 -297.859414)
			(xy 46.155771 -297.951347) (xy 46.102348 -298.039388) (xy 46.042234 -298.123005) (xy 45.975794 -298.201689)
			(xy 45.939964 -298.238672) (xy 45.932598 -298.245784) (xy 45.925232 -298.264072) (xy 45.925232 -298.35602)
			(xy 45.932598 -298.374308) (xy 45.939964 -298.38142) (xy 45.975799 -298.4184) (xy 46.042238 -298.497084)
			(xy 46.102352 -298.5807) (xy 46.155775 -298.668742) (xy 46.202184 -298.760676) (xy 46.241296 -298.855942)
			(xy 46.272874 -298.953964) (xy 46.296726 -299.054146) (xy 46.312709 -299.155881) (xy 46.320724 -299.258551)
			(xy 46.320724 -299.361534) (xy 46.312708 -299.464204) (xy 46.296725 -299.565939) (xy 46.272872 -299.666122)
			(xy 46.241294 -299.764143) (xy 46.202181 -299.85941) (xy 46.155773 -299.951343) (xy 46.102349 -300.039384)
			(xy 46.042235 -300.123001) (xy 45.975795 -300.201685) (xy 45.939964 -300.238668) (xy 45.932598 -300.24578)
			(xy 45.925232 -300.264068) (xy 45.925232 -300.356016) (xy 45.932598 -300.374304) (xy 45.939964 -300.381416)
			(xy 45.975795 -300.418399) (xy 46.042234 -300.497083) (xy 46.102348 -300.5807) (xy 46.155772 -300.668741)
			(xy 46.20218 -300.760674) (xy 46.241292 -300.85594) (xy 46.27287 -300.953962) (xy 46.296723 -301.054144)
			(xy 46.312706 -301.155879) (xy 46.320721 -301.258549) (xy 46.320721 -301.361531) (xy 46.312706 -301.464201)
			(xy 46.296723 -301.565936) (xy 46.27287 -301.666118) (xy 46.241292 -301.76414) (xy 46.20218 -301.859406)
			(xy 46.155772 -301.951339) (xy 46.102348 -302.03938) (xy 46.042234 -302.122997) (xy 45.975795 -302.201681)
			(xy 45.939964 -302.238664) (xy 45.932598 -302.245776) (xy 45.925232 -302.264064) (xy 45.925232 -302.356012)
			(xy 45.932598 -302.3743) (xy 45.939964 -302.381412) (xy 45.975805 -302.418385) (xy 46.042246 -302.49707)
			(xy 46.102361 -302.580687) (xy 46.155784 -302.66873) (xy 46.202192 -302.760664) (xy 46.241304 -302.855931)
			(xy 46.272881 -302.953954) (xy 46.296732 -303.054137) (xy 46.312713 -303.155873) (xy 46.320726 -303.258544)
			(xy 46.321218 -303.310036) (xy 46.320694 -303.360854) (xy 46.31289 -303.462191) (xy 46.297322 -303.562628)
			(xy 46.274082 -303.661573) (xy 46.243309 -303.758439) (xy 46.205184 -303.852654) (xy 46.159932 -303.943661)
			(xy 46.107821 -304.030922) (xy 46.04916 -304.113921) (xy 45.984294 -304.192167) (xy 45.913608 -304.265198)
			(xy 45.837519 -304.332581) (xy 45.756478 -304.393919) (xy 45.670963 -304.448849) (xy 45.581481 -304.497045)
			(xy 45.488559 -304.538223) (xy 45.392749 -304.57214) (xy 45.294615 -304.598594) (xy 45.244766 -304.608484)
			(xy 45.233336 -304.610516) (xy 45.215048 -304.623724) (xy 45.16628 -304.712624) (xy 45.164756 -304.73523)
			(xy 45.169074 -304.745898) (xy 45.187081 -304.792579) (xy 45.21649 -304.888222) (xy 45.238206 -304.985899)
			(xy 45.252093 -305.084993) (xy 45.258064 -305.184877) (xy 45.256079 -305.28492) (xy 45.246151 -305.384488)
			(xy 45.228345 -305.482953) (xy 45.202771 -305.579692) (xy 45.169592 -305.674094) (xy 45.129017 -305.76556)
			(xy 45.081303 -305.853514) (xy 45.026752 -305.937399) (xy 44.965709 -306.016684) (xy 44.898559 -306.090869)
			(xy 44.825728 -306.159484) (xy 44.747674 -306.222095) (xy 44.664894 -306.278307) (xy 44.577908 -306.327764)
			(xy 44.487268 -306.370153) (xy 44.393547 -306.405207) (xy 44.297337 -306.432704) (xy 44.199246 -306.45247)
			(xy 44.099895 -306.464379) (xy 43.999912 -306.468357) (xy 43.899929 -306.464379) (xy 43.800578 -306.45247)
			(xy 43.702487 -306.432704) (xy 43.606277 -306.405207) (xy 43.512556 -306.370153) (xy 43.421916 -306.327764)
			(xy 43.33493 -306.278307) (xy 43.25215 -306.222095) (xy 43.174096 -306.159484) (xy 43.101265 -306.090869)
			(xy 43.034115 -306.016684) (xy 42.973072 -305.937399) (xy 42.918521 -305.853514) (xy 42.870807 -305.76556)
			(xy 42.830232 -305.674094) (xy 42.797053 -305.579692) (xy 42.771479 -305.482953) (xy 42.753673 -305.384488)
			(xy 42.743745 -305.28492) (xy 42.74176 -305.184877) (xy 42.747731 -305.084993) (xy 42.761618 -304.985899)
			(xy 42.783334 -304.888222) (xy 42.812743 -304.792579) (xy 42.83075 -304.745898) (xy 42.835068 -304.73523)
			(xy 42.833544 -304.712624) (xy 42.784776 -304.623724) (xy 42.766488 -304.610516) (xy 42.755058 -304.608484)
			(xy 42.705207 -304.598601) (xy 42.607074 -304.572143) (xy 42.511264 -304.538223) (xy 42.418343 -304.497043)
			(xy 42.32886 -304.448845) (xy 42.243345 -304.393914) (xy 42.162304 -304.332576) (xy 42.086214 -304.265192)
			(xy 42.015527 -304.192161) (xy 41.95066 -304.113916) (xy 41.891996 -304.030918) (xy 41.839882 -303.943657)
			(xy 41.794626 -303.852651) (xy 41.756497 -303.758437) (xy 41.725719 -303.661572) (xy 41.702474 -303.562628)
			(xy 41.686899 -303.462191) (xy 41.679088 -303.360855) (xy 41.678606 -303.310036) (xy 41.679134 -303.258545)
			(xy 41.687147 -303.155876) (xy 41.703126 -303.054143) (xy 41.726976 -302.953961) (xy 41.758551 -302.85594)
			(xy 41.797659 -302.760674) (xy 41.844064 -302.668741) (xy 41.897484 -302.580698) (xy 41.957595 -302.497081)
			(xy 42.024031 -302.418396) (xy 42.05986 -302.381412) (xy 42.067226 -302.3743) (xy 42.074592 -302.356012)
			(xy 42.074592 -302.264064) (xy 42.067226 -302.245776) (xy 42.05986 -302.238664) (xy 42.024029 -302.201681)
			(xy 41.957589 -302.122997) (xy 41.897475 -302.039381) (xy 41.844052 -301.951339) (xy 41.797643 -301.859406)
			(xy 41.758531 -301.76414) (xy 41.726953 -301.666118) (xy 41.7031 -301.565936) (xy 41.687117 -301.464201)
			(xy 41.679101 -301.361531) (xy 41.679101 -301.258549) (xy 41.687117 -301.155879) (xy 41.7031 -301.054144)
			(xy 41.726953 -300.953962) (xy 41.758531 -300.85594) (xy 41.797643 -300.760674) (xy 41.844052 -300.668741)
			(xy 41.897475 -300.580699) (xy 41.957589 -300.497083) (xy 42.024029 -300.418399) (xy 42.05986 -300.381416)
			(xy 42.067226 -300.374304) (xy 42.074592 -300.356016) (xy 42.074592 -300.264068) (xy 42.067226 -300.24578)
			(xy 42.05986 -300.238668) (xy 42.024044 -300.201671) (xy 41.957603 -300.122989) (xy 41.897489 -300.039374)
			(xy 41.844064 -299.951334) (xy 41.797654 -299.859403) (xy 41.758541 -299.764138) (xy 41.72696 -299.666118)
			(xy 41.703105 -299.565937) (xy 41.68712 -299.464204) (xy 41.679101 -299.361535) (xy 41.678606 -299.310044)
			(xy 41.679135 -299.256156) (xy 41.687914 -299.148739) (xy 41.705417 -299.042395) (xy 41.731528 -298.93783)
			(xy 41.766073 -298.835741) (xy 41.808823 -298.736807) (xy 41.859492 -298.641685) (xy 41.888156 -298.59605)
			(xy 41.896284 -298.583604) (xy 41.89603 -298.553632) (xy 41.829736 -298.450762) (xy 41.802304 -298.43857)
			(xy 41.787572 -298.440602) (xy 41.754875 -298.44522) (xy 41.68902 -298.450179) (xy 41.656 -298.450508)
			(xy 41.613652 -298.450004) (xy 41.529338 -298.441953) (xy 41.446172 -298.425924) (xy 41.364905 -298.402063)
			(xy 41.286275 -298.370584) (xy 41.210994 -298.331773) (xy 41.139742 -298.285983) (xy 41.073166 -298.233627)
			(xy 41.011868 -298.175179) (xy 40.956403 -298.111169) (xy 40.907274 -298.042177) (xy 40.864925 -297.968827)
			(xy 40.829741 -297.891784) (xy 40.802039 -297.811745) (xy 40.782071 -297.729436) (xy 40.770018 -297.645601)
			(xy 40.765988 -297.561) (xy 24.707319 -297.561) (xy 24.761017 -297.622971) (xy 24.810146 -297.691963)
			(xy 24.852495 -297.765313) (xy 24.887679 -297.842356) (xy 24.915381 -297.922395) (xy 24.935349 -298.004704)
			(xy 24.947402 -298.088539) (xy 24.951433 -298.17314) (xy 24.947402 -298.257741) (xy 24.935349 -298.341576)
			(xy 24.915381 -298.423885) (xy 24.887679 -298.503924) (xy 24.852495 -298.580967) (xy 24.810146 -298.654317)
			(xy 24.761017 -298.723309) (xy 24.705552 -298.787319) (xy 24.644254 -298.845767) (xy 24.577678 -298.898123)
			(xy 24.506426 -298.943913) (xy 24.431145 -298.982724) (xy 24.352515 -299.014203) (xy 24.271248 -299.038064)
			(xy 24.188082 -299.054093) (xy 24.103768 -299.062144) (xy 24.06142 -299.062648) (xy 24.019343 -299.06216)
			(xy 23.935565 -299.054214) (xy 23.852912 -299.038389) (xy 23.772124 -299.014828) (xy 23.693922 -298.983742)
			(xy 23.619005 -298.945409) (xy 23.548045 -298.90017) (xy 23.514558 -298.874688) (xy 23.507164 -298.869414)
			(xy 23.48986 -298.863944) (xy 23.471734 -298.864844) (xy 23.46325 -298.868084) (xy 23.421765 -298.885199)
			(xy 23.336096 -298.91194) (xy 23.248166 -298.929907) (xy 23.158873 -298.938916) (xy 23.114 -298.939458)
			(xy 23.069956 -298.938939) (xy 22.982297 -298.930265) (xy 22.895925 -298.912962) (xy 22.85365 -298.900596)
			(xy 22.842982 -298.897294) (xy 22.821392 -298.900088) (xy 22.737064 -298.953174) (xy 22.72538 -298.971462)
			(xy 22.723602 -298.982638) (xy 22.716841 -299.024242) (xy 22.696443 -299.106032) (xy 22.668399 -299.185525)
			(xy 22.632961 -299.262009) (xy 22.590447 -299.334797) (xy 22.541237 -299.403237) (xy 22.485774 -299.466715)
			(xy 22.424554 -299.524661) (xy 22.358128 -299.576556) (xy 22.287089 -299.621935) (xy 22.212077 -299.660389)
			(xy 22.133763 -299.691575) (xy 22.05285 -299.715213) (xy 21.970064 -299.73109) (xy 21.886147 -299.739064)
			(xy 21.844 -299.739558) (xy 21.800195 -299.739008) (xy 21.713007 -299.730412) (xy 21.627088 -299.713285)
			(xy 21.543269 -299.687793) (xy 21.462363 -299.654181) (xy 21.385154 -299.612777) (xy 21.31239 -299.563982)
			(xy 21.244778 -299.508268) (xy 21.182971 -299.446175) (xy 21.12757 -299.378306) (xy 21.079112 -299.305318)
			(xy 21.058124 -299.266864) (xy 21.05347 -299.258953) (xy 21.039738 -299.246805) (xy 21.022588 -299.240323)
			(xy 21.01342 -299.23994) (xy 20.923504 -299.23994) (xy 20.914347 -299.240368) (xy 20.897224 -299.246879)
			(xy 20.883463 -299.258971) (xy 20.8788 -299.266864) (xy 20.857846 -299.305335) (xy 20.80937 -299.378312)
			(xy 20.753957 -299.446171) (xy 20.692142 -299.508255) (xy 20.624525 -299.563963) (xy 20.55176 -299.612756)
			(xy 20.474552 -299.654161) (xy 20.393648 -299.687777) (xy 20.309831 -299.713279) (xy 20.223914 -299.730419)
			(xy 20.136729 -299.739032) (xy 20.092924 -299.739558) (xy 20.052742 -299.739126) (xy 19.972704 -299.73189)
			(xy 19.893647 -299.717456) (xy 19.816216 -299.695944) (xy 19.778472 -299.682154) (xy 19.769299 -299.67907)
			(xy 19.749965 -299.679329) (xy 19.74088 -299.682662) (xy 19.71294 -299.694346) (xy 19.70421 -299.698368)
			(xy 19.690372 -299.711686) (xy 19.686016 -299.720254) (xy 19.668048 -299.758765) (xy 19.625827 -299.832523)
			(xy 19.576764 -299.901918) (xy 19.521305 -299.966317) (xy 19.513291 -299.974) (xy 30.352492 -299.974)
			(xy 30.352966 -299.93121) (xy 30.361176 -299.846025) (xy 30.37753 -299.762022) (xy 30.401878 -299.679979)
			(xy 30.433993 -299.600653) (xy 30.473579 -299.524779) (xy 30.52027 -299.453058) (xy 30.573633 -299.386153)
			(xy 30.633176 -299.324683) (xy 30.698348 -299.269217) (xy 30.768547 -299.220266) (xy 30.843122 -299.178285)
			(xy 30.921385 -299.143661) (xy 30.961838 -299.129704) (xy 30.971744 -299.126402) (xy 30.98673 -299.113194)
			(xy 31.027878 -299.028866) (xy 31.028894 -299.0088) (xy 31.025338 -298.998894) (xy 31.012586 -298.962468)
			(xy 30.992719 -298.887885) (xy 30.979382 -298.811863) (xy 30.972676 -298.734972) (xy 30.972252 -298.69638)
			(xy 30.972756 -298.654032) (xy 30.980807 -298.569718) (xy 30.996836 -298.486552) (xy 31.020697 -298.405285)
			(xy 31.052176 -298.326655) (xy 31.090987 -298.251374) (xy 31.136777 -298.180122) (xy 31.189133 -298.113546)
			(xy 31.247581 -298.052248) (xy 31.311591 -297.996783) (xy 31.380583 -297.947654) (xy 31.453933 -297.905305)
			(xy 31.530976 -297.870121) (xy 31.611015 -297.842419) (xy 31.693324 -297.822451) (xy 31.777159 -297.810398)
			(xy 31.86176 -297.806368) (xy 31.946361 -297.810398) (xy 32.030196 -297.822451) (xy 32.112505 -297.842419)
			(xy 32.192544 -297.870121) (xy 32.269587 -297.905305) (xy 32.342937 -297.947654) (xy 32.411929 -297.996783)
			(xy 32.475939 -298.052248) (xy 32.534387 -298.113546) (xy 32.586743 -298.180122) (xy 32.632533 -298.251374)
			(xy 32.671344 -298.326655) (xy 32.702823 -298.405285) (xy 32.726684 -298.486552) (xy 32.742713 -298.569718)
			(xy 32.750764 -298.654032) (xy 32.751268 -298.69638) (xy 32.750804 -298.739171) (xy 32.750112 -298.746348)
			(xy 35.305996 -298.746348) (xy 35.305996 -298.661652) (xy 35.314047 -298.577338) (xy 35.330076 -298.494172)
			(xy 35.353937 -298.412905) (xy 35.385416 -298.334275) (xy 35.424227 -298.258994) (xy 35.470017 -298.187742)
			(xy 35.522373 -298.121166) (xy 35.580821 -298.059868) (xy 35.644831 -298.004403) (xy 35.713823 -297.955274)
			(xy 35.787173 -297.912925) (xy 35.864216 -297.877741) (xy 35.944255 -297.850039) (xy 36.026564 -297.830071)
			(xy 36.110399 -297.818018) (xy 36.195 -297.813988) (xy 36.279601 -297.818018) (xy 36.363436 -297.830071)
			(xy 36.445745 -297.850039) (xy 36.525784 -297.877741) (xy 36.602827 -297.912925) (xy 36.676177 -297.955274)
			(xy 36.745169 -298.004403) (xy 36.809179 -298.059868) (xy 36.867627 -298.121166) (xy 36.919983 -298.187742)
			(xy 36.965773 -298.258994) (xy 37.004584 -298.334275) (xy 37.036063 -298.412905) (xy 37.059924 -298.494172)
			(xy 37.075953 -298.577338) (xy 37.084004 -298.661652) (xy 37.084508 -298.704) (xy 37.084004 -298.746348)
			(xy 37.075953 -298.830662) (xy 37.059924 -298.913828) (xy 37.036063 -298.995095) (xy 37.004584 -299.073725)
			(xy 36.965773 -299.149006) (xy 36.919983 -299.220258) (xy 36.867627 -299.286834) (xy 36.809179 -299.348132)
			(xy 36.745169 -299.403597) (xy 36.676177 -299.452726) (xy 36.602827 -299.495075) (xy 36.525784 -299.530259)
			(xy 36.445745 -299.557961) (xy 36.363436 -299.577929) (xy 36.279601 -299.589982) (xy 36.195 -299.594013)
			(xy 36.110399 -299.589982) (xy 36.026564 -299.577929) (xy 35.944255 -299.557961) (xy 35.864216 -299.530259)
			(xy 35.787173 -299.495075) (xy 35.713823 -299.452726) (xy 35.644831 -299.403597) (xy 35.580821 -299.348132)
			(xy 35.522373 -299.286834) (xy 35.470017 -299.220258) (xy 35.424227 -299.149006) (xy 35.385416 -299.073725)
			(xy 35.353937 -298.995095) (xy 35.330076 -298.913828) (xy 35.314047 -298.830662) (xy 35.305996 -298.746348)
			(xy 32.750112 -298.746348) (xy 32.742595 -298.824357) (xy 32.726241 -298.908361) (xy 32.701894 -298.990405)
			(xy 32.669779 -299.069732) (xy 32.630193 -299.145607) (xy 32.583501 -299.217328) (xy 32.530137 -299.284233)
			(xy 32.470592 -299.345703) (xy 32.405418 -299.401169) (xy 32.335218 -299.450118) (xy 32.260641 -299.492098)
			(xy 32.182376 -299.52672) (xy 32.141922 -299.540676) (xy 32.132016 -299.543978) (xy 32.11703 -299.557186)
			(xy 32.075882 -299.641514) (xy 32.074866 -299.66158) (xy 32.078422 -299.671486) (xy 32.09117 -299.707913)
			(xy 32.111038 -299.782495) (xy 32.124376 -299.858517) (xy 32.131083 -299.935409) (xy 32.131508 -299.974)
			(xy 32.131049 -300.014999) (xy 32.123501 -300.096648) (xy 32.108468 -300.177255) (xy 32.097726 -300.216824)
			(xy 32.094678 -300.227746) (xy 32.098234 -300.24959) (xy 32.154876 -300.333156) (xy 32.173672 -300.344332)
			(xy 32.185102 -300.345602) (xy 32.228419 -300.350497) (xy 32.313879 -300.367724) (xy 32.397244 -300.393229)
			(xy 32.477714 -300.426768) (xy 32.554516 -300.468019) (xy 32.626913 -300.516587) (xy 32.694212 -300.572004)
			(xy 32.755765 -300.63374) (xy 32.770177 -300.651348) (xy 35.305996 -300.651348) (xy 35.305996 -300.566652)
			(xy 35.314047 -300.482338) (xy 35.330076 -300.399172) (xy 35.353937 -300.317905) (xy 35.385416 -300.239275)
			(xy 35.424227 -300.163994) (xy 35.470017 -300.092742) (xy 35.522373 -300.026166) (xy 35.580821 -299.964868)
			(xy 35.644831 -299.909403) (xy 35.713823 -299.860274) (xy 35.787173 -299.817925) (xy 35.864216 -299.782741)
			(xy 35.944255 -299.755039) (xy 36.026564 -299.735071) (xy 36.110399 -299.723018) (xy 36.195 -299.718988)
			(xy 36.279601 -299.723018) (xy 36.363436 -299.735071) (xy 36.445745 -299.755039) (xy 36.525784 -299.782741)
			(xy 36.602827 -299.817925) (xy 36.676177 -299.860274) (xy 36.745169 -299.909403) (xy 36.809179 -299.964868)
			(xy 36.867627 -300.026166) (xy 36.919983 -300.092742) (xy 36.965773 -300.163994) (xy 37.004584 -300.239275)
			(xy 37.036063 -300.317905) (xy 37.059924 -300.399172) (xy 37.075953 -300.482338) (xy 37.084004 -300.566652)
			(xy 37.084508 -300.609) (xy 37.084004 -300.651348) (xy 37.075953 -300.735662) (xy 37.059924 -300.818828)
			(xy 37.036063 -300.900095) (xy 37.004584 -300.978725) (xy 36.965773 -301.054006) (xy 36.919983 -301.125258)
			(xy 36.867627 -301.191834) (xy 36.809179 -301.253132) (xy 36.745169 -301.308597) (xy 36.676177 -301.357726)
			(xy 36.602827 -301.400075) (xy 36.525784 -301.435259) (xy 36.445745 -301.462961) (xy 36.363436 -301.482929)
			(xy 36.279601 -301.494982) (xy 36.195 -301.499013) (xy 36.110399 -301.494982) (xy 36.026564 -301.482929)
			(xy 35.944255 -301.462961) (xy 35.864216 -301.435259) (xy 35.787173 -301.400075) (xy 35.713823 -301.357726)
			(xy 35.644831 -301.308597) (xy 35.580821 -301.253132) (xy 35.522373 -301.191834) (xy 35.470017 -301.125258)
			(xy 35.424227 -301.054006) (xy 35.385416 -300.978725) (xy 35.353937 -300.900095) (xy 35.330076 -300.818828)
			(xy 35.314047 -300.735662) (xy 35.305996 -300.651348) (xy 32.770177 -300.651348) (xy 32.810984 -300.701203)
			(xy 32.859337 -300.773744) (xy 32.90036 -300.850668) (xy 32.933661 -300.931236) (xy 32.958919 -301.014676)
			(xy 32.975892 -301.100187) (xy 32.984418 -301.186948) (xy 32.984948 -301.230538) (xy 32.984444 -301.272886)
			(xy 32.976393 -301.3572) (xy 32.960364 -301.440366) (xy 32.936503 -301.521633) (xy 32.905024 -301.600263)
			(xy 32.866213 -301.675544) (xy 32.820423 -301.746796) (xy 32.768067 -301.813372) (xy 32.709619 -301.87467)
			(xy 32.645609 -301.930135) (xy 32.576617 -301.979264) (xy 32.503267 -302.021613) (xy 32.426224 -302.056797)
			(xy 32.346185 -302.084499) (xy 32.263876 -302.104467) (xy 32.180041 -302.11652) (xy 32.09544 -302.120551)
			(xy 32.010839 -302.11652) (xy 31.927004 -302.104467) (xy 31.844695 -302.084499) (xy 31.764656 -302.056797)
			(xy 31.687613 -302.021613) (xy 31.614263 -301.979264) (xy 31.545271 -301.930135) (xy 31.481261 -301.87467)
			(xy 31.422813 -301.813372) (xy 31.370457 -301.746796) (xy 31.324667 -301.675544) (xy 31.285856 -301.600263)
			(xy 31.254377 -301.521633) (xy 31.230516 -301.440366) (xy 31.214487 -301.3572) (xy 31.206436 -301.272886)
			(xy 31.205932 -301.230538) (xy 31.206398 -301.18954) (xy 31.213943 -301.107891) (xy 31.228973 -301.027283)
			(xy 31.239714 -300.987714) (xy 31.242762 -300.976792) (xy 31.239206 -300.954948) (xy 31.182564 -300.871382)
			(xy 31.163768 -300.860206) (xy 31.152338 -300.858936) (xy 31.10903 -300.85397) (xy 31.023572 -300.836748)
			(xy 30.94021 -300.811248) (xy 30.859742 -300.777714) (xy 30.782941 -300.736468) (xy 30.710544 -300.687906)
			(xy 30.643246 -300.632494) (xy 30.581692 -300.570763) (xy 30.526473 -300.503306) (xy 30.478118 -300.43077)
			(xy 30.437093 -300.353851) (xy 30.40379 -300.273287) (xy 30.378529 -300.189852) (xy 30.361553 -300.104345)
			(xy 30.353024 -300.017588) (xy 30.352492 -299.974) (xy 19.513291 -299.974) (xy 19.459957 -300.025132)
			(xy 19.393279 -300.077828) (xy 19.321878 -300.123924) (xy 19.246407 -300.162999) (xy 19.167552 -300.194697)
			(xy 19.086034 -300.21873) (xy 19.002594 -300.234878) (xy 18.917996 -300.242994) (xy 18.875502 -300.243494)
			(xy 18.833152 -300.243034) (xy 18.748836 -300.234983) (xy 18.665666 -300.218954) (xy 18.584397 -300.195091)
			(xy 18.505765 -300.163611) (xy 18.43048 -300.1248) (xy 18.359226 -300.079008) (xy 18.292647 -300.02665)
			(xy 18.231347 -299.9682) (xy 18.17588 -299.904188) (xy 18.126749 -299.835194) (xy 18.084399 -299.761841)
			(xy 18.049214 -299.684796) (xy 18.021511 -299.604754) (xy 18.001542 -299.522442) (xy 17.989488 -299.438604)
			(xy 17.985458 -299.354) (xy 17.354253 -299.354) (xy 17.360904 -299.423652) (xy 17.361408 -299.466)
			(xy 17.360904 -299.508348) (xy 17.352853 -299.592662) (xy 17.336824 -299.675828) (xy 17.312963 -299.757095)
			(xy 17.281484 -299.835725) (xy 17.242673 -299.911006) (xy 17.196883 -299.982258) (xy 17.144527 -300.048834)
			(xy 17.086079 -300.110132) (xy 17.022069 -300.165597) (xy 16.953077 -300.214726) (xy 16.879727 -300.257075)
			(xy 16.802684 -300.292259) (xy 16.722645 -300.319961) (xy 16.640336 -300.339929) (xy 16.556501 -300.351982)
			(xy 16.4719 -300.356013) (xy 16.387299 -300.351982) (xy 16.303464 -300.339929) (xy 16.221155 -300.319961)
			(xy 16.141116 -300.292259) (xy 16.064073 -300.257075) (xy 15.990723 -300.214726) (xy 15.921731 -300.165597)
			(xy 15.857721 -300.110132) (xy 15.799273 -300.048834) (xy 15.746917 -299.982258) (xy 15.701127 -299.911006)
			(xy 15.662316 -299.835725) (xy 15.630837 -299.757095) (xy 15.606976 -299.675828) (xy 15.590947 -299.592662)
			(xy 15.582896 -299.508348) (xy 15.362505 -299.508348) (xy 15.375773 -299.528994) (xy 15.414584 -299.604275)
			(xy 15.446063 -299.682905) (xy 15.469924 -299.764172) (xy 15.485953 -299.847338) (xy 15.494004 -299.931652)
			(xy 15.494508 -299.974) (xy 15.494004 -300.016348) (xy 15.485953 -300.100662) (xy 15.469924 -300.183828)
			(xy 15.446063 -300.265095) (xy 15.414584 -300.343725) (xy 15.375773 -300.419006) (xy 15.329983 -300.490258)
			(xy 15.277627 -300.556834) (xy 15.219179 -300.618132) (xy 15.155169 -300.673597) (xy 15.086177 -300.722726)
			(xy 15.012827 -300.765075) (xy 14.935784 -300.800259) (xy 14.855745 -300.827961) (xy 14.773436 -300.847929)
			(xy 14.689601 -300.859982) (xy 14.605 -300.864013) (xy 14.520399 -300.859982) (xy 14.436564 -300.847929)
			(xy 14.354255 -300.827961) (xy 14.274216 -300.800259) (xy 14.197173 -300.765075) (xy 14.123823 -300.722726)
			(xy 14.054831 -300.673597) (xy 13.990821 -300.618132) (xy 13.932373 -300.556834) (xy 13.880017 -300.490258)
			(xy 13.834227 -300.419006) (xy 13.795416 -300.343725) (xy 13.763937 -300.265095) (xy 13.740076 -300.183828)
			(xy 13.724047 -300.100662) (xy 13.715996 -300.016348) (xy 9.816425 -300.016348) (xy 9.802447 -300.039384)
			(xy 9.742333 -300.123001) (xy 9.675893 -300.201685) (xy 9.640062 -300.238668) (xy 9.632696 -300.24578)
			(xy 9.62533 -300.264068) (xy 9.62533 -300.356016) (xy 9.632696 -300.374304) (xy 9.640062 -300.381416)
			(xy 9.675893 -300.418399) (xy 9.742333 -300.497083) (xy 9.802447 -300.580699) (xy 9.85587 -300.668741)
			(xy 9.902278 -300.760674) (xy 9.94139 -300.85594) (xy 9.972969 -300.953962) (xy 9.996822 -301.054144)
			(xy 10.012804 -301.155879) (xy 10.02082 -301.258549) (xy 10.02082 -301.361531) (xy 10.012804 -301.464201)
			(xy 9.996822 -301.565936) (xy 9.972969 -301.666118) (xy 9.94139 -301.76414) (xy 9.902278 -301.859406)
			(xy 9.85587 -301.951339) (xy 9.802447 -302.039381) (xy 9.742333 -302.122997) (xy 9.675893 -302.201681)
			(xy 9.640062 -302.238664) (xy 9.632696 -302.245776) (xy 9.62533 -302.264064) (xy 9.62533 -302.356012)
			(xy 9.632696 -302.3743) (xy 9.640062 -302.381412) (xy 9.675894 -302.418394) (xy 9.742334 -302.497078)
			(xy 9.802449 -302.580694) (xy 9.855873 -302.668736) (xy 9.902282 -302.760669) (xy 9.941394 -302.855935)
			(xy 9.972972 -302.953957) (xy 9.996825 -303.054139) (xy 10.012808 -303.155874) (xy 10.020823 -303.258545)
			(xy 10.021316 -303.310036) (xy 10.021239 -303.318348) (xy 15.581118 -303.318348) (xy 15.581118 -303.233652)
			(xy 15.589169 -303.149338) (xy 15.605198 -303.066172) (xy 15.629059 -302.984905) (xy 15.660538 -302.906275)
			(xy 15.699349 -302.830994) (xy 15.745139 -302.759742) (xy 15.797495 -302.693166) (xy 15.855943 -302.631868)
			(xy 15.919953 -302.576403) (xy 15.988945 -302.527274) (xy 16.062295 -302.484925) (xy 16.139338 -302.449741)
			(xy 16.219377 -302.422039) (xy 16.301686 -302.402071) (xy 16.385521 -302.390018) (xy 16.470122 -302.385988)
			(xy 16.554723 -302.390018) (xy 16.638558 -302.402071) (xy 16.720867 -302.422039) (xy 16.800906 -302.449741)
			(xy 16.877949 -302.484925) (xy 16.951299 -302.527274) (xy 17.020291 -302.576403) (xy 17.084301 -302.631868)
			(xy 17.142749 -302.693166) (xy 17.195105 -302.759742) (xy 17.240895 -302.830994) (xy 17.279706 -302.906275)
			(xy 17.311185 -302.984905) (xy 17.335046 -303.066172) (xy 17.351075 -303.149338) (xy 17.359126 -303.233652)
			(xy 17.35963 -303.276) (xy 17.359126 -303.318348) (xy 17.351075 -303.402662) (xy 17.335046 -303.485828)
			(xy 17.311185 -303.567095) (xy 17.279706 -303.645725) (xy 17.240895 -303.721006) (xy 17.195105 -303.792258)
			(xy 17.142749 -303.858834) (xy 17.084301 -303.920132) (xy 17.020291 -303.975597) (xy 16.951299 -304.024726)
			(xy 16.877949 -304.067075) (xy 16.800906 -304.102259) (xy 16.720867 -304.129961) (xy 16.638558 -304.149929)
			(xy 16.554723 -304.161982) (xy 16.470122 -304.166013) (xy 16.385521 -304.161982) (xy 16.301686 -304.149929)
			(xy 16.219377 -304.129961) (xy 16.139338 -304.102259) (xy 16.062295 -304.067075) (xy 15.988945 -304.024726)
			(xy 15.919953 -303.975597) (xy 15.855943 -303.920132) (xy 15.797495 -303.858834) (xy 15.745139 -303.792258)
			(xy 15.699349 -303.721006) (xy 15.660538 -303.645725) (xy 15.629059 -303.567095) (xy 15.605198 -303.485828)
			(xy 15.589169 -303.402662) (xy 15.581118 -303.318348) (xy 10.021239 -303.318348) (xy 10.020833 -303.361931)
			(xy 10.012687 -303.4654) (xy 9.996449 -303.567911) (xy 9.972217 -303.668832) (xy 9.940142 -303.767541)
			(xy 9.900422 -303.863429) (xy 9.853301 -303.955905) (xy 9.79907 -304.044399) (xy 9.738063 -304.128365)
			(xy 9.670657 -304.207286) (xy 9.597266 -304.280676) (xy 9.518343 -304.348081) (xy 9.434375 -304.409086)
			(xy 9.34588 -304.463315) (xy 9.253403 -304.510434) (xy 9.157514 -304.550152) (xy 9.058805 -304.582225)
			(xy 8.957883 -304.606454) (xy 8.855372 -304.62269) (xy 8.751903 -304.630834) (xy 8.700008 -304.631344)
			(xy 8.648517 -304.630849) (xy 8.545846 -304.622834) (xy 8.444112 -304.606851) (xy 8.343929 -304.582999)
			(xy 8.245908 -304.55142) (xy 8.150641 -304.512308) (xy 8.058708 -304.4659) (xy 7.970667 -304.412476)
			(xy 7.887051 -304.352361) (xy 7.808367 -304.285921) (xy 7.771384 -304.25009) (xy 7.764272 -304.242724)
			(xy 7.745984 -304.235358) (xy 7.654036 -304.235358) (xy 7.635748 -304.242724) (xy 7.628636 -304.25009)
			(xy 7.591645 -304.285913) (xy 7.512963 -304.352354) (xy 7.429347 -304.412469) (xy 7.341307 -304.465894)
			(xy 7.249375 -304.512303) (xy 7.154109 -304.551416) (xy 7.056089 -304.582996) (xy 6.955907 -304.60685)
			(xy 6.854173 -304.622834) (xy 6.751503 -304.63085) (xy 6.700012 -304.631344) (xy 6.648117 -304.630849)
			(xy 6.544647 -304.622706) (xy 6.442135 -304.60647) (xy 6.341213 -304.582241) (xy 6.242503 -304.550168)
			(xy 6.146614 -304.51045) (xy 6.054137 -304.46333) (xy 5.965641 -304.4091) (xy 5.881674 -304.348094)
			(xy 5.802751 -304.280688) (xy 5.729361 -304.207297) (xy 5.661955 -304.128375) (xy 5.600949 -304.044407)
			(xy 5.546719 -303.955912) (xy 5.499599 -303.863434) (xy 5.459881 -303.767545) (xy 5.427808 -303.668835)
			(xy 5.403579 -303.567913) (xy 5.387343 -303.465401) (xy 5.3792 -303.361931) (xy 5.378704 -303.310036)
			(xy 1.651254 -303.310036) (xy 1.651254 -305.67369) (xy 13.334996 -305.67369) (xy 13.334996 -305.588994)
			(xy 13.343047 -305.50468) (xy 13.359076 -305.421514) (xy 13.382937 -305.340247) (xy 13.414416 -305.261617)
			(xy 13.453227 -305.186336) (xy 13.499017 -305.115084) (xy 13.551373 -305.048508) (xy 13.609821 -304.98721)
			(xy 13.673831 -304.931745) (xy 13.742823 -304.882616) (xy 13.816173 -304.840267) (xy 13.893216 -304.805083)
			(xy 13.973255 -304.777381) (xy 14.055564 -304.757413) (xy 14.139399 -304.74536) (xy 14.224 -304.74133)
			(xy 14.308601 -304.74536) (xy 14.392436 -304.757413) (xy 14.474745 -304.777381) (xy 14.554784 -304.805083)
			(xy 14.585368 -304.81905) (xy 17.780762 -304.81905) (xy 17.781227 -304.776932) (xy 17.789204 -304.693074)
			(xy 17.805071 -304.610346) (xy 17.828687 -304.529488) (xy 17.85984 -304.451224) (xy 17.898251 -304.376255)
			(xy 17.943576 -304.305253) (xy 17.99541 -304.238852) (xy 18.053288 -304.177649) (xy 18.116693 -304.12219)
			(xy 18.150586 -304.097182) (xy 18.158004 -304.091444) (xy 18.168317 -304.075795) (xy 18.172264 -304.057473)
			(xy 18.17116 -304.04816) (xy 18.166172 -304.014089) (xy 18.160833 -303.945432) (xy 18.160492 -303.911)
			(xy 18.160967 -303.869898) (xy 18.168552 -303.788043) (xy 18.183657 -303.707238) (xy 18.206153 -303.628171)
			(xy 18.235849 -303.551517) (xy 18.272491 -303.47793) (xy 18.315766 -303.408038) (xy 18.365306 -303.342437)
			(xy 18.420687 -303.281687) (xy 18.481437 -303.226306) (xy 18.547038 -303.176766) (xy 18.61693 -303.133491)
			(xy 18.690517 -303.096849) (xy 18.767171 -303.067153) (xy 18.846238 -303.044657) (xy 18.927043 -303.029552)
			(xy 19.008898 -303.021967) (xy 19.05 -303.021492) (xy 19.092218 -303.021982) (xy 19.176274 -303.029996)
			(xy 19.259192 -303.045944) (xy 19.340224 -303.069681) (xy 19.41864 -303.100993) (xy 19.493735 -303.139598)
			(xy 19.529552 -303.161954) (xy 19.541236 -303.16932) (xy 19.567906 -303.17059) (xy 19.670522 -303.118012)
			(xy 19.685 -303.095406) (xy 19.685762 -303.08169) (xy 19.68837 -303.042073) (xy 19.699743 -302.963492)
			(xy 19.718066 -302.886235) (xy 19.743193 -302.810916) (xy 19.75866 -302.77435) (xy 19.764502 -302.760888)
			(xy 19.760184 -302.731932) (xy 19.680936 -302.640492) (xy 19.652996 -302.631856) (xy 19.638772 -302.635666)
			(xy 19.600709 -302.645583) (xy 19.523282 -302.659463) (xy 19.444931 -302.666452) (xy 19.4056 -302.666908)
			(xy 19.363675 -302.666424) (xy 19.280196 -302.658533) (xy 19.197831 -302.642821) (xy 19.117309 -302.619428)
			(xy 19.039347 -302.58856) (xy 18.964636 -302.550493) (xy 18.893838 -302.505563) (xy 18.827583 -302.454171)
			(xy 18.766459 -302.396771) (xy 18.711007 -302.333874) (xy 18.661721 -302.266037) (xy 18.619038 -302.193863)
			(xy 18.583336 -302.117993) (xy 18.554932 -302.0391) (xy 18.534079 -301.957883) (xy 18.520962 -301.875065)
			(xy 18.515697 -301.79138) (xy 18.518331 -301.70757) (xy 18.52884 -301.624381) (xy 18.547132 -301.54255)
			(xy 18.573043 -301.462803) (xy 18.606344 -301.385849) (xy 18.64674 -301.31237) (xy 18.693871 -301.243018)
			(xy 18.747319 -301.17841) (xy 18.80661 -301.119119) (xy 18.871218 -301.065671) (xy 18.94057 -301.01854)
			(xy 19.014049 -300.978144) (xy 19.091003 -300.944843) (xy 19.17075 -300.918932) (xy 19.252581 -300.90064)
			(xy 19.33577 -300.890131) (xy 19.41958 -300.887497) (xy 19.503265 -300.892762) (xy 19.586083 -300.905879)
			(xy 19.6673 -300.926732) (xy 19.746193 -300.955136) (xy 19.822063 -300.990838) (xy 19.894237 -301.033521)
			(xy 19.962074 -301.082807) (xy 20.024971 -301.138259) (xy 20.082371 -301.199383) (xy 20.133763 -301.265638)
			(xy 20.178693 -301.336436) (xy 20.21676 -301.411147) (xy 20.247628 -301.489109) (xy 20.271021 -301.569631)
			(xy 20.286733 -301.651996) (xy 20.294624 -301.735475) (xy 20.295108 -301.7774) (xy 20.294534 -301.823139)
			(xy 20.285144 -301.914133) (xy 20.266464 -302.003683) (xy 20.23869 -302.090842) (xy 20.22094 -302.133)
			(xy 20.215098 -302.146462) (xy 20.219416 -302.175418) (xy 20.298664 -302.266858) (xy 20.326604 -302.275494)
			(xy 20.340828 -302.271684) (xy 20.378891 -302.261768) (xy 20.456318 -302.247887) (xy 20.534669 -302.240898)
			(xy 20.574 -302.240442) (xy 20.616348 -302.240946) (xy 20.700662 -302.248997) (xy 20.783828 -302.265026)
			(xy 20.865095 -302.288887) (xy 20.943725 -302.320366) (xy 21.019006 -302.359177) (xy 21.090258 -302.404967)
			(xy 21.156834 -302.457323) (xy 21.218132 -302.515771) (xy 21.273597 -302.579781) (xy 21.322726 -302.648773)
			(xy 21.365075 -302.722123) (xy 21.400259 -302.799166) (xy 21.427961 -302.879205) (xy 21.447929 -302.961514)
			(xy 21.459982 -303.045349) (xy 21.464013 -303.12995) (xy 21.459982 -303.214551) (xy 21.447929 -303.298386)
			(xy 21.427961 -303.380695) (xy 21.400259 -303.460734) (xy 21.365075 -303.537777) (xy 21.322726 -303.611127)
			(xy 21.273597 -303.680119) (xy 21.218132 -303.744129) (xy 21.156834 -303.802577) (xy 21.090258 -303.854933)
			(xy 21.019006 -303.900723) (xy 20.943725 -303.939534) (xy 20.865095 -303.971013) (xy 20.783828 -303.994874)
			(xy 20.700662 -304.010903) (xy 20.616348 -304.018954) (xy 20.574 -304.019458) (xy 20.531782 -304.01896)
			(xy 20.447726 -304.010946) (xy 20.364809 -303.995) (xy 20.283778 -303.971264) (xy 20.205361 -303.939954)
			(xy 20.130266 -303.901351) (xy 20.094448 -303.878996) (xy 20.082764 -303.87163) (xy 20.056094 -303.87036)
			(xy 19.953478 -303.922938) (xy 19.939 -303.945544) (xy 19.938238 -303.95926) (xy 19.935321 -304.003283)
			(xy 19.921811 -304.090475) (xy 19.899738 -304.175901) (xy 19.869319 -304.258724) (xy 19.832685 -304.334348)
			(xy 30.860996 -304.334348) (xy 30.860996 -304.249652) (xy 30.869047 -304.165338) (xy 30.885076 -304.082172)
			(xy 30.908937 -304.000905) (xy 30.940416 -303.922275) (xy 30.979227 -303.846994) (xy 31.025017 -303.775742)
			(xy 31.077373 -303.709166) (xy 31.135821 -303.647868) (xy 31.199831 -303.592403) (xy 31.268823 -303.543274)
			(xy 31.342173 -303.500925) (xy 31.419216 -303.465741) (xy 31.499255 -303.438039) (xy 31.581564 -303.418071)
			(xy 31.665399 -303.406018) (xy 31.75 -303.401988) (xy 31.834601 -303.406018) (xy 31.918436 -303.418071)
			(xy 32.000745 -303.438039) (xy 32.080784 -303.465741) (xy 32.157827 -303.500925) (xy 32.231177 -303.543274)
			(xy 32.300169 -303.592403) (xy 32.364179 -303.647868) (xy 32.422627 -303.709166) (xy 32.474983 -303.775742)
			(xy 32.520773 -303.846994) (xy 32.559584 -303.922275) (xy 32.591063 -304.000905) (xy 32.614924 -304.082172)
			(xy 32.630888 -304.165) (xy 33.400492 -304.165) (xy 33.400972 -304.122877) (xy 33.408937 -304.03901)
			(xy 33.424797 -303.956271) (xy 33.448408 -303.875402) (xy 33.479559 -303.797128) (xy 33.517971 -303.72215)
			(xy 33.563301 -303.651139) (xy 33.615141 -303.584733) (xy 33.673028 -303.523525) (xy 33.736442 -303.468065)
			(xy 33.804816 -303.418849) (xy 33.840928 -303.397158) (xy 33.850715 -303.390843) (xy 33.863681 -303.371523)
			(xy 33.86582 -303.360074) (xy 33.872005 -303.317926) (xy 33.891435 -303.234977) (xy 33.918706 -303.154266)
			(xy 33.953569 -303.076532) (xy 33.995705 -303.002488) (xy 34.044727 -302.932811) (xy 34.100186 -302.868141)
			(xy 34.161574 -302.809069) (xy 34.228329 -302.756137) (xy 34.299839 -302.709831) (xy 34.375449 -302.670573)
			(xy 34.454466 -302.638725) (xy 34.536166 -302.614577) (xy 34.619801 -302.598352) (xy 34.704603 -302.590197)
			(xy 34.7472 -302.589692) (xy 34.788302 -302.590167) (xy 34.870157 -302.597752) (xy 34.950962 -302.612857)
			(xy 35.030029 -302.635353) (xy 35.106683 -302.665049) (xy 35.18027 -302.701691) (xy 35.250162 -302.744966)
			(xy 35.315763 -302.794506) (xy 35.376513 -302.849887) (xy 35.431894 -302.910637) (xy 35.481434 -302.976238)
			(xy 35.524709 -303.04613) (xy 35.561351 -303.119717) (xy 35.591047 -303.196371) (xy 35.613543 -303.275438)
			(xy 35.628648 -303.356243) (xy 35.636233 -303.438098) (xy 35.636708 -303.4792) (xy 35.636228 -303.521323)
			(xy 35.628263 -303.60519) (xy 35.612403 -303.687929) (xy 35.588792 -303.768798) (xy 35.557641 -303.847072)
			(xy 35.519229 -303.92205) (xy 35.473899 -303.993061) (xy 35.422059 -304.059467) (xy 35.364172 -304.120675)
			(xy 35.300758 -304.176135) (xy 35.232384 -304.225351) (xy 35.196272 -304.247042) (xy 35.186485 -304.253357)
			(xy 35.173519 -304.272677) (xy 35.17138 -304.284126) (xy 35.165195 -304.326274) (xy 35.145765 -304.409223)
			(xy 35.118494 -304.489934) (xy 35.083631 -304.567668) (xy 35.041495 -304.641712) (xy 34.992473 -304.711389)
			(xy 34.937014 -304.776059) (xy 34.875626 -304.835131) (xy 34.808871 -304.888063) (xy 34.737361 -304.934369)
			(xy 34.661751 -304.973627) (xy 34.582734 -305.005475) (xy 34.501034 -305.029623) (xy 34.417399 -305.045848)
			(xy 34.332597 -305.054003) (xy 34.29 -305.054508) (xy 34.248898 -305.054033) (xy 34.167043 -305.046448)
			(xy 34.086238 -305.031343) (xy 34.007171 -305.008847) (xy 33.930517 -304.979151) (xy 33.85693 -304.942509)
			(xy 33.787038 -304.899234) (xy 33.721437 -304.849694) (xy 33.660687 -304.794313) (xy 33.605306 -304.733563)
			(xy 33.555766 -304.667962) (xy 33.512491 -304.59807) (xy 33.475849 -304.524483) (xy 33.446153 -304.447829)
			(xy 33.423657 -304.368762) (xy 33.408552 -304.287957) (xy 33.400967 -304.206102) (xy 33.400492 -304.165)
			(xy 32.630888 -304.165) (xy 32.630953 -304.165338) (xy 32.639004 -304.249652) (xy 32.639508 -304.292)
			(xy 32.639004 -304.334348) (xy 32.630953 -304.418662) (xy 32.614924 -304.501828) (xy 32.591063 -304.583095)
			(xy 32.559584 -304.661725) (xy 32.520773 -304.737006) (xy 32.474983 -304.808258) (xy 32.422627 -304.874834)
			(xy 32.364179 -304.936132) (xy 32.300169 -304.991597) (xy 32.231177 -305.040726) (xy 32.157827 -305.083075)
			(xy 32.080784 -305.118259) (xy 32.000745 -305.145961) (xy 31.918436 -305.165929) (xy 31.834601 -305.177982)
			(xy 31.75 -305.182013) (xy 31.665399 -305.177982) (xy 31.581564 -305.165929) (xy 31.499255 -305.145961)
			(xy 31.419216 -305.118259) (xy 31.342173 -305.083075) (xy 31.268823 -305.040726) (xy 31.199831 -304.991597)
			(xy 31.135821 -304.936132) (xy 31.077373 -304.874834) (xy 31.025017 -304.808258) (xy 30.979227 -304.737006)
			(xy 30.940416 -304.661725) (xy 30.908937 -304.583095) (xy 30.885076 -304.501828) (xy 30.869047 -304.418662)
			(xy 30.860996 -304.334348) (xy 19.832685 -304.334348) (xy 19.830853 -304.33813) (xy 19.784717 -304.41334)
			(xy 19.731364 -304.483614) (xy 19.671319 -304.548263) (xy 19.60517 -304.606652) (xy 19.569684 -304.632868)
			(xy 19.562288 -304.638631) (xy 19.551974 -304.65427) (xy 19.548015 -304.67258) (xy 19.54911 -304.68189)
			(xy 19.554092 -304.715961) (xy 19.559435 -304.784618) (xy 19.559778 -304.81905) (xy 19.559274 -304.861398)
			(xy 19.551223 -304.945712) (xy 19.535194 -305.028878) (xy 19.511333 -305.110145) (xy 19.479854 -305.188775)
			(xy 19.441043 -305.264056) (xy 19.395253 -305.335308) (xy 19.342897 -305.401884) (xy 19.284449 -305.463182)
			(xy 19.220439 -305.518647) (xy 19.151447 -305.567776) (xy 19.078097 -305.610125) (xy 19.001054 -305.645309)
			(xy 18.921015 -305.673011) (xy 18.838706 -305.692979) (xy 18.754871 -305.705032) (xy 18.67027 -305.709063)
			(xy 18.585669 -305.705032) (xy 18.501834 -305.692979) (xy 18.419525 -305.673011) (xy 18.339486 -305.645309)
			(xy 18.262443 -305.610125) (xy 18.189093 -305.567776) (xy 18.120101 -305.518647) (xy 18.056091 -305.463182)
			(xy 17.997643 -305.401884) (xy 17.945287 -305.335308) (xy 17.899497 -305.264056) (xy 17.860686 -305.188775)
			(xy 17.829207 -305.110145) (xy 17.805346 -305.028878) (xy 17.789317 -304.945712) (xy 17.781266 -304.861398)
			(xy 17.780762 -304.81905) (xy 14.585368 -304.81905) (xy 14.631827 -304.840267) (xy 14.705177 -304.882616)
			(xy 14.774169 -304.931745) (xy 14.838179 -304.98721) (xy 14.896627 -305.048508) (xy 14.948983 -305.115084)
			(xy 14.994773 -305.186336) (xy 15.033584 -305.261617) (xy 15.065063 -305.340247) (xy 15.088924 -305.421514)
			(xy 15.104953 -305.50468) (xy 15.113004 -305.588994) (xy 15.113508 -305.631342) (xy 15.113004 -305.67369)
			(xy 15.104953 -305.758004) (xy 15.088924 -305.84117) (xy 15.065063 -305.922437) (xy 15.033584 -306.001067)
			(xy 14.994773 -306.076348) (xy 14.948983 -306.1476) (xy 14.896627 -306.214176) (xy 14.838179 -306.275474)
			(xy 14.774169 -306.330939) (xy 14.705177 -306.380068) (xy 14.631827 -306.422417) (xy 14.554784 -306.457601)
			(xy 14.474745 -306.485303) (xy 14.392436 -306.505271) (xy 14.308601 -306.517324) (xy 14.224 -306.521355)
			(xy 14.139399 -306.517324) (xy 14.055564 -306.505271) (xy 13.973255 -306.485303) (xy 13.893216 -306.457601)
			(xy 13.816173 -306.422417) (xy 13.742823 -306.380068) (xy 13.673831 -306.330939) (xy 13.609821 -306.275474)
			(xy 13.551373 -306.214176) (xy 13.499017 -306.1476) (xy 13.453227 -306.076348) (xy 13.414416 -306.001067)
			(xy 13.382937 -305.922437) (xy 13.359076 -305.84117) (xy 13.343047 -305.758004) (xy 13.334996 -305.67369)
			(xy 1.651254 -305.67369) (xy 1.651254 -307.460904) (xy 1.652778 -307.51145) (xy 1.651254 -307.561996)
			(xy 1.651254 -308.929024) (xy 1.651876 -308.940869) (xy 1.662472 -308.962059) (xy 1.671574 -308.969664)
			(xy 1.746504 -309.025798) (xy 1.769618 -309.029862) (xy 1.781556 -309.02656) (xy 1.802659 -309.020493)
			(xy 1.845351 -309.010202) (xy 1.8669 -309.005986) (xy 1.877822 -309.003954) (xy 1.895348 -308.991762)
			(xy 1.945894 -308.907434) (xy 1.948434 -308.886352) (xy 1.945132 -308.875684) (xy 1.932241 -308.83259)
			(xy 1.914173 -308.74447) (xy 1.905078 -308.654977) (xy 1.904492 -308.61) (xy 1.904996 -308.567652)
			(xy 1.913047 -308.483338) (xy 1.929076 -308.400172) (xy 1.952937 -308.318905) (xy 1.984416 -308.240275)
			(xy 2.023227 -308.164994) (xy 2.069017 -308.093742) (xy 2.121373 -308.027166) (xy 2.179821 -307.965868)
			(xy 2.243831 -307.910403) (xy 2.312823 -307.861274) (xy 2.386173 -307.818925) (xy 2.463216 -307.783741)
			(xy 2.543255 -307.756039) (xy 2.625564 -307.736071) (xy 2.709399 -307.724018) (xy 2.794 -307.719988)
			(xy 2.878601 -307.724018) (xy 2.962436 -307.736071) (xy 3.044745 -307.756039) (xy 3.124784 -307.783741)
			(xy 3.201827 -307.818925) (xy 3.275177 -307.861274) (xy 3.344169 -307.910403) (xy 3.408179 -307.965868)
			(xy 3.466627 -308.027166) (xy 3.518983 -308.093742) (xy 3.564773 -308.164994) (xy 3.603584 -308.240275)
			(xy 3.635063 -308.318905) (xy 3.658924 -308.400172) (xy 3.674953 -308.483338) (xy 3.683004 -308.567652)
			(xy 3.683508 -308.61) (xy 3.683037 -308.651046) (xy 3.675475 -308.732789) (xy 3.660413 -308.813487)
			(xy 3.637978 -308.892454) (xy 3.608362 -308.969017) (xy 3.571817 -309.042526) (xy 3.528653 -309.112354)
			(xy 3.479238 -309.177908) (xy 3.423993 -309.238629) (xy 3.363388 -309.294001) (xy 3.297937 -309.343552)
			(xy 3.228199 -309.386862) (xy 3.154767 -309.423561) (xy 3.078266 -309.453336) (xy 2.999346 -309.475936)
			(xy 2.9591 -309.484014) (xy 2.948178 -309.486046) (xy 2.930652 -309.498238) (xy 2.880106 -309.582566)
			(xy 2.877566 -309.603648) (xy 2.880868 -309.614316) (xy 2.893759 -309.65741) (xy 2.911827 -309.74553)
			(xy 2.920922 -309.835023) (xy 2.921508 -309.88) (xy 2.921099 -309.91829) (xy 2.914494 -309.994584)
			(xy 2.901346 -310.070027) (xy 2.881753 -310.144058) (xy 2.869184 -310.180228) (xy 2.866543 -310.188666)
			(xy 2.866543 -310.206334) (xy 2.869184 -310.214772) (xy 2.881726 -310.25095) (xy 2.9013 -310.324982)
			(xy 2.914444 -310.400422) (xy 2.921062 -310.476712) (xy 2.921508 -310.515) (xy 2.920982 -310.558461)
			(xy 2.912503 -310.644968) (xy 2.895629 -310.730235) (xy 2.870519 -310.813451) (xy 2.854452 -310.853836)
			(xy 2.849372 -310.866282) (xy 2.852928 -310.89346) (xy 2.923794 -310.984646) (xy 2.94894 -310.994806)
			(xy 2.962656 -310.993028) (xy 2.993357 -310.988987) (xy 3.055135 -310.984665) (xy 3.0861 -310.984392)
			(xy 3.127202 -310.984867) (xy 3.209057 -310.992452) (xy 3.289862 -311.007557) (xy 3.368929 -311.030053)
			(xy 3.445583 -311.059749) (xy 3.51917 -311.096391) (xy 3.589062 -311.139666) (xy 3.654663 -311.189206)
			(xy 3.715413 -311.244587) (xy 3.770794 -311.305337) (xy 3.820334 -311.370938) (xy 3.863609 -311.44083)
			(xy 3.900251 -311.514417) (xy 3.929947 -311.591071) (xy 3.952443 -311.670138) (xy 3.967548 -311.750943)
			(xy 3.975133 -311.832798) (xy 3.975608 -311.8739) (xy 3.975138 -311.915149) (xy 3.967494 -311.997294)
			(xy 3.952279 -312.078377) (xy 3.929623 -312.157704) (xy 3.89972 -312.234593) (xy 3.862828 -312.308384)
			(xy 3.819263 -312.378442) (xy 3.774877 -312.436948) (xy 41.147996 -312.436948) (xy 41.147996 -312.352252)
			(xy 41.156047 -312.267938) (xy 41.172076 -312.184772) (xy 41.195937 -312.103505) (xy 41.227416 -312.024875)
			(xy 41.266227 -311.949594) (xy 41.312017 -311.878342) (xy 41.364373 -311.811766) (xy 41.422821 -311.750468)
			(xy 41.486831 -311.695003) (xy 41.555823 -311.645874) (xy 41.629173 -311.603525) (xy 41.706216 -311.568341)
			(xy 41.786255 -311.540639) (xy 41.868564 -311.520671) (xy 41.952399 -311.508618) (xy 42.037 -311.504588)
			(xy 42.121601 -311.508618) (xy 42.205436 -311.520671) (xy 42.287745 -311.540639) (xy 42.367784 -311.568341)
			(xy 42.444827 -311.603525) (xy 42.518177 -311.645874) (xy 42.587169 -311.695003) (xy 42.651179 -311.750468)
			(xy 42.709627 -311.811766) (xy 42.761983 -311.878342) (xy 42.807773 -311.949594) (xy 42.846584 -312.024875)
			(xy 42.878063 -312.103505) (xy 42.885226 -312.1279) (xy 45.490892 -312.1279) (xy 45.491396 -312.085552)
			(xy 45.499447 -312.001238) (xy 45.515476 -311.918072) (xy 45.539337 -311.836805) (xy 45.570816 -311.758175)
			(xy 45.609627 -311.682894) (xy 45.655417 -311.611642) (xy 45.707773 -311.545066) (xy 45.766221 -311.483768)
			(xy 45.830231 -311.428303) (xy 45.899223 -311.379174) (xy 45.972573 -311.336825) (xy 46.049616 -311.301641)
			(xy 46.129655 -311.273939) (xy 46.211964 -311.253971) (xy 46.295799 -311.241918) (xy 46.3804 -311.237888)
			(xy 46.465001 -311.241918) (xy 46.548836 -311.253971) (xy 46.631145 -311.273939) (xy 46.711184 -311.301641)
			(xy 46.788227 -311.336825) (xy 46.861577 -311.379174) (xy 46.930569 -311.428303) (xy 46.994579 -311.483768)
			(xy 47.053027 -311.545066) (xy 47.105383 -311.611642) (xy 47.151173 -311.682894) (xy 47.189984 -311.758175)
			(xy 47.221463 -311.836805) (xy 47.245324 -311.918072) (xy 47.261353 -312.001238) (xy 47.269404 -312.085552)
			(xy 47.269908 -312.1279) (xy 47.269424 -312.168711) (xy 47.261948 -312.249989) (xy 47.24706 -312.330241)
			(xy 47.224885 -312.408792) (xy 47.195609 -312.484983) (xy 47.159477 -312.558171) (xy 47.116795 -312.627743)
			(xy 47.06792 -312.693114) (xy 47.013263 -312.753733) (xy 46.953284 -312.809092) (xy 46.921166 -312.834274)
			(xy 46.91126 -312.84164) (xy 46.900846 -312.863484) (xy 46.903132 -312.970164) (xy 46.914562 -312.991246)
			(xy 46.924722 -312.998358) (xy 46.959567 -313.023219) (xy 47.024778 -313.078677) (xy 47.08436 -313.140143)
			(xy 47.13776 -313.20705) (xy 47.184484 -313.278778) (xy 47.224101 -313.354664) (xy 47.256243 -313.434004)
			(xy 47.280614 -313.516066) (xy 47.296987 -313.60009) (xy 47.305212 -313.685298) (xy 47.305722 -313.7281)
			(xy 47.305271 -313.767751) (xy 47.298217 -313.846738) (xy 47.284157 -313.924783) (xy 47.263202 -314.001266)
			(xy 47.235519 -314.075579) (xy 47.201328 -314.147131) (xy 47.1609 -314.215354) (xy 47.138082 -314.247784)
			(xy 47.13224 -314.255912) (xy 47.127668 -314.274708) (xy 47.140368 -314.364116) (xy 47.15002 -314.38088)
			(xy 47.157894 -314.386976) (xy 47.189292 -314.412235) (xy 47.247951 -314.467494) (xy 47.301371 -314.527832)
			(xy 47.349113 -314.592755) (xy 47.390788 -314.661731) (xy 47.426052 -314.734194) (xy 47.454616 -314.809549)
			(xy 47.476247 -314.88718) (xy 47.490767 -314.966449) (xy 47.498057 -315.046706) (xy 47.498508 -315.087)
			(xy 47.498004 -315.129348) (xy 47.878996 -315.129348) (xy 47.878996 -315.044652) (xy 47.887047 -314.960338)
			(xy 47.903076 -314.877172) (xy 47.926937 -314.795905) (xy 47.958416 -314.717275) (xy 47.997227 -314.641994)
			(xy 48.043017 -314.570742) (xy 48.095373 -314.504166) (xy 48.153821 -314.442868) (xy 48.217831 -314.387403)
			(xy 48.286823 -314.338274) (xy 48.360173 -314.295925) (xy 48.437216 -314.260741) (xy 48.517255 -314.233039)
			(xy 48.599564 -314.213071) (xy 48.683399 -314.201018) (xy 48.768 -314.196988) (xy 48.852601 -314.201018)
			(xy 48.936436 -314.213071) (xy 49.018745 -314.233039) (xy 49.098784 -314.260741) (xy 49.175827 -314.295925)
			(xy 49.249177 -314.338274) (xy 49.318169 -314.387403) (xy 49.382179 -314.442868) (xy 49.440627 -314.504166)
			(xy 49.492983 -314.570742) (xy 49.538773 -314.641994) (xy 49.577584 -314.717275) (xy 49.609063 -314.795905)
			(xy 49.632924 -314.877172) (xy 49.648953 -314.960338) (xy 49.657004 -315.044652) (xy 49.657508 -315.087)
			(xy 49.657004 -315.129348) (xy 49.648953 -315.213662) (xy 49.632924 -315.296828) (xy 49.609063 -315.378095)
			(xy 49.577584 -315.456725) (xy 49.538773 -315.532006) (xy 49.492983 -315.603258) (xy 49.440627 -315.669834)
			(xy 49.382179 -315.731132) (xy 49.318169 -315.786597) (xy 49.249177 -315.835726) (xy 49.175827 -315.878075)
			(xy 49.098784 -315.913259) (xy 49.018745 -315.940961) (xy 48.936436 -315.960929) (xy 48.852601 -315.972982)
			(xy 48.768 -315.977013) (xy 48.683399 -315.972982) (xy 48.599564 -315.960929) (xy 48.517255 -315.940961)
			(xy 48.437216 -315.913259) (xy 48.360173 -315.878075) (xy 48.286823 -315.835726) (xy 48.217831 -315.786597)
			(xy 48.153821 -315.731132) (xy 48.095373 -315.669834) (xy 48.043017 -315.603258) (xy 47.997227 -315.532006)
			(xy 47.958416 -315.456725) (xy 47.926937 -315.378095) (xy 47.903076 -315.296828) (xy 47.887047 -315.213662)
			(xy 47.878996 -315.129348) (xy 47.498004 -315.129348) (xy 47.489953 -315.213662) (xy 47.473924 -315.296828)
			(xy 47.450063 -315.378095) (xy 47.418584 -315.456725) (xy 47.379773 -315.532006) (xy 47.333983 -315.603258)
			(xy 47.281627 -315.669834) (xy 47.223179 -315.731132) (xy 47.159169 -315.786597) (xy 47.090177 -315.835726)
			(xy 47.016827 -315.878075) (xy 46.939784 -315.913259) (xy 46.859745 -315.940961) (xy 46.777436 -315.960929)
			(xy 46.693601 -315.972982) (xy 46.609 -315.977013) (xy 46.524399 -315.972982) (xy 46.440564 -315.960929)
			(xy 46.358255 -315.940961) (xy 46.278216 -315.913259) (xy 46.201173 -315.878075) (xy 46.127823 -315.835726)
			(xy 46.058831 -315.786597) (xy 45.994821 -315.731132) (xy 45.936373 -315.669834) (xy 45.884017 -315.603258)
			(xy 45.838227 -315.532006) (xy 45.799416 -315.456725) (xy 45.767937 -315.378095) (xy 45.744076 -315.296828)
			(xy 45.728047 -315.213662) (xy 45.719996 -315.129348) (xy 45.719492 -315.087) (xy 45.71994 -315.047349)
			(xy 45.726994 -314.968362) (xy 45.741054 -314.890316) (xy 45.76201 -314.813833) (xy 45.789693 -314.739521)
			(xy 45.823885 -314.667969) (xy 45.864314 -314.599746) (xy 45.887132 -314.567316) (xy 45.892974 -314.559188)
			(xy 45.897546 -314.540392) (xy 45.884846 -314.450984) (xy 45.875194 -314.43422) (xy 45.86732 -314.428124)
			(xy 45.835903 -314.402888) (xy 45.777247 -314.347625) (xy 45.723831 -314.287282) (xy 45.676091 -314.222356)
			(xy 45.634419 -314.153377) (xy 45.599157 -314.080912) (xy 45.570595 -314.005555) (xy 45.548965 -313.927923)
			(xy 45.534446 -313.848653) (xy 45.527157 -313.768394) (xy 45.526706 -313.7281) (xy 45.527185 -313.687289)
			(xy 45.53466 -313.60601) (xy 45.549549 -313.525758) (xy 45.571724 -313.447207) (xy 45.601001 -313.371016)
			(xy 45.637133 -313.297827) (xy 45.679816 -313.228256) (xy 45.728692 -313.162885) (xy 45.78335 -313.102266)
			(xy 45.843329 -313.046908) (xy 45.875448 -313.021726) (xy 45.885354 -313.01436) (xy 45.895768 -312.992516)
			(xy 45.893482 -312.885836) (xy 45.882052 -312.864754) (xy 45.871892 -312.857642) (xy 45.83705 -312.832777)
			(xy 45.771838 -312.77732) (xy 45.712257 -312.715854) (xy 45.658856 -312.648948) (xy 45.612131 -312.57722)
			(xy 45.572514 -312.501335) (xy 45.540371 -312.421995) (xy 45.516 -312.339933) (xy 45.499627 -312.25591)
			(xy 45.491402 -312.170702) (xy 45.490892 -312.1279) (xy 42.885226 -312.1279) (xy 42.901924 -312.184772)
			(xy 42.917953 -312.267938) (xy 42.926004 -312.352252) (xy 42.926508 -312.3946) (xy 42.926004 -312.436948)
			(xy 42.917953 -312.521262) (xy 42.901924 -312.604428) (xy 42.878063 -312.685695) (xy 42.846584 -312.764325)
			(xy 42.807773 -312.839606) (xy 42.761983 -312.910858) (xy 42.709627 -312.977434) (xy 42.651179 -313.038732)
			(xy 42.587169 -313.094197) (xy 42.518177 -313.143326) (xy 42.444827 -313.185675) (xy 42.367784 -313.220859)
			(xy 42.287745 -313.248561) (xy 42.205436 -313.268529) (xy 42.121601 -313.280582) (xy 42.037 -313.284613)
			(xy 41.952399 -313.280582) (xy 41.868564 -313.268529) (xy 41.786255 -313.248561) (xy 41.706216 -313.220859)
			(xy 41.629173 -313.185675) (xy 41.555823 -313.143326) (xy 41.486831 -313.094197) (xy 41.422821 -313.038732)
			(xy 41.364373 -312.977434) (xy 41.312017 -312.910858) (xy 41.266227 -312.839606) (xy 41.227416 -312.764325)
			(xy 41.195937 -312.685695) (xy 41.172076 -312.604428) (xy 41.156047 -312.521262) (xy 41.147996 -312.436948)
			(xy 3.774877 -312.436948) (xy 3.7694 -312.444167) (xy 3.713666 -312.504993) (xy 3.652541 -312.560399)
			(xy 3.586549 -312.609908) (xy 3.516257 -312.653095) (xy 3.442269 -312.689589) (xy 3.36522 -312.719078)
			(xy 3.325622 -312.730642) (xy 3.313176 -312.733944) (xy 3.294634 -312.752232) (xy 3.262122 -312.85942)
			(xy 3.267456 -312.884566) (xy 3.276092 -312.894472) (xy 3.305032 -312.929065) (xy 3.356553 -313.003099)
			(xy 3.400321 -313.081965) (xy 3.435885 -313.164854) (xy 3.462882 -313.250916) (xy 3.481034 -313.339267)
			(xy 3.490154 -313.429002) (xy 3.490722 -313.4741) (xy 3.490285 -313.513751) (xy 3.483223 -313.592737)
			(xy 3.469157 -313.670782) (xy 3.448199 -313.747264) (xy 3.420514 -313.821576) (xy 3.386324 -313.893129)
			(xy 3.345899 -313.961353) (xy 3.323082 -313.993784) (xy 3.31724 -314.001912) (xy 3.312668 -314.020708)
			(xy 3.325368 -314.110116) (xy 3.33502 -314.12688) (xy 3.342894 -314.132976) (xy 3.374317 -314.158202)
			(xy 3.432963 -314.213475) (xy 3.486371 -314.273823) (xy 3.534103 -314.338753) (xy 3.57577 -314.407733)
			(xy 3.611029 -314.480197) (xy 3.639592 -314.555553) (xy 3.661225 -314.633183) (xy 3.67575 -314.71245)
			(xy 3.683049 -314.792706) (xy 3.683508 -314.833) (xy 4.062988 -314.833) (xy 4.067018 -314.748399)
			(xy 4.079071 -314.664564) (xy 4.099039 -314.582255) (xy 4.126741 -314.502216) (xy 4.161925 -314.425173)
			(xy 4.204274 -314.351823) (xy 4.253403 -314.282831) (xy 4.308868 -314.218821) (xy 4.370166 -314.160373)
			(xy 4.436742 -314.108017) (xy 4.507994 -314.062227) (xy 4.583275 -314.023416) (xy 4.661905 -313.991937)
			(xy 4.743172 -313.968076) (xy 4.826338 -313.952047) (xy 4.910652 -313.943996) (xy 4.953 -313.943492)
			(xy 4.982363 -313.943764) (xy 5.040958 -313.947706) (xy 5.070094 -313.951366) (xy 5.081866 -313.952267)
			(xy 5.104169 -313.944628) (xy 5.120719 -313.927838) (xy 5.124958 -313.916822) (xy 5.138957 -313.876426)
			(xy 5.173651 -313.798283) (xy 5.215681 -313.723828) (xy 5.264661 -313.653749) (xy 5.320138 -313.588692)
			(xy 5.3816 -313.529257) (xy 5.44848 -313.475993) (xy 5.520162 -313.429391) (xy 5.595984 -313.38988)
			(xy 5.675247 -313.357826) (xy 5.75722 -313.333523) (xy 5.841146 -313.317197) (xy 5.92625 -313.308998)
			(xy 5.969 -313.308492) (xy 6.011348 -313.308996) (xy 6.095662 -313.317047) (xy 6.178828 -313.333076)
			(xy 6.260095 -313.356937) (xy 6.338725 -313.388416) (xy 6.414006 -313.427227) (xy 6.485258 -313.473017)
			(xy 6.551834 -313.525373) (xy 6.613132 -313.583821) (xy 6.668597 -313.647831) (xy 6.717726 -313.716823)
			(xy 6.760075 -313.790173) (xy 6.795259 -313.867216) (xy 6.822961 -313.947255) (xy 6.842929 -314.029564)
			(xy 6.854982 -314.113399) (xy 6.859013 -314.198) (xy 6.854982 -314.282601) (xy 6.842929 -314.366436)
			(xy 6.822961 -314.448745) (xy 6.795259 -314.528784) (xy 6.760075 -314.605827) (xy 6.717726 -314.679177)
			(xy 6.668597 -314.748169) (xy 6.613132 -314.812179) (xy 6.551834 -314.870627) (xy 6.485258 -314.922983)
			(xy 6.414006 -314.968773) (xy 6.338725 -315.007584) (xy 6.260095 -315.039063) (xy 6.178828 -315.062924)
			(xy 6.095662 -315.078953) (xy 6.011348 -315.087004) (xy 5.969 -315.087508) (xy 5.939637 -315.087236)
			(xy 5.881042 -315.083294) (xy 5.851906 -315.079634) (xy 5.840134 -315.078733) (xy 5.817831 -315.086372)
			(xy 5.801281 -315.103162) (xy 5.797042 -315.114178) (xy 5.783043 -315.154574) (xy 5.748349 -315.232717)
			(xy 5.706319 -315.307172) (xy 5.657339 -315.377251) (xy 5.601862 -315.442308) (xy 5.5404 -315.501743)
			(xy 5.47352 -315.555007) (xy 5.401838 -315.601609) (xy 5.326016 -315.64112) (xy 5.246753 -315.673174)
			(xy 5.16478 -315.697477) (xy 5.080854 -315.713803) (xy 4.99575 -315.722002) (xy 4.953 -315.722508)
			(xy 4.910652 -315.722004) (xy 4.826338 -315.713953) (xy 4.743172 -315.697924) (xy 4.661905 -315.674063)
			(xy 4.583275 -315.642584) (xy 4.507994 -315.603773) (xy 4.436742 -315.557983) (xy 4.370166 -315.505627)
			(xy 4.308868 -315.447179) (xy 4.253403 -315.383169) (xy 4.204274 -315.314177) (xy 4.161925 -315.240827)
			(xy 4.126741 -315.163784) (xy 4.099039 -315.083745) (xy 4.079071 -315.001436) (xy 4.067018 -314.917601)
			(xy 4.062988 -314.833) (xy 3.683508 -314.833) (xy 3.683004 -314.875348) (xy 3.674953 -314.959662)
			(xy 3.658924 -315.042828) (xy 3.635063 -315.124095) (xy 3.603584 -315.202725) (xy 3.564773 -315.278006)
			(xy 3.518983 -315.349258) (xy 3.466627 -315.415834) (xy 3.408179 -315.477132) (xy 3.344169 -315.532597)
			(xy 3.275177 -315.581726) (xy 3.201827 -315.624075) (xy 3.124784 -315.659259) (xy 3.044745 -315.686961)
			(xy 2.962436 -315.706929) (xy 2.878601 -315.718982) (xy 2.794 -315.723013) (xy 2.709399 -315.718982)
			(xy 2.625564 -315.706929) (xy 2.543255 -315.686961) (xy 2.463216 -315.659259) (xy 2.386173 -315.624075)
			(xy 2.312823 -315.581726) (xy 2.243831 -315.532597) (xy 2.179821 -315.477132) (xy 2.121373 -315.415834)
			(xy 2.069017 -315.349258) (xy 2.023227 -315.278006) (xy 1.984416 -315.202725) (xy 1.952937 -315.124095)
			(xy 1.929076 -315.042828) (xy 1.913047 -314.959662) (xy 1.904996 -314.875348) (xy 1.904492 -314.833)
			(xy 1.904929 -314.793349) (xy 1.911991 -314.714363) (xy 1.926057 -314.636318) (xy 1.947015 -314.559836)
			(xy 1.9747 -314.485524) (xy 2.00889 -314.413972) (xy 2.049316 -314.345747) (xy 2.072132 -314.313316)
			(xy 2.077974 -314.305188) (xy 2.082546 -314.286392) (xy 2.069846 -314.196984) (xy 2.060194 -314.18022)
			(xy 2.05232 -314.174124) (xy 2.020196 -314.148325) (xy 1.960357 -314.091682) (xy 1.906013 -314.029747)
			(xy 1.857631 -313.963052) (xy 1.815624 -313.892168) (xy 1.780353 -313.817702) (xy 1.765808 -313.779154)
			(xy 1.761744 -313.76874) (xy 1.75387 -313.760866) (xy 1.746436 -313.75415) (xy 1.727936 -313.746514)
			(xy 1.707922 -313.746514) (xy 1.689422 -313.75415) (xy 1.681988 -313.760866) (xy 1.66624 -313.776614)
			(xy 1.659391 -313.784011) (xy 1.651656 -313.80261) (xy 1.651254 -313.812682) (xy 1.651254 -317.620904)
			(xy 1.652778 -317.67145) (xy 1.651254 -317.721996) (xy 1.651254 -322.700904) (xy 1.652778 -322.75145)
			(xy 1.651254 -322.801996) (xy 1.651254 -327.016821) (xy 20.13508 -327.016821) (xy 20.13508 -326.803055)
			(xy 20.143073 -326.589439) (xy 20.159048 -326.376271) (xy 20.182982 -326.163849) (xy 20.214842 -325.952471)
			(xy 20.254583 -325.742432) (xy 20.302151 -325.534026) (xy 20.357477 -325.327544) (xy 20.420486 -325.123275)
			(xy 20.491088 -324.921506) (xy 20.569186 -324.722517) (xy 20.654669 -324.526587) (xy 20.747418 -324.333991)
			(xy 20.847304 -324.144997) (xy 20.954187 -323.959871) (xy 21.067917 -323.77887) (xy 21.188336 -323.602249)
			(xy 21.315274 -323.430253) (xy 21.448555 -323.263124) (xy 21.587992 -323.101096) (xy 21.733389 -322.944395)
			(xy 21.884545 -322.793239) (xy 22.041246 -322.647842) (xy 22.203274 -322.508405) (xy 22.370403 -322.375124)
			(xy 22.542399 -322.248186) (xy 22.71902 -322.127767) (xy 22.900021 -322.014037) (xy 23.085147 -321.907154)
			(xy 23.274141 -321.807268) (xy 23.466737 -321.714519) (xy 23.662667 -321.629036) (xy 23.861656 -321.550938)
			(xy 24.063425 -321.480336) (xy 24.267694 -321.417327) (xy 24.474176 -321.362001) (xy 24.682582 -321.314433)
			(xy 24.892621 -321.274692) (xy 25.103999 -321.242832) (xy 25.316421 -321.218898) (xy 25.529589 -321.202923)
			(xy 25.743205 -321.19493) (xy 25.956971 -321.19493) (xy 26.170587 -321.202923) (xy 26.383755 -321.218898)
			(xy 26.596177 -321.242832) (xy 26.807555 -321.274692) (xy 27.017594 -321.314433) (xy 27.226 -321.362001)
			(xy 27.432482 -321.417327) (xy 27.636751 -321.480336) (xy 27.83852 -321.550938) (xy 28.037509 -321.629036)
			(xy 28.233439 -321.714519) (xy 28.426035 -321.807268) (xy 28.615029 -321.907154) (xy 28.800155 -322.014037)
			(xy 28.981156 -322.127767) (xy 29.157777 -322.248186) (xy 29.329773 -322.375124) (xy 29.496902 -322.508405)
			(xy 29.65893 -322.647842) (xy 29.815631 -322.793239) (xy 29.966787 -322.944395) (xy 30.112184 -323.101096)
			(xy 30.251621 -323.263124) (xy 30.384902 -323.430253) (xy 30.51184 -323.602249) (xy 30.632259 -323.77887)
			(xy 30.745989 -323.959871) (xy 30.852872 -324.144997) (xy 30.952758 -324.333991) (xy 31.045507 -324.526587)
			(xy 31.13099 -324.722517) (xy 31.209088 -324.921506) (xy 31.27969 -325.123275) (xy 31.342699 -325.327544)
			(xy 31.398025 -325.534026) (xy 31.445593 -325.742432) (xy 31.485334 -325.952471) (xy 31.517194 -326.163849)
			(xy 31.541128 -326.376271) (xy 31.557103 -326.589439) (xy 31.565096 -326.803055) (xy 31.565596 -326.909938)
			(xy 31.565096 -327.016821) (xy 31.557103 -327.230437) (xy 31.541128 -327.443605) (xy 31.517194 -327.656027)
			(xy 31.485334 -327.867405) (xy 31.445593 -328.077444) (xy 31.398025 -328.28585) (xy 31.342699 -328.492332)
			(xy 31.27969 -328.696601) (xy 31.209088 -328.89837) (xy 31.13099 -329.097359) (xy 31.045507 -329.293289)
			(xy 30.952758 -329.485885) (xy 30.852872 -329.674879) (xy 30.745989 -329.860005) (xy 30.632259 -330.041006)
			(xy 30.51184 -330.217627) (xy 30.384902 -330.389623) (xy 30.251621 -330.556752) (xy 30.112184 -330.71878)
			(xy 29.966787 -330.875481) (xy 29.815631 -331.026637) (xy 29.65893 -331.172034) (xy 29.496902 -331.311471)
			(xy 29.329773 -331.444752) (xy 29.157777 -331.57169) (xy 28.981156 -331.692109) (xy 28.800155 -331.805839)
			(xy 28.615029 -331.912722) (xy 28.426035 -332.012608) (xy 28.233439 -332.105357) (xy 28.037509 -332.19084)
			(xy 27.83852 -332.268938) (xy 27.636751 -332.33954) (xy 27.432482 -332.402549) (xy 27.226 -332.457875)
			(xy 27.017594 -332.505443) (xy 26.807555 -332.545184) (xy 26.596177 -332.577044) (xy 26.383755 -332.600978)
			(xy 26.170587 -332.616953) (xy 25.956971 -332.624946) (xy 25.743205 -332.624946) (xy 25.529589 -332.616953)
			(xy 25.316421 -332.600978) (xy 25.103999 -332.577044) (xy 24.892621 -332.545184) (xy 24.682582 -332.505443)
			(xy 24.474176 -332.457875) (xy 24.267694 -332.402549) (xy 24.063425 -332.33954) (xy 23.861656 -332.268938)
			(xy 23.662667 -332.19084) (xy 23.466737 -332.105357) (xy 23.274141 -332.012608) (xy 23.085147 -331.912722)
			(xy 22.900021 -331.805839) (xy 22.71902 -331.692109) (xy 22.542399 -331.57169) (xy 22.370403 -331.444752)
			(xy 22.203274 -331.311471) (xy 22.041246 -331.172034) (xy 21.884545 -331.026637) (xy 21.733389 -330.875481)
			(xy 21.587992 -330.71878) (xy 21.448555 -330.556752) (xy 21.315274 -330.389623) (xy 21.188336 -330.217627)
			(xy 21.067917 -330.041006) (xy 20.954187 -329.860005) (xy 20.847304 -329.674879) (xy 20.747418 -329.485885)
			(xy 20.654669 -329.293289) (xy 20.569186 -329.097359) (xy 20.491088 -328.89837) (xy 20.420486 -328.696601)
			(xy 20.357477 -328.492332) (xy 20.302151 -328.28585) (xy 20.254583 -328.077444) (xy 20.214842 -327.867405)
			(xy 20.182982 -327.656027) (xy 20.159048 -327.443605) (xy 20.143073 -327.230437) (xy 20.13508 -327.016821)
			(xy 1.651254 -327.016821) (xy 1.651254 -327.780904) (xy 1.652778 -327.83145) (xy 1.651254 -327.881996)
			(xy 1.651254 -332.04257) (xy 2.984235 -332.04257) (xy 2.984235 -331.91343) (xy 2.992185 -331.784535)
			(xy 3.008055 -331.656375) (xy 3.031784 -331.529434) (xy 3.063283 -331.404195) (xy 3.102432 -331.281132)
			(xy 3.149083 -331.160713) (xy 3.203058 -331.043394) (xy 3.264153 -330.92962) (xy 3.332136 -330.819823)
			(xy 3.40675 -330.71442) (xy 3.487711 -330.61381) (xy 3.574711 -330.518375) (xy 3.667422 -330.428476)
			(xy 3.765492 -330.344455) (xy 3.868547 -330.266631) (xy 3.976198 -330.195299) (xy 4.088037 -330.130729)
			(xy 4.203638 -330.073167) (xy 4.322563 -330.02283) (xy 4.444362 -329.97991) (xy 4.568572 -329.944569)
			(xy 4.694721 -329.916942) (xy 4.822333 -329.897133) (xy 4.950922 -329.885217) (xy 5.08 -329.881241)
			(xy 5.209078 -329.885217) (xy 5.337667 -329.897133) (xy 5.465279 -329.916942) (xy 5.591428 -329.944569)
			(xy 5.715638 -329.97991) (xy 5.837437 -330.02283) (xy 5.956362 -330.073167) (xy 6.071963 -330.130729)
			(xy 6.183802 -330.195299) (xy 6.291453 -330.266631) (xy 6.394508 -330.344455) (xy 6.492578 -330.428476)
			(xy 6.585289 -330.518375) (xy 6.672289 -330.61381) (xy 6.75325 -330.71442) (xy 6.827864 -330.819823)
			(xy 6.895847 -330.92962) (xy 6.956942 -331.043394) (xy 7.010917 -331.160713) (xy 7.057568 -331.281132)
			(xy 7.096717 -331.404195) (xy 7.128216 -331.529434) (xy 7.151945 -331.656375) (xy 7.167815 -331.784535)
			(xy 7.175765 -331.91343) (xy 7.176262 -331.978) (xy 7.175765 -332.04257) (xy 7.167815 -332.171465)
			(xy 7.151945 -332.299625) (xy 7.128216 -332.426566) (xy 7.096717 -332.551805) (xy 7.057568 -332.674868)
			(xy 7.010917 -332.795287) (xy 6.956942 -332.912606) (xy 6.895847 -333.02638) (xy 6.827864 -333.136177)
			(xy 6.75325 -333.24158) (xy 6.672289 -333.34219) (xy 6.585289 -333.437625) (xy 6.492578 -333.527524)
			(xy 6.394508 -333.611545) (xy 6.291453 -333.689369) (xy 6.183802 -333.760701) (xy 6.071963 -333.825271)
			(xy 5.956362 -333.882833) (xy 5.837437 -333.93317) (xy 5.715638 -333.97609) (xy 5.591428 -334.011431)
			(xy 5.465279 -334.039058) (xy 5.337667 -334.058867) (xy 5.209078 -334.070783) (xy 5.08 -334.07476)
			(xy 4.950922 -334.070783) (xy 4.822333 -334.058867) (xy 4.694721 -334.039058) (xy 4.568572 -334.011431)
			(xy 4.444362 -333.97609) (xy 4.322563 -333.93317) (xy 4.203638 -333.882833) (xy 4.088037 -333.825271)
			(xy 3.976198 -333.760701) (xy 3.868547 -333.689369) (xy 3.765492 -333.611545) (xy 3.667422 -333.527524)
			(xy 3.574711 -333.437625) (xy 3.487711 -333.34219) (xy 3.40675 -333.24158) (xy 3.332136 -333.136177)
			(xy 3.264153 -333.02638) (xy 3.203058 -332.912606) (xy 3.149083 -332.795287) (xy 3.102432 -332.674868)
			(xy 3.063283 -332.551805) (xy 3.031784 -332.426566) (xy 3.008055 -332.299625) (xy 2.992185 -332.171465)
			(xy 2.984235 -332.04257) (xy 1.651254 -332.04257) (xy 1.651254 -332.860904) (xy 1.652778 -332.91145)
			(xy 1.651254 -332.961996) (xy 1.651254 -333.000096) (xy 1.651741 -333.068423) (xy 1.659687 -333.204846)
			(xy 1.675552 -333.340576) (xy 1.699281 -333.475155) (xy 1.730796 -333.608125) (xy 1.769989 -333.739039)
			(xy 1.816727 -333.867452) (xy 1.870853 -333.99293) (xy 1.932183 -334.115049) (xy 2.000511 -334.233395)
			(xy 2.075603 -334.347568) (xy 2.157208 -334.457181) (xy 2.245047 -334.561864) (xy 2.338825 -334.661263)
			(xy 2.438224 -334.755041) (xy 2.542907 -334.84288) (xy 2.65252 -334.924485) (xy 2.766693 -334.999577)
			(xy 2.885039 -335.067905) (xy 3.007158 -335.129235) (xy 3.132636 -335.183361) (xy 3.261049 -335.230099)
			(xy 3.391963 -335.269292) (xy 3.524933 -335.300807) (xy 3.659512 -335.324536) (xy 3.795242 -335.340401)
			(xy 3.931665 -335.348347) (xy 3.999992 -335.348834) (xy 4.032504 -335.348834)
		)
		(stroke
			(width 0)
			(type solid)
		)
		(fill yes)
		(layer "In3.Cu")
		(net "P52V_HSC")
	)
	(gr_poly
		(pts
			(xy -3.999992 -336.492088) (xy -3.944185 -336.491566) (xy -3.832883 -336.483225) (xy -3.722516 -336.46659)
			(xy -3.6137 -336.441753) (xy -3.507045 -336.408854) (xy -3.403146 -336.368077) (xy -3.302586 -336.31965)
			(xy -3.205925 -336.263842) (xy -3.113705 -336.200968) (xy -3.026442 -336.131378) (xy -2.944623 -336.055461)
			(xy -2.868706 -335.973642) (xy -2.799116 -335.886379) (xy -2.736242 -335.794159) (xy -2.680434 -335.697498)
			(xy -2.632007 -335.596938) (xy -2.59123 -335.493039) (xy -2.558331 -335.386384) (xy -2.533494 -335.277568)
			(xy -2.516859 -335.167201) (xy -2.508518 -335.055899) (xy -2.507996 -335.000092) (xy -2.507996 -154.399996)
			(xy -2.508518 -154.344189) (xy -2.516859 -154.232887) (xy -2.533494 -154.12252) (xy -2.558331 -154.013704)
			(xy -2.59123 -153.907049) (xy -2.632007 -153.80315) (xy -2.680434 -153.70259) (xy -2.736242 -153.605929)
			(xy -2.799116 -153.513709) (xy -2.868706 -153.426446) (xy -2.944623 -153.344627) (xy -3.026442 -153.26871)
			(xy -3.113705 -153.19912) (xy -3.205925 -153.136246) (xy -3.302586 -153.080438) (xy -3.403146 -153.032011)
			(xy -3.507045 -152.991234) (xy -3.6137 -152.958335) (xy -3.722516 -152.933498) (xy -3.832883 -152.916863)
			(xy -3.944185 -152.908522) (xy -3.999992 -152.908) (xy -17.78 -152.908) (xy -17.835807 -152.908522)
			(xy -17.947109 -152.916863) (xy -18.057476 -152.933498) (xy -18.166292 -152.958335) (xy -18.272947 -152.991234)
			(xy -18.376846 -153.032011) (xy -18.477406 -153.080438) (xy -18.574067 -153.136246) (xy -18.666287 -153.19912)
			(xy -18.75355 -153.26871) (xy -18.835369 -153.344627) (xy -18.911286 -153.426446) (xy -18.980876 -153.513709)
			(xy -19.04375 -153.605929) (xy -19.099558 -153.70259) (xy -19.147985 -153.80315) (xy -19.188762 -153.907049)
			(xy -19.221661 -154.013704) (xy -19.246498 -154.12252) (xy -19.263133 -154.232887) (xy -19.271474 -154.344189)
			(xy -19.271996 -154.399996) (xy -19.271996 -157.46456) (xy -16.875771 -157.46456) (xy -16.875771 -157.33542)
			(xy -16.867821 -157.206525) (xy -16.851951 -157.078365) (xy -16.828222 -156.951424) (xy -16.796723 -156.826185)
			(xy -16.757574 -156.703122) (xy -16.710923 -156.582703) (xy -16.656948 -156.465384) (xy -16.595853 -156.35161)
			(xy -16.52787 -156.241813) (xy -16.453256 -156.13641) (xy -16.372295 -156.0358) (xy -16.285295 -155.940365)
			(xy -16.192584 -155.850466) (xy -16.094514 -155.766445) (xy -15.991459 -155.688621) (xy -15.883808 -155.617289)
			(xy -15.771969 -155.552719) (xy -15.656368 -155.495157) (xy -15.537443 -155.44482) (xy -15.415644 -155.4019)
			(xy -15.291434 -155.366559) (xy -15.165285 -155.338932) (xy -15.037673 -155.319123) (xy -14.909084 -155.307207)
			(xy -14.780006 -155.303231) (xy -14.650928 -155.307207) (xy -14.522339 -155.319123) (xy -14.394727 -155.338932)
			(xy -14.268578 -155.366559) (xy -14.144368 -155.4019) (xy -14.022569 -155.44482) (xy -13.903644 -155.495157)
			(xy -13.788043 -155.552719) (xy -13.676204 -155.617289) (xy -13.568553 -155.688621) (xy -13.465498 -155.766445)
			(xy -13.367428 -155.850466) (xy -13.274717 -155.940365) (xy -13.187717 -156.0358) (xy -13.106756 -156.13641)
			(xy -13.032142 -156.241813) (xy -12.964159 -156.35161) (xy -12.903064 -156.465384) (xy -12.849089 -156.582703)
			(xy -12.802438 -156.703122) (xy -12.763289 -156.826185) (xy -12.73179 -156.951424) (xy -12.708061 -157.078365)
			(xy -12.692191 -157.206525) (xy -12.684241 -157.33542) (xy -12.683744 -157.39999) (xy -12.684241 -157.46456)
			(xy -12.692191 -157.593455) (xy -12.708061 -157.721615) (xy -12.73179 -157.848556) (xy -12.763289 -157.973795)
			(xy -12.802438 -158.096858) (xy -12.849089 -158.217277) (xy -12.903064 -158.334596) (xy -12.964159 -158.44837)
			(xy -13.032142 -158.558167) (xy -13.106756 -158.66357) (xy -13.187717 -158.76418) (xy -13.274717 -158.859615)
			(xy -13.367428 -158.949514) (xy -13.465498 -159.033535) (xy -13.568553 -159.111359) (xy -13.676204 -159.182691)
			(xy -13.788043 -159.247261) (xy -13.903644 -159.304823) (xy -14.022569 -159.35516) (xy -14.144368 -159.39808)
			(xy -14.268578 -159.433421) (xy -14.394727 -159.461048) (xy -14.522339 -159.480857) (xy -14.650928 -159.492773)
			(xy -14.780006 -159.49675) (xy -14.909084 -159.492773) (xy -15.037673 -159.480857) (xy -15.165285 -159.461048)
			(xy -15.291434 -159.433421) (xy -15.415644 -159.39808) (xy -15.537443 -159.35516) (xy -15.656368 -159.304823)
			(xy -15.771969 -159.247261) (xy -15.883808 -159.182691) (xy -15.991459 -159.111359) (xy -16.094514 -159.033535)
			(xy -16.192584 -158.949514) (xy -16.285295 -158.859615) (xy -16.372295 -158.76418) (xy -16.453256 -158.66357)
			(xy -16.52787 -158.558167) (xy -16.595853 -158.44837) (xy -16.656948 -158.334596) (xy -16.710923 -158.217277)
			(xy -16.757574 -158.096858) (xy -16.796723 -157.973795) (xy -16.828222 -157.848556) (xy -16.851951 -157.721615)
			(xy -16.867821 -157.593455) (xy -16.875771 -157.46456) (xy -19.271996 -157.46456) (xy -19.271996 -332.064668)
			(xy -16.875771 -332.064668) (xy -16.875771 -331.935528) (xy -16.867821 -331.806633) (xy -16.851951 -331.678473)
			(xy -16.828222 -331.551532) (xy -16.796723 -331.426293) (xy -16.757574 -331.30323) (xy -16.710923 -331.182811)
			(xy -16.656948 -331.065492) (xy -16.595853 -330.951718) (xy -16.52787 -330.841921) (xy -16.453256 -330.736518)
			(xy -16.372295 -330.635908) (xy -16.285295 -330.540473) (xy -16.192584 -330.450574) (xy -16.094514 -330.366553)
			(xy -15.991459 -330.288729) (xy -15.883808 -330.217397) (xy -15.771969 -330.152827) (xy -15.656368 -330.095265)
			(xy -15.537443 -330.044928) (xy -15.415644 -330.002008) (xy -15.291434 -329.966667) (xy -15.165285 -329.93904)
			(xy -15.037673 -329.919231) (xy -14.909084 -329.907315) (xy -14.780006 -329.903339) (xy -14.650928 -329.907315)
			(xy -14.522339 -329.919231) (xy -14.394727 -329.93904) (xy -14.268578 -329.966667) (xy -14.144368 -330.002008)
			(xy -14.022569 -330.044928) (xy -13.903644 -330.095265) (xy -13.788043 -330.152827) (xy -13.676204 -330.217397)
			(xy -13.568553 -330.288729) (xy -13.465498 -330.366553) (xy -13.367428 -330.450574) (xy -13.274717 -330.540473)
			(xy -13.187717 -330.635908) (xy -13.106756 -330.736518) (xy -13.032142 -330.841921) (xy -12.964159 -330.951718)
			(xy -12.903064 -331.065492) (xy -12.849089 -331.182811) (xy -12.802438 -331.30323) (xy -12.763289 -331.426293)
			(xy -12.73179 -331.551532) (xy -12.708061 -331.678473) (xy -12.692191 -331.806633) (xy -12.684241 -331.935528)
			(xy -12.683744 -332.000098) (xy -12.684241 -332.064668) (xy -12.692191 -332.193563) (xy -12.708061 -332.321723)
			(xy -12.73179 -332.448664) (xy -12.763289 -332.573903) (xy -12.802438 -332.696966) (xy -12.849089 -332.817385)
			(xy -12.903064 -332.934704) (xy -12.964159 -333.048478) (xy -13.032142 -333.158275) (xy -13.106756 -333.263678)
			(xy -13.187717 -333.364288) (xy -13.274717 -333.459723) (xy -13.367428 -333.549622) (xy -13.465498 -333.633643)
			(xy -13.568553 -333.711467) (xy -13.676204 -333.782799) (xy -13.788043 -333.847369) (xy -13.903644 -333.904931)
			(xy -14.022569 -333.955268) (xy -14.144368 -333.998188) (xy -14.268578 -334.033529) (xy -14.394727 -334.061156)
			(xy -14.522339 -334.080965) (xy -14.650928 -334.092881) (xy -14.780006 -334.096858) (xy -14.909084 -334.092881)
			(xy -15.037673 -334.080965) (xy -15.165285 -334.061156) (xy -15.291434 -334.033529) (xy -15.415644 -333.998188)
			(xy -15.537443 -333.955268) (xy -15.656368 -333.904931) (xy -15.771969 -333.847369) (xy -15.883808 -333.782799)
			(xy -15.991459 -333.711467) (xy -16.094514 -333.633643) (xy -16.192584 -333.549622) (xy -16.285295 -333.459723)
			(xy -16.372295 -333.364288) (xy -16.453256 -333.263678) (xy -16.52787 -333.158275) (xy -16.595853 -333.048478)
			(xy -16.656948 -332.934704) (xy -16.710923 -332.817385) (xy -16.757574 -332.696966) (xy -16.796723 -332.573903)
			(xy -16.828222 -332.448664) (xy -16.851951 -332.321723) (xy -16.867821 -332.193563) (xy -16.875771 -332.064668)
			(xy -19.271996 -332.064668) (xy -19.271996 -335.000092) (xy -19.271474 -335.055899) (xy -19.263133 -335.167201)
			(xy -19.246498 -335.277568) (xy -19.221661 -335.386384) (xy -19.188762 -335.493039) (xy -19.147985 -335.596938)
			(xy -19.099558 -335.697498) (xy -19.04375 -335.794159) (xy -18.980876 -335.886379) (xy -18.911286 -335.973642)
			(xy -18.835369 -336.055461) (xy -18.75355 -336.131378) (xy -18.666287 -336.200968) (xy -18.574067 -336.263842)
			(xy -18.477406 -336.31965) (xy -18.376846 -336.368077) (xy -18.272947 -336.408854) (xy -18.166292 -336.441753)
			(xy -18.057476 -336.46659) (xy -17.947109 -336.483225) (xy -17.835807 -336.491566) (xy -17.78 -336.492088)
		)
		(stroke
			(width 0)
			(type solid)
		)
		(fill yes)
		(layer "In4.Cu")
		(net "GND2")
	)
	(gr_poly
		(pts
			(xy 47.69993 -336.491072) (xy 47.783018 -336.490577) (xy 47.949007 -336.482669) (xy 48.114431 -336.466871)
			(xy 48.278917 -336.44322) (xy 48.44209 -336.41177) (xy 48.603583 -336.372591) (xy 48.763028 -336.325772)
			(xy 48.920065 -336.27142) (xy 49.074338 -336.209657) (xy 49.225497 -336.140624) (xy 49.373201 -336.064476)
			(xy 49.517114 -335.981387) (xy 49.65691 -335.891544) (xy 49.792273 -335.795151) (xy 49.922897 -335.692427)
			(xy 50.048484 -335.583603) (xy 50.168752 -335.468928) (xy 50.283426 -335.348659) (xy 50.392248 -335.223071)
			(xy 50.494972 -335.092446) (xy 50.591363 -334.957082) (xy 50.681205 -334.817285) (xy 50.764293 -334.673371)
			(xy 50.840439 -334.525667) (xy 50.909471 -334.374507) (xy 50.971232 -334.220233) (xy 51.025583 -334.063196)
			(xy 51.0724 -333.90375) (xy 51.111577 -333.742257) (xy 51.143026 -333.579083) (xy 51.166675 -333.414598)
			(xy 51.182471 -333.249173) (xy 51.190378 -333.083184) (xy 51.190906 -333.000096) (xy 51.190906 -3.999992)
			(xy 51.190412 -3.916903) (xy 51.182504 -3.750913) (xy 51.166708 -3.585487) (xy 51.143058 -3.421001)
			(xy 51.111608 -3.257825) (xy 51.07243 -3.096332) (xy 51.025612 -2.936885) (xy 50.971261 -2.779846)
			(xy 50.909499 -2.625572) (xy 50.840466 -2.474411) (xy 50.764319 -2.326706) (xy 50.68123 -2.182791)
			(xy 50.591387 -2.042993) (xy 50.494995 -1.907628) (xy 50.39227 -1.777003) (xy 50.283447 -1.651413)
			(xy 50.168771 -1.531144) (xy 50.048503 -1.416468) (xy 49.922914 -1.307644) (xy 49.79229 -1.204919)
			(xy 49.656925 -1.108525) (xy 49.517128 -1.018682) (xy 49.373214 -0.935592) (xy 49.225509 -0.859444)
			(xy 49.074349 -0.79041) (xy 48.920074 -0.728647) (xy 48.763036 -0.674294) (xy 48.60359 -0.627476)
			(xy 48.442096 -0.588297) (xy 48.278921 -0.556846) (xy 48.114435 -0.533195) (xy 47.949009 -0.517397)
			(xy 47.783019 -0.509489) (xy 47.69993 -0.509016) (xy 36.971986 -0.509016) (xy 36.961917 -0.509442)
			(xy 36.943318 -0.517162) (xy 36.935918 -0.524002) (xy 35.763962 -1.695958) (xy 35.757118 -1.703357)
			(xy 35.749395 -1.721956) (xy 35.748976 -1.732026) (xy 35.748976 -4.50957) (xy 43.243235 -4.50957)
			(xy 43.243235 -4.38043) (xy 43.251185 -4.251535) (xy 43.267055 -4.123375) (xy 43.290784 -3.996434)
			(xy 43.322283 -3.871195) (xy 43.361432 -3.748132) (xy 43.408083 -3.627713) (xy 43.462058 -3.510394)
			(xy 43.523153 -3.39662) (xy 43.591136 -3.286823) (xy 43.66575 -3.18142) (xy 43.746711 -3.08081) (xy 43.833711 -2.985375)
			(xy 43.926422 -2.895476) (xy 44.024492 -2.811455) (xy 44.127547 -2.733631) (xy 44.235198 -2.662299)
			(xy 44.347037 -2.597729) (xy 44.462638 -2.540167) (xy 44.581563 -2.48983) (xy 44.703362 -2.44691)
			(xy 44.827572 -2.411569) (xy 44.953721 -2.383942) (xy 45.081333 -2.364133) (xy 45.209922 -2.352217)
			(xy 45.339 -2.348241) (xy 45.468078 -2.352217) (xy 45.596667 -2.364133) (xy 45.724279 -2.383942)
			(xy 45.850428 -2.411569) (xy 45.974638 -2.44691) (xy 46.096437 -2.48983) (xy 46.215362 -2.540167)
			(xy 46.330963 -2.597729) (xy 46.442802 -2.662299) (xy 46.550453 -2.733631) (xy 46.653508 -2.811455)
			(xy 46.751578 -2.895476) (xy 46.844289 -2.985375) (xy 46.931289 -3.08081) (xy 47.01225 -3.18142)
			(xy 47.086864 -3.286823) (xy 47.154847 -3.39662) (xy 47.215942 -3.510394) (xy 47.269917 -3.627713)
			(xy 47.316568 -3.748132) (xy 47.355717 -3.871195) (xy 47.387216 -3.996434) (xy 47.410945 -4.123375)
			(xy 47.426815 -4.251535) (xy 47.434765 -4.38043) (xy 47.435262 -4.445) (xy 47.434765 -4.50957) (xy 47.426815 -4.638465)
			(xy 47.410945 -4.766625) (xy 47.387216 -4.893566) (xy 47.355717 -5.018805) (xy 47.316568 -5.141868)
			(xy 47.269917 -5.262287) (xy 47.215942 -5.379606) (xy 47.154847 -5.49338) (xy 47.086864 -5.603177)
			(xy 47.01225 -5.70858) (xy 46.931289 -5.80919) (xy 46.844289 -5.904625) (xy 46.751578 -5.994524)
			(xy 46.653508 -6.078545) (xy 46.550453 -6.156369) (xy 46.442802 -6.227701) (xy 46.330963 -6.292271)
			(xy 46.215362 -6.349833) (xy 46.096437 -6.40017) (xy 45.974638 -6.44309) (xy 45.850428 -6.478431)
			(xy 45.724279 -6.506058) (xy 45.596667 -6.525867) (xy 45.468078 -6.537783) (xy 45.339 -6.54176) (xy 45.209922 -6.537783)
			(xy 45.081333 -6.525867) (xy 44.953721 -6.506058) (xy 44.827572 -6.478431) (xy 44.703362 -6.44309)
			(xy 44.581563 -6.40017) (xy 44.462638 -6.349833) (xy 44.347037 -6.292271) (xy 44.235198 -6.227701)
			(xy 44.127547 -6.156369) (xy 44.024492 -6.078545) (xy 43.926422 -5.994524) (xy 43.833711 -5.904625)
			(xy 43.746711 -5.80919) (xy 43.66575 -5.70858) (xy 43.591136 -5.603177) (xy 43.523153 -5.49338) (xy 43.462058 -5.379606)
			(xy 43.408083 -5.262287) (xy 43.361432 -5.141868) (xy 43.322283 -5.018805) (xy 43.290784 -4.893566)
			(xy 43.267055 -4.766625) (xy 43.251185 -4.638465) (xy 43.243235 -4.50957) (xy 35.748976 -4.50957)
			(xy 35.748976 -10.999978) (xy 35.748474 -11.058341) (xy 35.7405 -11.174794) (xy 35.724598 -11.290431)
			(xy 35.700842 -11.404713) (xy 35.669343 -11.517108) (xy 35.630247 -11.627092) (xy 35.583738 -11.734151)
			(xy 35.530031 -11.837787) (xy 35.469378 -11.937517) (xy 35.40206 -12.032875) (xy 35.328392 -12.123417)
			(xy 35.248718 -12.208721) (xy 35.163408 -12.28839) (xy 35.07286 -12.362051) (xy 34.977497 -12.429361)
			(xy 34.877763 -12.490008) (xy 34.774123 -12.543707) (xy 34.66706 -12.590208) (xy 34.557073 -12.629295)
			(xy 34.444676 -12.660786) (xy 34.330392 -12.684533) (xy 34.214753 -12.700427) (xy 34.0983 -12.708392)
			(xy 33.981574 -12.708392) (xy 33.865121 -12.700427) (xy 33.749482 -12.684533) (xy 33.635198 -12.660786)
			(xy 33.522801 -12.629295) (xy 33.412814 -12.590208) (xy 33.305751 -12.543707) (xy 33.202111 -12.490008)
			(xy 33.102377 -12.429361) (xy 33.007014 -12.362051) (xy 32.916466 -12.28839) (xy 32.831156 -12.208721)
			(xy 32.751482 -12.123417) (xy 32.677814 -12.032875) (xy 32.610496 -11.937517) (xy 32.549843 -11.837787)
			(xy 32.496136 -11.734151) (xy 32.449627 -11.627092) (xy 32.410531 -11.517108) (xy 32.379032 -11.404713)
			(xy 32.355276 -11.290431) (xy 32.339374 -11.174794) (xy 32.3314 -11.058341) (xy 32.330898 -10.999978)
			(xy 32.330898 -8.20039) (xy 32.330408 -8.190384) (xy 32.322747 -8.171896) (xy 32.308594 -8.157747)
			(xy 32.290104 -8.15009) (xy 32.280098 -8.14959) (xy 28.029916 -8.14959) (xy 28.019892 -8.150007)
			(xy 28.001368 -8.157673) (xy 27.987188 -8.171846) (xy 27.979512 -8.190366) (xy 27.979116 -8.20039)
			(xy 27.979116 -9.148826) (xy 27.979678 -9.160453) (xy 27.989853 -9.181364) (xy 27.998674 -9.188958)
			(xy 28.071572 -9.2456) (xy 28.094432 -9.250426) (xy 28.105862 -9.247378) (xy 28.141979 -9.238548)
			(xy 28.215307 -9.226221) (xy 28.289409 -9.22006) (xy 28.326588 -9.219692) (xy 28.372984 -9.220276)
			(xy 28.465275 -9.229908) (xy 28.55606 -9.2491) (xy 28.644353 -9.277643) (xy 28.687014 -9.295892)
			(xy 28.696956 -9.299698) (xy 28.71822 -9.299698) (xy 28.728162 -9.295892) (xy 28.770827 -9.277654)
			(xy 28.85912 -9.249114) (xy 28.949904 -9.229917) (xy 29.042192 -9.220271) (xy 29.088588 -9.219692)
			(xy 29.129692 -9.220152) (xy 29.211548 -9.227736) (xy 29.292355 -9.24284) (xy 29.371425 -9.265336)
			(xy 29.448081 -9.295032) (xy 29.52167 -9.331674) (xy 29.591564 -9.37495) (xy 29.657167 -9.42449)
			(xy 29.717919 -9.479872) (xy 29.773302 -9.540624) (xy 29.822843 -9.606226) (xy 29.86612 -9.67612)
			(xy 29.902763 -9.749708) (xy 29.93246 -9.826364) (xy 29.954957 -9.905433) (xy 29.970063 -9.98624)
			(xy 29.977648 -10.068096) (xy 29.978096 -10.1092) (xy 29.977694 -10.147483) (xy 29.971139 -10.223769)
			(xy 29.958059 -10.29921) (xy 29.938551 -10.373249) (xy 29.926026 -10.409428) (xy 29.923376 -10.417865)
			(xy 29.923376 -10.435535) (xy 29.926026 -10.443972) (xy 29.938561 -10.480148) (xy 29.958088 -10.554185)
			(xy 29.97117 -10.629627) (xy 29.977709 -10.705916) (xy 29.978096 -10.7442) (xy 29.977694 -10.782483)
			(xy 29.971139 -10.858769) (xy 29.958059 -10.93421) (xy 29.938551 -11.008249) (xy 29.926026 -11.044428)
			(xy 29.923376 -11.052865) (xy 29.923376 -11.070535) (xy 29.926026 -11.078972) (xy 29.938561 -11.115148)
			(xy 29.958088 -11.189185) (xy 29.97117 -11.264627) (xy 29.977709 -11.340916) (xy 29.978096 -11.3792)
			(xy 29.977694 -11.417483) (xy 29.971139 -11.493769) (xy 29.958059 -11.56921) (xy 29.938551 -11.643249)
			(xy 29.926026 -11.679428) (xy 29.923376 -11.687865) (xy 29.923376 -11.705535) (xy 29.926026 -11.713972)
			(xy 29.938561 -11.750148) (xy 29.958088 -11.824185) (xy 29.97117 -11.899627) (xy 29.977709 -11.975916)
			(xy 29.978096 -12.0142) (xy 29.977694 -12.052483) (xy 29.971139 -12.128769) (xy 29.958059 -12.20421)
			(xy 29.938551 -12.278249) (xy 29.926026 -12.314428) (xy 29.923376 -12.322865) (xy 29.923376 -12.340535)
			(xy 29.926026 -12.348972) (xy 29.938561 -12.385148) (xy 29.958088 -12.459185) (xy 29.97117 -12.534627)
			(xy 29.977709 -12.610916) (xy 29.978096 -12.6492) (xy 29.977694 -12.687483) (xy 29.971139 -12.763769)
			(xy 29.958059 -12.83921) (xy 29.938551 -12.913249) (xy 29.926026 -12.949428) (xy 29.923376 -12.957865)
			(xy 29.923376 -12.975535) (xy 29.926026 -12.983972) (xy 29.938561 -13.020148) (xy 29.958088 -13.094185)
			(xy 29.97117 -13.169627) (xy 29.977709 -13.245916) (xy 29.978096 -13.2842) (xy 29.977636 -13.325303)
			(xy 29.970051 -13.407158) (xy 29.954945 -13.487964) (xy 29.932448 -13.567032) (xy 29.902752 -13.643687)
			(xy 29.866109 -13.717274) (xy 29.822833 -13.787167) (xy 29.773293 -13.852768) (xy 29.717911 -13.913519)
			(xy 29.657159 -13.9689) (xy 29.591557 -14.01844) (xy 29.521664 -14.061715) (xy 29.448076 -14.098357)
			(xy 29.371421 -14.128052) (xy 29.292353 -14.150548) (xy 29.211546 -14.165652) (xy 29.129691 -14.173236)
			(xy 29.088588 -14.173708) (xy 29.042192 -14.173123) (xy 28.949902 -14.163488) (xy 28.859118 -14.144294)
			(xy 28.770826 -14.115749) (xy 28.728162 -14.097508) (xy 28.71822 -14.093702) (xy 28.696956 -14.093702)
			(xy 28.687014 -14.097508) (xy 28.644349 -14.115745) (xy 28.556055 -14.144282) (xy 28.465272 -14.163477)
			(xy 28.372983 -14.173121) (xy 28.326588 -14.173708) (xy 28.285486 -14.173233) (xy 28.203632 -14.165647)
			(xy 28.122828 -14.150541) (xy 28.043762 -14.128044) (xy 27.967109 -14.098347) (xy 27.893523 -14.061705)
			(xy 27.823632 -14.01843) (xy 27.758032 -13.96889) (xy 27.697283 -13.913509) (xy 27.641902 -13.852759)
			(xy 27.592364 -13.787158) (xy 27.549089 -13.717266) (xy 27.512448 -13.64368) (xy 27.482752 -13.567027)
			(xy 27.460256 -13.48796) (xy 27.445151 -13.407156) (xy 27.437567 -13.325302) (xy 27.43708 -13.2842)
			(xy 27.437482 -13.245917) (xy 27.444037 -13.169631) (xy 27.457117 -13.09419) (xy 27.476624 -13.02015)
			(xy 27.48915 -12.983972) (xy 27.491801 -12.975535) (xy 27.491801 -12.957865) (xy 27.48915 -12.949428)
			(xy 27.476615 -12.913252) (xy 27.457089 -12.839215) (xy 27.444007 -12.763773) (xy 27.437468 -12.687484)
			(xy 27.43708 -12.6492) (xy 27.437482 -12.610917) (xy 27.444037 -12.534631) (xy 27.457117 -12.45919)
			(xy 27.476624 -12.38515) (xy 27.48915 -12.348972) (xy 27.491801 -12.340535) (xy 27.491801 -12.322865)
			(xy 27.48915 -12.314428) (xy 27.476615 -12.278252) (xy 27.457089 -12.204215) (xy 27.444007 -12.128773)
			(xy 27.437468 -12.052484) (xy 27.43708 -12.0142) (xy 27.437162 -11.996528) (xy 27.438561 -11.961211)
			(xy 27.439874 -11.943588) (xy 27.440636 -11.931142) (xy 27.431492 -11.909044) (xy 27.35072 -11.839448)
			(xy 27.327352 -11.833606) (xy 27.315414 -11.8364) (xy 27.267275 -11.846965) (xy 27.169368 -11.858292)
			(xy 27.120088 -11.859006) (xy 27.077912 -11.858505) (xy 26.993966 -11.850235) (xy 26.911236 -11.833778)
			(xy 26.830516 -11.80929) (xy 26.752586 -11.777009) (xy 26.678195 -11.737245) (xy 26.608059 -11.69038)
			(xy 26.542856 -11.636866) (xy 26.483211 -11.577219) (xy 26.4297 -11.512013) (xy 26.382838 -11.441876)
			(xy 26.343076 -11.367484) (xy 26.310798 -11.289552) (xy 26.286314 -11.208831) (xy 26.26986 -11.1261)
			(xy 26.261594 -11.042154) (xy 26.26106 -10.999978) (xy 26.26106 -8.20039) (xy 26.260638 -8.190373)
			(xy 26.252965 -8.171866) (xy 26.238792 -8.157707) (xy 26.220277 -8.150052) (xy 26.21026 -8.14959)
			(xy 19.419824 -8.14959) (xy 19.409799 -8.150005) (xy 19.391272 -8.157671) (xy 19.37709 -8.171843)
			(xy 19.369412 -8.190365) (xy 19.369024 -8.20039) (xy 19.369024 -10.999978) (xy 19.368522 -11.058341)
			(xy 19.360548 -11.174794) (xy 19.344646 -11.290431) (xy 19.32089 -11.404713) (xy 19.289391 -11.517108)
			(xy 19.250295 -11.627092) (xy 19.203786 -11.734151) (xy 19.150079 -11.837787) (xy 19.089426 -11.937517)
			(xy 19.022108 -12.032875) (xy 18.94844 -12.123417) (xy 18.868766 -12.208721) (xy 18.783456 -12.28839)
			(xy 18.692908 -12.362051) (xy 18.597545 -12.429361) (xy 18.497811 -12.490008) (xy 18.394171 -12.543707)
			(xy 18.287108 -12.590208) (xy 18.177121 -12.629295) (xy 18.064724 -12.660786) (xy 17.95044 -12.684533)
			(xy 17.834801 -12.700427) (xy 17.718348 -12.708392) (xy 17.601622 -12.708392) (xy 17.485169 -12.700427)
			(xy 17.36953 -12.684533) (xy 17.255246 -12.660786) (xy 17.142849 -12.629295) (xy 17.032862 -12.590208)
			(xy 16.925799 -12.543707) (xy 16.822159 -12.490008) (xy 16.722425 -12.429361) (xy 16.627062 -12.362051)
			(xy 16.536514 -12.28839) (xy 16.451204 -12.208721) (xy 16.37153 -12.123417) (xy 16.297862 -12.032875)
			(xy 16.230544 -11.937517) (xy 16.169891 -11.837787) (xy 16.116184 -11.734151) (xy 16.069675 -11.627092)
			(xy 16.030579 -11.517108) (xy 15.99908 -11.404713) (xy 15.975324 -11.290431) (xy 15.959422 -11.174794)
			(xy 15.951448 -11.058341) (xy 15.950946 -10.999978) (xy 15.950946 -1.732026) (xy 15.950508 -1.721963)
			(xy 15.942769 -1.703383) (xy 15.93596 -1.695958) (xy 14.764004 -0.524002) (xy 14.756606 -0.517155)
			(xy 14.738008 -0.509418) (xy 14.727936 -0.509016) (xy 3.999992 -0.509016) (xy 3.916903 -0.509503)
			(xy 3.750913 -0.51741) (xy 3.585487 -0.533206) (xy 3.421 -0.556855) (xy 3.257825 -0.588305) (xy 3.096331 -0.627483)
			(xy 2.936884 -0.674301) (xy 2.779845 -0.728652) (xy 2.625571 -0.790414) (xy 2.474409 -0.859447) (xy 2.326704 -0.935595)
			(xy 2.18279 -1.018684) (xy 2.042992 -1.108526) (xy 1.907627 -1.204919) (xy 1.777002 -1.307644) (xy 1.651413 -1.416467)
			(xy 1.531144 -1.531144) (xy 1.416467 -1.651413) (xy 1.307644 -1.777002) (xy 1.204919 -1.907627) (xy 1.108526 -2.042992)
			(xy 1.018684 -2.18279) (xy 0.935595 -2.326704) (xy 0.859447 -2.474409) (xy 0.790414 -2.625571) (xy 0.728652 -2.779845)
			(xy 0.674301 -2.936884) (xy 0.627483 -3.096331) (xy 0.588305 -3.257825) (xy 0.556855 -3.421) (xy 0.533206 -3.585487)
			(xy 0.51741 -3.750913) (xy 0.509503 -3.916903) (xy 0.509016 -3.999992) (xy 0.509016 -4.50957) (xy 9.080235 -4.50957)
			(xy 9.080235 -4.38043) (xy 9.088185 -4.251535) (xy 9.104055 -4.123375) (xy 9.127784 -3.996434) (xy 9.159283 -3.871195)
			(xy 9.198432 -3.748132) (xy 9.245083 -3.627713) (xy 9.299058 -3.510394) (xy 9.360153 -3.39662) (xy 9.428136 -3.286823)
			(xy 9.50275 -3.18142) (xy 9.583711 -3.08081) (xy 9.670711 -2.985375) (xy 9.763422 -2.895476) (xy 9.861492 -2.811455)
			(xy 9.964547 -2.733631) (xy 10.072198 -2.662299) (xy 10.184037 -2.597729) (xy 10.299638 -2.540167)
			(xy 10.418563 -2.48983) (xy 10.540362 -2.44691) (xy 10.664572 -2.411569) (xy 10.790721 -2.383942)
			(xy 10.918333 -2.364133) (xy 11.046922 -2.352217) (xy 11.176 -2.348241) (xy 11.305078 -2.352217)
			(xy 11.433667 -2.364133) (xy 11.561279 -2.383942) (xy 11.687428 -2.411569) (xy 11.811638 -2.44691)
			(xy 11.933437 -2.48983) (xy 12.052362 -2.540167) (xy 12.167963 -2.597729) (xy 12.279802 -2.662299)
			(xy 12.387453 -2.733631) (xy 12.490508 -2.811455) (xy 12.588578 -2.895476) (xy 12.681289 -2.985375)
			(xy 12.768289 -3.08081) (xy 12.84925 -3.18142) (xy 12.923864 -3.286823) (xy 12.991847 -3.39662) (xy 13.052942 -3.510394)
			(xy 13.106917 -3.627713) (xy 13.153568 -3.748132) (xy 13.192717 -3.871195) (xy 13.224216 -3.996434)
			(xy 13.247945 -4.123375) (xy 13.263815 -4.251535) (xy 13.271765 -4.38043) (xy 13.272262 -4.445) (xy 13.271765 -4.50957)
			(xy 13.263815 -4.638465) (xy 13.247945 -4.766625) (xy 13.224216 -4.893566) (xy 13.192717 -5.018805)
			(xy 13.153568 -5.141868) (xy 13.106917 -5.262287) (xy 13.052942 -5.379606) (xy 12.991847 -5.49338)
			(xy 12.923864 -5.603177) (xy 12.84925 -5.70858) (xy 12.768289 -5.80919) (xy 12.681289 -5.904625)
			(xy 12.588578 -5.994524) (xy 12.490508 -6.078545) (xy 12.387453 -6.156369) (xy 12.279802 -6.227701)
			(xy 12.167963 -6.292271) (xy 12.052362 -6.349833) (xy 11.933437 -6.40017) (xy 11.811638 -6.44309)
			(xy 11.687428 -6.478431) (xy 11.561279 -6.506058) (xy 11.433667 -6.525867) (xy 11.305078 -6.537783)
			(xy 11.176 -6.54176) (xy 11.046922 -6.537783) (xy 10.918333 -6.525867) (xy 10.790721 -6.506058) (xy 10.664572 -6.478431)
			(xy 10.540362 -6.44309) (xy 10.418563 -6.40017) (xy 10.299638 -6.349833) (xy 10.184037 -6.292271)
			(xy 10.072198 -6.227701) (xy 9.964547 -6.156369) (xy 9.861492 -6.078545) (xy 9.763422 -5.994524)
			(xy 9.670711 -5.904625) (xy 9.583711 -5.80919) (xy 9.50275 -5.70858) (xy 9.428136 -5.603177) (xy 9.360153 -5.49338)
			(xy 9.299058 -5.379606) (xy 9.245083 -5.262287) (xy 9.198432 -5.141868) (xy 9.159283 -5.018805) (xy 9.127784 -4.893566)
			(xy 9.104055 -4.766625) (xy 9.088185 -4.638465) (xy 9.080235 -4.50957) (xy 0.509016 -4.50957) (xy 0.509016 -11.218361)
			(xy 1.015742 -11.218361) (xy 1.015742 -11.133639) (xy 1.023795 -11.049302) (xy 1.039829 -10.966112)
			(xy 1.063697 -10.884822) (xy 1.095185 -10.80617) (xy 1.134007 -10.730867) (xy 1.17981 -10.659595)
			(xy 1.232181 -10.592999) (xy 1.290646 -10.531684) (xy 1.354674 -10.476203) (xy 1.423686 -10.42706)
			(xy 1.497056 -10.3847) (xy 1.574121 -10.349505) (xy 1.654183 -10.321796) (xy 1.736516 -10.301822)
			(xy 1.820375 -10.289765) (xy 1.905 -10.285734) (xy 1.989625 -10.289765) (xy 2.073484 -10.301822)
			(xy 2.155817 -10.321796) (xy 2.235879 -10.349505) (xy 2.312944 -10.3847) (xy 2.386314 -10.42706)
			(xy 2.455326 -10.476203) (xy 2.494343 -10.510012) (xy 6.441451 -10.510012) (xy 6.445429 -10.410019)
			(xy 6.457339 -10.310659) (xy 6.477106 -10.212558) (xy 6.504605 -10.116339) (xy 6.539661 -10.022608)
			(xy 6.582053 -9.931959) (xy 6.631514 -9.844965) (xy 6.68773 -9.762175) (xy 6.750346 -9.684113) (xy 6.818965 -9.611273)
			(xy 6.893156 -9.544115) (xy 6.972447 -9.483063) (xy 7.056338 -9.428505) (xy 7.144299 -9.380784) (xy 7.235773 -9.340202)
			(xy 7.330182 -9.307016) (xy 7.426929 -9.281436) (xy 7.525403 -9.263623) (xy 7.624981 -9.253691) (xy 7.725033 -9.251701)
			(xy 7.824927 -9.257667) (xy 7.924031 -9.271551) (xy 8.021719 -9.293264) (xy 8.117373 -9.32267) (xy 8.210388 -9.359583)
			(xy 8.300176 -9.403769) (xy 8.38617 -9.45495) (xy 8.467826 -9.5128) (xy 8.544627 -9.576956) (xy 8.616089 -9.64701)
			(xy 8.681759 -9.722521) (xy 8.741221 -9.803011) (xy 8.794101 -9.88797) (xy 8.840064 -9.976862) (xy 8.878819 -10.069125)
			(xy 8.910121 -10.164175) (xy 8.933773 -10.261412) (xy 8.949624 -10.360221) (xy 8.957574 -10.459976)
			(xy 8.958072 -10.510012) (xy 8.957574 -10.560048) (xy 8.949624 -10.659803) (xy 8.933773 -10.758612)
			(xy 8.910121 -10.855849) (xy 8.878819 -10.950899) (xy 8.840064 -11.043162) (xy 8.794101 -11.132054)
			(xy 8.741221 -11.217013) (xy 8.681759 -11.297503) (xy 8.616089 -11.373014) (xy 8.544627 -11.443068)
			(xy 8.467826 -11.507224) (xy 8.38617 -11.565074) (xy 8.300176 -11.616255) (xy 8.210388 -11.660441)
			(xy 8.117373 -11.697354) (xy 8.021719 -11.72676) (xy 7.924031 -11.748473) (xy 7.824927 -11.762357)
			(xy 7.725033 -11.768323) (xy 7.624981 -11.766333) (xy 7.525403 -11.756401) (xy 7.426929 -11.738588)
			(xy 7.330182 -11.713008) (xy 7.235773 -11.679822) (xy 7.144299 -11.63924) (xy 7.056338 -11.591519)
			(xy 6.972447 -11.536961) (xy 6.893156 -11.475909) (xy 6.818965 -11.408751) (xy 6.750346 -11.335911)
			(xy 6.68773 -11.257849) (xy 6.631514 -11.175059) (xy 6.582053 -11.088065) (xy 6.539661 -10.997416)
			(xy 6.504605 -10.903685) (xy 6.477106 -10.807466) (xy 6.457339 -10.709365) (xy 6.445429 -10.610005)
			(xy 6.441451 -10.510012) (xy 2.494343 -10.510012) (xy 2.519354 -10.531684) (xy 2.577819 -10.592999)
			(xy 2.63019 -10.659595) (xy 2.675993 -10.730867) (xy 2.714815 -10.80617) (xy 2.746303 -10.884822)
			(xy 2.770171 -10.966112) (xy 2.786205 -11.049302) (xy 2.794258 -11.133639) (xy 2.794762 -11.176)
			(xy 2.794258 -11.218361) (xy 2.786205 -11.302698) (xy 2.770171 -11.385888) (xy 2.746303 -11.467178)
			(xy 2.714815 -11.54583) (xy 2.675993 -11.621133) (xy 2.63019 -11.692405) (xy 2.577819 -11.759001)
			(xy 2.519354 -11.820316) (xy 2.455326 -11.875797) (xy 2.386314 -11.92494) (xy 2.312944 -11.9673)
			(xy 2.235879 -12.002495) (xy 2.155817 -12.030204) (xy 2.073484 -12.050178) (xy 1.989625 -12.062235)
			(xy 1.905 -12.066267) (xy 1.820375 -12.062235) (xy 1.736516 -12.050178) (xy 1.654183 -12.030204)
			(xy 1.574121 -12.002495) (xy 1.497056 -11.9673) (xy 1.423686 -11.92494) (xy 1.354674 -11.875797)
			(xy 1.290646 -11.820316) (xy 1.232181 -11.759001) (xy 1.17981 -11.692405) (xy 1.134007 -11.621133)
			(xy 1.095185 -11.54583) (xy 1.063697 -11.467178) (xy 1.039829 -11.385888) (xy 1.023795 -11.302698)
			(xy 1.015742 -11.218361) (xy 0.509016 -11.218361) (xy 0.509016 -15.155361) (xy 30.479742 -15.155361)
			(xy 30.479742 -15.070639) (xy 30.487795 -14.986302) (xy 30.503829 -14.903112) (xy 30.527697 -14.821822)
			(xy 30.559185 -14.74317) (xy 30.598007 -14.667867) (xy 30.64381 -14.596595) (xy 30.696181 -14.529999)
			(xy 30.754646 -14.468684) (xy 30.818674 -14.413203) (xy 30.887686 -14.36406) (xy 30.961056 -14.3217)
			(xy 31.038121 -14.286505) (xy 31.118183 -14.258796) (xy 31.200516 -14.238822) (xy 31.284375 -14.226765)
			(xy 31.369 -14.222734) (xy 31.453625 -14.226765) (xy 31.537484 -14.238822) (xy 31.619817 -14.258796)
			(xy 31.699879 -14.286505) (xy 31.776944 -14.3217) (xy 31.850314 -14.36406) (xy 31.919326 -14.413203)
			(xy 31.983354 -14.468684) (xy 32.041819 -14.529999) (xy 32.09419 -14.596595) (xy 32.139993 -14.667867)
			(xy 32.178815 -14.74317) (xy 32.210303 -14.821822) (xy 32.234171 -14.903112) (xy 32.250205 -14.986302)
			(xy 32.258258 -15.070639) (xy 32.258762 -15.113) (xy 32.258258 -15.155361) (xy 32.250205 -15.239698)
			(xy 32.250147 -15.24) (xy 34.036 -15.24) (xy 34.036407 -15.20171) (xy 34.043019 -15.125417) (xy 34.056169 -15.049975)
			(xy 34.075759 -14.975944) (xy 34.088324 -14.939772) (xy 34.090976 -14.931335) (xy 34.090976 -14.913665)
			(xy 34.088324 -14.905228) (xy 34.075746 -14.869061) (xy 34.05616 -14.795028) (xy 34.043015 -14.719584)
			(xy 34.03641 -14.64329) (xy 34.036 -14.605) (xy 34.036474 -14.563921) (xy 34.044055 -14.482113) (xy 34.059151 -14.401354)
			(xy 34.081635 -14.322332) (xy 34.111314 -14.245722) (xy 34.147935 -14.172177) (xy 34.191185 -14.102325)
			(xy 34.240697 -14.036762) (xy 34.296046 -13.976046) (xy 34.356762 -13.920697) (xy 34.422325 -13.871185)
			(xy 34.492177 -13.827935) (xy 34.565722 -13.791314) (xy 34.642332 -13.761635) (xy 34.721354 -13.739151)
			(xy 34.802113 -13.724055) (xy 34.883921 -13.716474) (xy 34.925 -13.716) (xy 34.96329 -13.716407)
			(xy 35.039583 -13.723019) (xy 35.115025 -13.736169) (xy 35.189056 -13.755759) (xy 35.225228 -13.768324)
			(xy 35.233665 -13.770975) (xy 35.251335 -13.770975) (xy 35.259772 -13.768324) (xy 35.308032 -13.752322)
			(xy 35.316056 -13.749639) (xy 35.329831 -13.739831) (xy 35.339639 -13.726056) (xy 35.342322 -13.718032)
			(xy 35.354371 -13.679091) (xy 35.384539 -13.603362) (xy 35.421514 -13.530711) (xy 35.464983 -13.461751)
			(xy 35.514583 -13.397059) (xy 35.569896 -13.337179) (xy 35.630458 -13.282614) (xy 35.695761 -13.233823)
			(xy 35.765257 -13.191213) (xy 35.838361 -13.155145) (xy 35.91446 -13.125919) (xy 35.992914 -13.103783)
			(xy 36.073066 -13.088921) (xy 36.154241 -13.081459) (xy 36.195 -13.081) (xy 36.23329 -13.081407)
			(xy 36.309583 -13.088019) (xy 36.385025 -13.101169) (xy 36.459056 -13.120759) (xy 36.495228 -13.133324)
			(xy 36.503665 -13.135975) (xy 36.521335 -13.135975) (xy 36.529772 -13.133324) (xy 36.565939 -13.120746)
			(xy 36.639972 -13.10116) (xy 36.715416 -13.088015) (xy 36.79171 -13.08141) (xy 36.83 -13.081) (xy 36.86829 -13.081407)
			(xy 36.944583 -13.088019) (xy 37.020025 -13.101169) (xy 37.094056 -13.120759) (xy 37.130228 -13.133324)
			(xy 37.138665 -13.135975) (xy 37.156335 -13.135975) (xy 37.164772 -13.133324) (xy 37.200939 -13.120746)
			(xy 37.274972 -13.10116) (xy 37.350416 -13.088015) (xy 37.42671 -13.08141) (xy 37.465 -13.081) (xy 37.506079 -13.081474)
			(xy 37.587887 -13.089055) (xy 37.668646 -13.104151) (xy 37.747668 -13.126635) (xy 37.824278 -13.156314)
			(xy 37.897823 -13.192935) (xy 37.967675 -13.236185) (xy 38.033238 -13.285697) (xy 38.093954 -13.341046)
			(xy 38.149303 -13.401762) (xy 38.198815 -13.467325) (xy 38.242065 -13.537177) (xy 38.278686 -13.610722)
			(xy 38.308365 -13.687332) (xy 38.330849 -13.766354) (xy 38.345945 -13.847113) (xy 38.353526 -13.928921)
			(xy 38.354 -13.97) (xy 38.353593 -14.00829) (xy 38.346981 -14.084583) (xy 38.333831 -14.160025) (xy 38.314241 -14.234056)
			(xy 38.301676 -14.270228) (xy 38.299024 -14.278665) (xy 38.299024 -14.296335) (xy 38.301676 -14.304772)
			(xy 38.314254 -14.340939) (xy 38.33384 -14.414972) (xy 38.346985 -14.490416) (xy 38.35359 -14.56671)
			(xy 38.354 -14.605) (xy 38.353593 -14.64329) (xy 38.346981 -14.719583) (xy 38.333831 -14.795025)
			(xy 38.314241 -14.869056) (xy 38.301676 -14.905228) (xy 38.299024 -14.913665) (xy 38.299024 -14.931335)
			(xy 38.301676 -14.939772) (xy 38.314254 -14.975939) (xy 38.33384 -15.049972) (xy 38.346985 -15.125416)
			(xy 38.35359 -15.20171) (xy 38.354 -15.24) (xy 38.353526 -15.281079) (xy 38.345945 -15.362887) (xy 38.330849 -15.443646)
			(xy 38.308365 -15.522668) (xy 38.278686 -15.599278) (xy 38.242065 -15.672823) (xy 38.198815 -15.742675)
			(xy 38.149303 -15.808238) (xy 38.093954 -15.868954) (xy 38.033238 -15.924303) (xy 37.967675 -15.973815)
			(xy 37.897823 -16.017065) (xy 37.824278 -16.053686) (xy 37.747668 -16.083365) (xy 37.668646 -16.105849)
			(xy 37.587887 -16.120945) (xy 37.506079 -16.128526) (xy 37.465 -16.129) (xy 37.42671 -16.128593)
			(xy 37.350417 -16.121981) (xy 37.274975 -16.108831) (xy 37.200944 -16.089241) (xy 37.164772 -16.076676)
			(xy 37.156335 -16.074025) (xy 37.138665 -16.074025) (xy 37.130228 -16.076676) (xy 37.094061 -16.089254)
			(xy 37.020028 -16.10884) (xy 36.944584 -16.121985) (xy 36.86829 -16.12859) (xy 36.83 -16.129) (xy 36.79171 -16.128593)
			(xy 36.715417 -16.121981) (xy 36.639975 -16.108831) (xy 36.565944 -16.089241) (xy 36.529772 -16.076676)
			(xy 36.521335 -16.074025) (xy 36.503665 -16.074025) (xy 36.495228 -16.076676) (xy 36.459061 -16.089254)
			(xy 36.385028 -16.10884) (xy 36.309584 -16.121985) (xy 36.23329 -16.12859) (xy 36.195 -16.129) (xy 36.15671 -16.128593)
			(xy 36.080417 -16.121981) (xy 36.004975 -16.108831) (xy 35.930944 -16.089241) (xy 35.894772 -16.076676)
			(xy 35.886335 -16.074025) (xy 35.868665 -16.074025) (xy 35.860228 -16.076676) (xy 35.824061 -16.089254)
			(xy 35.750028 -16.10884) (xy 35.674584 -16.121985) (xy 35.59829 -16.12859) (xy 35.56 -16.129) (xy 35.52171 -16.128593)
			(xy 35.445417 -16.121981) (xy 35.369975 -16.108831) (xy 35.295944 -16.089241) (xy 35.259772 -16.076676)
			(xy 35.251335 -16.074025) (xy 35.233665 -16.074025) (xy 35.225228 -16.076676) (xy 35.189061 -16.089254)
			(xy 35.115028 -16.10884) (xy 35.039584 -16.121985) (xy 34.96329 -16.12859) (xy 34.925 -16.129) (xy 34.883921 -16.128526)
			(xy 34.802113 -16.120945) (xy 34.721354 -16.105849) (xy 34.642332 -16.083365) (xy 34.565722 -16.053686)
			(xy 34.492177 -16.017065) (xy 34.422325 -15.973815) (xy 34.356762 -15.924303) (xy 34.296046 -15.868954)
			(xy 34.240697 -15.808238) (xy 34.191185 -15.742675) (xy 34.147935 -15.672823) (xy 34.111314 -15.599278)
			(xy 34.081635 -15.522668) (xy 34.059151 -15.443646) (xy 34.044055 -15.362887) (xy 34.036474 -15.281079)
			(xy 34.036 -15.24) (xy 32.250147 -15.24) (xy 32.234171 -15.322888) (xy 32.210303 -15.404178) (xy 32.178815 -15.48283)
			(xy 32.139993 -15.558133) (xy 32.09419 -15.629405) (xy 32.041819 -15.696001) (xy 31.983354 -15.757316)
			(xy 31.919326 -15.812797) (xy 31.850314 -15.86194) (xy 31.776944 -15.9043) (xy 31.699879 -15.939495)
			(xy 31.619817 -15.967204) (xy 31.537484 -15.987178) (xy 31.453625 -15.999235) (xy 31.369 -16.003267)
			(xy 31.284375 -15.999235) (xy 31.200516 -15.987178) (xy 31.118183 -15.967204) (xy 31.038121 -15.939495)
			(xy 30.961056 -15.9043) (xy 30.887686 -15.86194) (xy 30.818674 -15.812797) (xy 30.754646 -15.757316)
			(xy 30.696181 -15.696001) (xy 30.64381 -15.629405) (xy 30.598007 -15.558133) (xy 30.559185 -15.48283)
			(xy 30.527697 -15.404178) (xy 30.503829 -15.322888) (xy 30.487795 -15.239698) (xy 30.479742 -15.155361)
			(xy 0.509016 -15.155361) (xy 0.509016 -16.409924) (xy 43.677851 -16.409924) (xy 43.681826 -16.307474)
			(xy 43.693729 -16.205641) (xy 43.713487 -16.105036) (xy 43.740982 -16.006265) (xy 43.776048 -15.909921)
			(xy 43.818474 -15.816585) (xy 43.868006 -15.726817) (xy 43.924346 -15.641157) (xy 43.987154 -15.560121)
			(xy 44.056052 -15.484195) (xy 44.130628 -15.413837) (xy 44.210431 -15.349469) (xy 44.294982 -15.29148)
			(xy 44.383773 -15.240216) (xy 44.476269 -15.195988) (xy 44.571914 -15.15906) (xy 44.670134 -15.129655)
			(xy 44.770337 -15.10795) (xy 44.87192 -15.094074) (xy 44.974274 -15.088113) (xy 45.076781 -15.090101)
			(xy 45.178826 -15.100027) (xy 45.279795 -15.11783) (xy 45.379081 -15.143405) (xy 45.476086 -15.176596)
			(xy 45.570228 -15.217205) (xy 45.66094 -15.264987) (xy 45.747676 -15.319655) (xy 45.829915 -15.380879)
			(xy 45.907162 -15.448293) (xy 45.978953 -15.52149) (xy 46.044856 -15.60003) (xy 46.104475 -15.68344)
			(xy 46.15745 -15.77122) (xy 46.203464 -15.862842) (xy 46.24224 -15.957753) (xy 46.273544 -16.055384)
			(xy 46.297188 -16.155147) (xy 46.31303 -16.256442) (xy 46.320975 -16.358661) (xy 46.321472 -16.409924)
			(xy 46.320975 -16.461187) (xy 46.31303 -16.563406) (xy 46.297188 -16.664701) (xy 46.273544 -16.764464)
			(xy 46.24224 -16.862095) (xy 46.203464 -16.957006) (xy 46.15745 -17.048628) (xy 46.104475 -17.136408)
			(xy 46.044856 -17.219818) (xy 45.978953 -17.298358) (xy 45.907162 -17.371555) (xy 45.829915 -17.438969)
			(xy 45.747676 -17.500193) (xy 45.66094 -17.554861) (xy 45.570228 -17.602643) (xy 45.476086 -17.643252)
			(xy 45.379081 -17.676443) (xy 45.279795 -17.702018) (xy 45.178826 -17.719821) (xy 45.076781 -17.729747)
			(xy 44.974274 -17.731735) (xy 44.87192 -17.725774) (xy 44.770337 -17.711898) (xy 44.670134 -17.690193)
			(xy 44.571914 -17.660788) (xy 44.476269 -17.62386) (xy 44.383773 -17.579632) (xy 44.294982 -17.528368)
			(xy 44.210431 -17.470379) (xy 44.130628 -17.406011) (xy 44.056052 -17.335653) (xy 43.987154 -17.259727)
			(xy 43.924346 -17.178691) (xy 43.868006 -17.093031) (xy 43.818474 -17.003263) (xy 43.776048 -16.909927)
			(xy 43.740982 -16.813583) (xy 43.713487 -16.714812) (xy 43.693729 -16.614207) (xy 43.681826 -16.512374)
			(xy 43.677851 -16.409924) (xy 0.509016 -16.409924) (xy 0.509016 -18.796) (xy 19.557492 -18.796) (xy 19.557996 -18.753652)
			(xy 19.566047 -18.669338) (xy 19.582076 -18.586172) (xy 19.605937 -18.504905) (xy 19.637416 -18.426275)
			(xy 19.676227 -18.350994) (xy 19.722017 -18.279742) (xy 19.774373 -18.213166) (xy 19.832821 -18.151868)
			(xy 19.896831 -18.096403) (xy 19.965823 -18.047274) (xy 20.039173 -18.004925) (xy 20.116216 -17.969741)
			(xy 20.196255 -17.942039) (xy 20.278564 -17.922071) (xy 20.362399 -17.910018) (xy 20.447 -17.905988)
			(xy 20.531601 -17.910018) (xy 20.615436 -17.922071) (xy 20.697745 -17.942039) (xy 20.777784 -17.969741)
			(xy 20.854827 -18.004925) (xy 20.928177 -18.047274) (xy 20.997169 -18.096403) (xy 21.061179 -18.151868)
			(xy 21.119627 -18.213166) (xy 21.171983 -18.279742) (xy 21.217773 -18.350994) (xy 21.248152 -18.40992)
			(xy 41.677855 -18.40992) (xy 41.68183 -18.30747) (xy 41.693733 -18.205637) (xy 41.713491 -18.105032)
			(xy 41.740986 -18.006261) (xy 41.776052 -17.909917) (xy 41.818478 -17.816581) (xy 41.86801 -17.726813)
			(xy 41.92435 -17.641153) (xy 41.987158 -17.560117) (xy 42.056056 -17.484191) (xy 42.130632 -17.413833)
			(xy 42.210435 -17.349465) (xy 42.294986 -17.291476) (xy 42.383777 -17.240212) (xy 42.476273 -17.195984)
			(xy 42.571918 -17.159056) (xy 42.670138 -17.129651) (xy 42.770341 -17.107946) (xy 42.871924 -17.09407)
			(xy 42.974278 -17.088109) (xy 43.076785 -17.090097) (xy 43.17883 -17.100023) (xy 43.279799 -17.117826)
			(xy 43.379085 -17.143401) (xy 43.47609 -17.176592) (xy 43.570232 -17.217201) (xy 43.660944 -17.264983)
			(xy 43.74768 -17.319651) (xy 43.829919 -17.380875) (xy 43.907166 -17.448289) (xy 43.978957 -17.521486)
			(xy 44.04486 -17.600026) (xy 44.104479 -17.683436) (xy 44.157454 -17.771216) (xy 44.203468 -17.862838)
			(xy 44.242244 -17.957749) (xy 44.273548 -18.05538) (xy 44.297192 -18.155143) (xy 44.313034 -18.256438)
			(xy 44.320979 -18.358657) (xy 44.321476 -18.40992) (xy 44.320979 -18.461183) (xy 44.313034 -18.563402)
			(xy 44.297192 -18.664697) (xy 44.273548 -18.76446) (xy 44.242244 -18.862091) (xy 44.203468 -18.957002)
			(xy 44.157454 -19.048624) (xy 44.104479 -19.136404) (xy 44.04486 -19.219814) (xy 43.978957 -19.298354)
			(xy 43.907166 -19.371551) (xy 43.829919 -19.438965) (xy 43.74768 -19.500189) (xy 43.660944 -19.554857)
			(xy 43.570232 -19.602639) (xy 43.47609 -19.643248) (xy 43.379085 -19.676439) (xy 43.279799 -19.702014)
			(xy 43.17883 -19.719817) (xy 43.076785 -19.729743) (xy 42.974278 -19.731731) (xy 42.871924 -19.72577)
			(xy 42.770341 -19.711894) (xy 42.670138 -19.690189) (xy 42.571918 -19.660784) (xy 42.476273 -19.623856)
			(xy 42.383777 -19.579628) (xy 42.294986 -19.528364) (xy 42.210435 -19.470375) (xy 42.130632 -19.406007)
			(xy 42.056056 -19.335649) (xy 41.987158 -19.259723) (xy 41.92435 -19.178687) (xy 41.86801 -19.093027)
			(xy 41.818478 -19.003259) (xy 41.776052 -18.909923) (xy 41.740986 -18.813579) (xy 41.713491 -18.714808)
			(xy 41.693733 -18.614203) (xy 41.68183 -18.51237) (xy 41.677855 -18.40992) (xy 21.248152 -18.40992)
			(xy 21.256584 -18.426275) (xy 21.288063 -18.504905) (xy 21.311924 -18.586172) (xy 21.327953 -18.669338)
			(xy 21.336004 -18.753652) (xy 21.336508 -18.796) (xy 21.335998 -18.838614) (xy 21.327848 -18.92345)
			(xy 21.311625 -19.007119) (xy 21.287475 -19.088853) (xy 21.255621 -19.167904) (xy 21.236432 -19.205956)
			(xy 21.232342 -19.214706) (xy 21.230376 -19.233901) (xy 21.232622 -19.243294) (xy 21.241004 -19.272504)
			(xy 21.244048 -19.281659) (xy 21.255789 -19.296945) (xy 21.263864 -19.302222) (xy 21.299504 -19.32402)
			(xy 21.366961 -19.373318) (xy 21.429494 -19.428728) (xy 21.486552 -19.489761) (xy 21.537632 -19.555879)
			(xy 21.582283 -19.626497) (xy 21.62011 -19.700994) (xy 21.65078 -19.778712) (xy 21.674023 -19.858964)
			(xy 21.689633 -19.941043) (xy 21.697472 -20.024225) (xy 21.69795 -20.066) (xy 21.697446 -20.108324)
			(xy 21.6894 -20.19259) (xy 21.67338 -20.275709) (xy 21.649532 -20.356928) (xy 21.618071 -20.435513)
			(xy 21.579283 -20.510752) (xy 21.533519 -20.581963) (xy 21.481192 -20.648501) (xy 21.422778 -20.709764)
			(xy 21.358805 -20.765197) (xy 21.289852 -20.814298) (xy 21.216544 -20.856623) (xy 21.139545 -20.891787)
			(xy 21.059552 -20.919473) (xy 20.97729 -20.93943) (xy 20.893503 -20.951476) (xy 20.80895 -20.955504)
			(xy 20.724397 -20.951476) (xy 20.64061 -20.93943) (xy 20.558348 -20.919473) (xy 20.478355 -20.891787)
			(xy 20.401356 -20.856623) (xy 20.328048 -20.814298) (xy 20.259095 -20.765197) (xy 20.195122 -20.709764)
			(xy 20.136708 -20.648501) (xy 20.084381 -20.581963) (xy 20.038617 -20.510752) (xy 19.999829 -20.435513)
			(xy 19.968368 -20.356928) (xy 19.94452 -20.275709) (xy 19.9285 -20.19259) (xy 19.920454 -20.108324)
			(xy 19.91995 -20.066) (xy 19.920452 -20.023468) (xy 19.928598 -19.938796) (xy 19.944789 -19.855287)
			(xy 19.968876 -19.773705) (xy 20.000638 -19.694794) (xy 20.019772 -19.656806) (xy 20.023813 -19.648041)
			(xy 20.025633 -19.628841) (xy 20.023328 -19.619468) (xy 20.0152 -19.590258) (xy 20.012125 -19.581121)
			(xy 20.000387 -19.565848) (xy 19.99234 -19.56054) (xy 19.956638 -19.538743) (xy 19.889069 -19.489423)
			(xy 19.826429 -19.433977) (xy 19.769272 -19.372894) (xy 19.718102 -19.306715) (xy 19.673372 -19.236024)
			(xy 19.635476 -19.161446) (xy 19.604749 -19.083639) (xy 19.581464 -19.003291) (xy 19.565825 -18.921112)
			(xy 19.557971 -18.837827) (xy 19.557492 -18.796) (xy 0.509016 -18.796) (xy 0.509016 -20.409916) (xy 7.377949 -20.409916)
			(xy 7.381924 -20.307466) (xy 7.393827 -20.205633) (xy 7.413585 -20.105028) (xy 7.44108 -20.006257)
			(xy 7.476146 -19.909913) (xy 7.518572 -19.816577) (xy 7.568104 -19.726809) (xy 7.624444 -19.641149)
			(xy 7.687252 -19.560113) (xy 7.75615 -19.484187) (xy 7.830726 -19.413829) (xy 7.910529 -19.349461)
			(xy 7.99508 -19.291472) (xy 8.083871 -19.240208) (xy 8.176367 -19.19598) (xy 8.272012 -19.159052)
			(xy 8.370232 -19.129647) (xy 8.470435 -19.107942) (xy 8.572018 -19.094066) (xy 8.674372 -19.088105)
			(xy 8.776879 -19.090093) (xy 8.878924 -19.100019) (xy 8.979893 -19.117822) (xy 9.079179 -19.143397)
			(xy 9.176184 -19.176588) (xy 9.270326 -19.217197) (xy 9.361038 -19.264979) (xy 9.447774 -19.319647)
			(xy 9.530013 -19.380871) (xy 9.60726 -19.448285) (xy 9.679051 -19.521482) (xy 9.744954 -19.600022)
			(xy 9.804573 -19.683432) (xy 9.857548 -19.771212) (xy 9.903562 -19.862834) (xy 9.942338 -19.957745)
			(xy 9.973642 -20.055376) (xy 9.997286 -20.155139) (xy 10.013128 -20.256434) (xy 10.021073 -20.358653)
			(xy 10.02157 -20.409916) (xy 10.021073 -20.461179) (xy 10.013128 -20.563398) (xy 9.997286 -20.664693)
			(xy 9.973642 -20.764456) (xy 9.942338 -20.862087) (xy 9.903562 -20.956998) (xy 9.857548 -21.04862)
			(xy 9.804573 -21.1364) (xy 9.744954 -21.21981) (xy 9.679051 -21.29835) (xy 9.60726 -21.371547) (xy 9.530013 -21.438961)
			(xy 9.447774 -21.500185) (xy 9.361038 -21.554853) (xy 9.270326 -21.602635) (xy 9.176184 -21.643244)
			(xy 9.079179 -21.676435) (xy 8.979893 -21.70201) (xy 8.878924 -21.719813) (xy 8.776879 -21.729739)
			(xy 8.674372 -21.731727) (xy 8.572018 -21.725766) (xy 8.470435 -21.71189) (xy 8.370232 -21.690185)
			(xy 8.272012 -21.66078) (xy 8.176367 -21.623852) (xy 8.083871 -21.579624) (xy 7.99508 -21.52836)
			(xy 7.910529 -21.470371) (xy 7.830726 -21.406003) (xy 7.75615 -21.335645) (xy 7.687252 -21.259719)
			(xy 7.624444 -21.178683) (xy 7.568104 -21.093023) (xy 7.518572 -21.003255) (xy 7.476146 -20.909919)
			(xy 7.44108 -20.813575) (xy 7.413585 -20.714804) (xy 7.393827 -20.614199) (xy 7.381924 -20.512366)
			(xy 7.377949 -20.409916) (xy 0.509016 -20.409916) (xy 0.509016 -22.409912) (xy 5.377953 -22.409912)
			(xy 5.381928 -22.307462) (xy 5.393831 -22.205629) (xy 5.413589 -22.105024) (xy 5.441084 -22.006253)
			(xy 5.47615 -21.909909) (xy 5.518576 -21.816573) (xy 5.568108 -21.726805) (xy 5.624448 -21.641145)
			(xy 5.687256 -21.560109) (xy 5.756154 -21.484183) (xy 5.83073 -21.413825) (xy 5.910533 -21.349457)
			(xy 5.995084 -21.291468) (xy 6.083875 -21.240204) (xy 6.176371 -21.195976) (xy 6.272016 -21.159048)
			(xy 6.370236 -21.129643) (xy 6.470439 -21.107938) (xy 6.572022 -21.094062) (xy 6.674376 -21.088101)
			(xy 6.776883 -21.090089) (xy 6.878928 -21.100015) (xy 6.979897 -21.117818) (xy 7.079183 -21.143393)
			(xy 7.176188 -21.176584) (xy 7.27033 -21.217193) (xy 7.361042 -21.264975) (xy 7.447778 -21.319643)
			(xy 7.530017 -21.380867) (xy 7.607264 -21.448281) (xy 7.679055 -21.521478) (xy 7.744958 -21.600018)
			(xy 7.804577 -21.683428) (xy 7.857552 -21.771208) (xy 7.903566 -21.86283) (xy 7.942342 -21.957741)
			(xy 7.973646 -22.055372) (xy 7.99729 -22.155135) (xy 8.013132 -22.25643) (xy 8.021077 -22.358649)
			(xy 8.021574 -22.409912) (xy 8.021077 -22.461175) (xy 8.013132 -22.563394) (xy 7.99729 -22.664689)
			(xy 7.973646 -22.764452) (xy 7.942342 -22.862083) (xy 7.903566 -22.956994) (xy 7.857552 -23.048616)
			(xy 7.804577 -23.136396) (xy 7.744958 -23.219806) (xy 7.679055 -23.298346) (xy 7.607264 -23.371543)
			(xy 7.530017 -23.438957) (xy 7.447778 -23.500181) (xy 7.361042 -23.554849) (xy 7.27033 -23.602631)
			(xy 7.176188 -23.64324) (xy 7.079183 -23.676431) (xy 6.979897 -23.702006) (xy 6.878928 -23.719809)
			(xy 6.776883 -23.729735) (xy 6.674376 -23.731723) (xy 6.572022 -23.725762) (xy 6.470439 -23.711886)
			(xy 6.370236 -23.690181) (xy 6.272016 -23.660776) (xy 6.176371 -23.623848) (xy 6.083875 -23.57962)
			(xy 5.995084 -23.528356) (xy 5.910533 -23.470367) (xy 5.83073 -23.405999) (xy 5.756154 -23.335641)
			(xy 5.687256 -23.259715) (xy 5.624448 -23.178679) (xy 5.568108 -23.093019) (xy 5.518576 -23.003251)
			(xy 5.47615 -22.909915) (xy 5.441084 -22.813571) (xy 5.413589 -22.7148) (xy 5.393831 -22.614195)
			(xy 5.381928 -22.512362) (xy 5.377953 -22.409912) (xy 0.509016 -22.409912) (xy 0.509016 -25.908)
			(xy 30.225492 -25.908) (xy 30.226006 -25.864322) (xy 30.234576 -25.777387) (xy 30.251624 -25.69171)
			(xy 30.276986 -25.608116) (xy 30.310417 -25.52741) (xy 30.351597 -25.450369) (xy 30.400127 -25.377733)
			(xy 30.455542 -25.310203) (xy 30.517308 -25.248429) (xy 30.58483 -25.193004) (xy 30.657459 -25.144463)
			(xy 30.734494 -25.103272) (xy 30.77464 -25.086056) (xy 30.783677 -25.081783) (xy 30.797795 -25.06766)
			(xy 30.802072 -25.058624) (xy 30.819293 -25.018567) (xy 30.8605 -24.941721) (xy 30.909032 -24.869278)
			(xy 30.964423 -24.801934) (xy 31.026142 -24.740338) (xy 31.093595 -24.68508) (xy 31.166134 -24.636692)
			(xy 31.243063 -24.595638) (xy 31.323641 -24.562314) (xy 31.407095 -24.537039) (xy 31.492622 -24.520056)
			(xy 31.579401 -24.511528) (xy 31.623 -24.511) (xy 31.664079 -24.511474) (xy 31.745887 -24.519055)
			(xy 31.826646 -24.534151) (xy 31.905668 -24.556635) (xy 31.982278 -24.586314) (xy 32.055823 -24.622935)
			(xy 32.125675 -24.666185) (xy 32.191238 -24.715697) (xy 32.251954 -24.771046) (xy 32.307303 -24.831762)
			(xy 32.356815 -24.897325) (xy 32.400065 -24.967177) (xy 32.436686 -25.040722) (xy 32.466365 -25.117332)
			(xy 32.474522 -25.146) (xy 32.764988 -25.146) (xy 32.769018 -25.061399) (xy 32.781071 -24.977564)
			(xy 32.801039 -24.895255) (xy 32.828741 -24.815216) (xy 32.863925 -24.738173) (xy 32.906274 -24.664823)
			(xy 32.955403 -24.595831) (xy 33.010868 -24.531821) (xy 33.072166 -24.473373) (xy 33.138742 -24.421017)
			(xy 33.209994 -24.375227) (xy 33.285275 -24.336416) (xy 33.363905 -24.304937) (xy 33.445172 -24.281076)
			(xy 33.528338 -24.265047) (xy 33.612652 -24.256996) (xy 33.655 -24.256492) (xy 33.698026 -24.256951)
			(xy 33.783677 -24.265259) (xy 33.868126 -24.281797) (xy 33.950583 -24.306411) (xy 34.030279 -24.338871)
			(xy 34.106469 -24.378873) (xy 34.178441 -24.426044) (xy 34.245523 -24.479944) (xy 34.307088 -24.540067)
			(xy 34.36256 -24.605854) (xy 34.411422 -24.676689) (xy 34.453217 -24.75191) (xy 34.470848 -24.791162)
			(xy 34.475674 -24.802084) (xy 34.4932 -24.81707) (xy 34.5948 -24.84247) (xy 34.61766 -24.837644)
			(xy 34.627058 -24.830024) (xy 34.660727 -24.804016) (xy 34.732174 -24.757818) (xy 34.807707 -24.718656)
			(xy 34.886635 -24.686888) (xy 34.968237 -24.662804) (xy 35.051766 -24.646624) (xy 35.136459 -24.638498)
			(xy 35.179 -24.638) (xy 35.221324 -24.638504) (xy 35.30559 -24.64655) (xy 35.388709 -24.66257) (xy 35.469928 -24.686418)
			(xy 35.548513 -24.717879) (xy 35.623752 -24.756667) (xy 35.694963 -24.802431) (xy 35.761501 -24.854758)
			(xy 35.822764 -24.913172) (xy 35.878197 -24.977145) (xy 35.927298 -25.046098) (xy 35.969623 -25.119406)
			(xy 36.004787 -25.196405) (xy 36.032473 -25.276398) (xy 36.05243 -25.35866) (xy 36.064476 -25.442447)
			(xy 36.068504 -25.527) (xy 36.064476 -25.611553) (xy 36.05243 -25.69534) (xy 36.032473 -25.777602)
			(xy 36.004787 -25.857595) (xy 35.969623 -25.934594) (xy 35.927298 -26.007902) (xy 35.878197 -26.076855)
			(xy 35.822764 -26.140828) (xy 35.761501 -26.199242) (xy 35.694963 -26.251569) (xy 35.623752 -26.297333)
			(xy 35.548513 -26.336121) (xy 35.469928 -26.367582) (xy 35.388709 -26.39143) (xy 35.30559 -26.40745)
			(xy 35.221324 -26.415496) (xy 35.179 -26.416) (xy 35.136021 -26.415519) (xy 35.050463 -26.40724)
			(xy 34.966104 -26.39074) (xy 34.883732 -26.366173) (xy 34.804116 -26.333768) (xy 34.728 -26.293829)
			(xy 34.656096 -26.246728) (xy 34.589074 -26.192906) (xy 34.527562 -26.132865) (xy 34.472133 -26.067165)
			(xy 34.423306 -25.996422) (xy 34.381536 -25.921295) (xy 34.363914 -25.882092) (xy 34.359088 -25.87117)
			(xy 34.341562 -25.85593) (xy 34.239962 -25.830784) (xy 34.217102 -25.83561) (xy 34.207704 -25.842976)
			(xy 34.17402 -25.869073) (xy 34.102487 -25.915385) (xy 34.026854 -25.954645) (xy 33.947814 -25.986494)
			(xy 33.866091 -26.010639) (xy 33.782433 -26.02686) (xy 33.697608 -26.035008) (xy 33.655 -26.035508)
			(xy 33.612652 -26.035004) (xy 33.528338 -26.026953) (xy 33.445172 -26.010924) (xy 33.363905 -25.987063)
			(xy 33.285275 -25.955584) (xy 33.209994 -25.916773) (xy 33.138742 -25.870983) (xy 33.072166 -25.818627)
			(xy 33.010868 -25.760179) (xy 32.955403 -25.696169) (xy 32.906274 -25.627177) (xy 32.863925 -25.553827)
			(xy 32.828741 -25.476784) (xy 32.801039 -25.396745) (xy 32.781071 -25.314436) (xy 32.769018 -25.230601)
			(xy 32.764988 -25.146) (xy 32.474522 -25.146) (xy 32.488849 -25.196354) (xy 32.503945 -25.277113)
			(xy 32.511526 -25.358921) (xy 32.512 -25.4) (xy 32.511475 -25.443596) (xy 32.502923 -25.530367) (xy 32.485921 -25.615886)
			(xy 32.460633 -25.69933) (xy 32.4273 -25.779899) (xy 32.386243 -25.856819) (xy 32.337855 -25.929353)
			(xy 32.282603 -25.996803) (xy 32.221015 -26.058523) (xy 32.153683 -26.11392) (xy 32.081253 -26.162463)
			(xy 32.00442 -26.203684) (xy 31.964376 -26.220928) (xy 31.955346 -26.225212) (xy 31.941224 -26.239328)
			(xy 31.936944 -26.24836) (xy 31.919697 -26.288493) (xy 31.878517 -26.365534) (xy 31.829985 -26.438168)
			(xy 31.774566 -26.505696) (xy 31.712796 -26.567466) (xy 31.645269 -26.622884) (xy 31.572635 -26.671417)
			(xy 31.495593 -26.712596) (xy 31.414886 -26.746026) (xy 31.331292 -26.771384) (xy 31.245614 -26.788427)
			(xy 31.158678 -26.796989) (xy 31.115 -26.797508) (xy 31.073898 -26.797033) (xy 30.992043 -26.789448)
			(xy 30.911238 -26.774343) (xy 30.832171 -26.751847) (xy 30.755517 -26.722151) (xy 30.68193 -26.685509)
			(xy 30.612038 -26.642234) (xy 30.546437 -26.592694) (xy 30.485687 -26.537313) (xy 30.430306 -26.476563)
			(xy 30.380766 -26.410962) (xy 30.337491 -26.34107) (xy 30.300849 -26.267483) (xy 30.271153 -26.190829)
			(xy 30.248657 -26.111762) (xy 30.233552 -26.030957) (xy 30.225967 -25.949102) (xy 30.225492 -25.908)
			(xy 0.509016 -25.908) (xy 0.509016 -28.309824) (xy 42.741353 -28.309824) (xy 42.745331 -28.209831)
			(xy 42.757241 -28.110471) (xy 42.777008 -28.01237) (xy 42.804507 -27.916151) (xy 42.839563 -27.82242)
			(xy 42.881955 -27.731771) (xy 42.931416 -27.644777) (xy 42.987632 -27.561987) (xy 43.050248 -27.483925)
			(xy 43.118867 -27.411085) (xy 43.193058 -27.343927) (xy 43.272349 -27.282875) (xy 43.35624 -27.228317)
			(xy 43.444201 -27.180596) (xy 43.535675 -27.140014) (xy 43.630084 -27.106828) (xy 43.726831 -27.081248)
			(xy 43.825305 -27.063435) (xy 43.924883 -27.053503) (xy 44.024935 -27.051513) (xy 44.124829 -27.057479)
			(xy 44.223933 -27.071363) (xy 44.321621 -27.093076) (xy 44.417275 -27.122482) (xy 44.51029 -27.159395)
			(xy 44.600078 -27.203581) (xy 44.686072 -27.254762) (xy 44.767728 -27.312612) (xy 44.844529 -27.376768)
			(xy 44.915991 -27.446822) (xy 44.981661 -27.522333) (xy 45.041123 -27.602823) (xy 45.094003 -27.687782)
			(xy 45.139966 -27.776674) (xy 45.178721 -27.868937) (xy 45.210023 -27.963987) (xy 45.233675 -28.061224)
			(xy 45.249526 -28.160033) (xy 45.257476 -28.259788) (xy 45.257974 -28.309824) (xy 45.257476 -28.35986)
			(xy 45.249526 -28.459615) (xy 45.233675 -28.558424) (xy 45.210023 -28.655661) (xy 45.178721 -28.750711)
			(xy 45.139966 -28.842974) (xy 45.094003 -28.931866) (xy 45.041123 -29.016825) (xy 44.981661 -29.097315)
			(xy 44.915991 -29.172826) (xy 44.844529 -29.24288) (xy 44.767728 -29.307036) (xy 44.686072 -29.364886)
			(xy 44.600078 -29.416067) (xy 44.51029 -29.460253) (xy 44.417275 -29.497166) (xy 44.321621 -29.526572)
			(xy 44.223933 -29.548285) (xy 44.124829 -29.562169) (xy 44.024935 -29.568135) (xy 43.924883 -29.566145)
			(xy 43.825305 -29.556213) (xy 43.726831 -29.5384) (xy 43.630084 -29.51282) (xy 43.535675 -29.479634)
			(xy 43.444201 -29.439052) (xy 43.35624 -29.391331) (xy 43.272349 -29.336773) (xy 43.193058 -29.275721)
			(xy 43.118867 -29.208563) (xy 43.050248 -29.135723) (xy 42.987632 -29.057661) (xy 42.931416 -28.974871)
			(xy 42.881955 -28.887877) (xy 42.839563 -28.797228) (xy 42.804507 -28.703497) (xy 42.777008 -28.607278)
			(xy 42.757241 -28.509177) (xy 42.745331 -28.409817) (xy 42.741353 -28.309824) (xy 0.509016 -28.309824)
			(xy 0.509016 -29.591) (xy 18.60296 -29.591) (xy 18.603452 -29.54989) (xy 18.61104 -29.468022) (xy 18.62615 -29.387203)
			(xy 18.648654 -29.308123) (xy 18.678359 -29.231458) (xy 18.715013 -29.15786) (xy 18.758302 -29.08796)
			(xy 18.807857 -29.022353) (xy 18.863255 -28.961598) (xy 18.924023 -28.906215) (xy 18.989643 -28.856677)
			(xy 19.059554 -28.813405) (xy 19.133161 -28.77677) (xy 19.209834 -28.747083) (xy 19.288919 -28.724599)
			(xy 19.369742 -28.709509) (xy 19.451612 -28.701942) (xy 19.492722 -28.701492) (xy 19.535817 -28.702062)
			(xy 19.621603 -28.710407) (xy 19.706179 -28.727008) (xy 19.788755 -28.751708) (xy 19.868555 -28.784277)
			(xy 19.944833 -28.824408) (xy 20.016872 -28.871727) (xy 20.083999 -28.92579) (xy 20.145585 -28.986089)
			(xy 20.201052 -29.052061) (xy 20.24988 -29.123086) (xy 20.291612 -29.1985) (xy 20.325857 -29.277596)
			(xy 20.339558 -29.318458) (xy 20.341332 -29.323554) (xy 20.346708 -29.332908) (xy 20.350226 -29.337)
			(xy 20.377137 -29.367587) (xy 20.425884 -29.432869) (xy 20.468455 -29.502338) (xy 20.50449 -29.57541)
			(xy 20.533689 -29.651473) (xy 20.555805 -29.729888) (xy 20.570655 -29.809998) (xy 20.578112 -29.891131)
			(xy 20.578572 -29.931868) (xy 20.578109 -29.972948) (xy 20.570531 -30.054758) (xy 20.555437 -30.135519)
			(xy 20.532954 -30.214543) (xy 20.503276 -30.291156) (xy 20.466656 -30.364703) (xy 20.423405 -30.434557)
			(xy 20.373893 -30.500123) (xy 20.318542 -30.56084) (xy 20.257826 -30.61619) (xy 20.19226 -30.665703)
			(xy 20.122406 -30.708954) (xy 20.048859 -30.745575) (xy 19.972247 -30.775253) (xy 19.893223 -30.797736)
			(xy 19.812462 -30.812831) (xy 19.730652 -30.820409) (xy 19.689572 -30.820868) (xy 19.646602 -30.820396)
			(xy 19.561064 -30.812107) (xy 19.476725 -30.795599) (xy 19.394373 -30.771028) (xy 19.314778 -30.738621)
			(xy 19.238683 -30.698683) (xy 19.166799 -30.651585) (xy 19.099796 -30.597768) (xy 19.038302 -30.537735)
			(xy 18.98289 -30.472046) (xy 18.934078 -30.401315) (xy 18.892321 -30.326202) (xy 18.85801 -30.247409)
			(xy 18.84426 -30.206696) (xy 18.84248 -30.20166) (xy 18.837097 -30.192438) (xy 18.833592 -30.188408)
			(xy 18.806416 -30.157771) (xy 18.757208 -30.092301) (xy 18.714226 -30.022586) (xy 18.677834 -29.949215)
			(xy 18.64834 -29.872809) (xy 18.625993 -29.794016) (xy 18.610983 -29.713503) (xy 18.603437 -29.63195)
			(xy 18.60296 -29.591) (xy 0.509016 -29.591) (xy 0.509016 -31.599792) (xy 16.256504 -31.599792) (xy 16.256504 -31.515144)
			(xy 16.26455 -31.430878) (xy 16.28057 -31.347759) (xy 16.304418 -31.26654) (xy 16.335879 -31.187955)
			(xy 16.374667 -31.112716) (xy 16.420431 -31.041505) (xy 16.472758 -30.974967) (xy 16.531172 -30.913704)
			(xy 16.595145 -30.858271) (xy 16.664098 -30.80917) (xy 16.737406 -30.766845) (xy 16.814405 -30.731681)
			(xy 16.894398 -30.703995) (xy 16.97666 -30.684038) (xy 17.060447 -30.671992) (xy 17.145 -30.667964)
			(xy 17.229553 -30.671992) (xy 17.31334 -30.684038) (xy 17.395602 -30.703995) (xy 17.475595 -30.731681)
			(xy 17.552594 -30.766845) (xy 17.625902 -30.80917) (xy 17.694855 -30.858271) (xy 17.758828 -30.913704)
			(xy 17.817242 -30.974967) (xy 17.869569 -31.041505) (xy 17.915333 -31.112716) (xy 17.954121 -31.187955)
			(xy 17.985582 -31.26654) (xy 18.00943 -31.347759) (xy 18.02545 -31.430878) (xy 18.033496 -31.515144)
			(xy 18.034 -31.557468) (xy 18.033496 -31.599792) (xy 18.02545 -31.684058) (xy 18.00943 -31.767177)
			(xy 17.985582 -31.848396) (xy 17.954121 -31.926981) (xy 17.915333 -32.00222) (xy 17.869569 -32.073431)
			(xy 17.817242 -32.139969) (xy 17.758828 -32.201232) (xy 17.694855 -32.256665) (xy 17.625902 -32.305766)
			(xy 17.552594 -32.348091) (xy 17.475595 -32.383255) (xy 17.395602 -32.410941) (xy 17.31334 -32.430898)
			(xy 17.229553 -32.442944) (xy 17.145 -32.446972) (xy 17.060447 -32.442944) (xy 16.97666 -32.430898)
			(xy 16.894398 -32.410941) (xy 16.814405 -32.383255) (xy 16.737406 -32.348091) (xy 16.664098 -32.305766)
			(xy 16.595145 -32.256665) (xy 16.531172 -32.201232) (xy 16.472758 -32.139969) (xy 16.420431 -32.073431)
			(xy 16.374667 -32.00222) (xy 16.335879 -31.926981) (xy 16.304418 -31.848396) (xy 16.28057 -31.767177)
			(xy 16.26455 -31.684058) (xy 16.256504 -31.599792) (xy 0.509016 -31.599792) (xy 0.509016 -32.935361)
			(xy 31.495742 -32.935361) (xy 31.495742 -32.850639) (xy 31.503795 -32.766302) (xy 31.519829 -32.683112)
			(xy 31.543697 -32.601822) (xy 31.575185 -32.52317) (xy 31.614007 -32.447867) (xy 31.65981 -32.376595)
			(xy 31.712181 -32.309999) (xy 31.770646 -32.248684) (xy 31.834674 -32.193203) (xy 31.903686 -32.14406)
			(xy 31.977056 -32.1017) (xy 32.054121 -32.066505) (xy 32.134183 -32.038796) (xy 32.216516 -32.018822)
			(xy 32.300375 -32.006765) (xy 32.385 -32.002734) (xy 32.469625 -32.006765) (xy 32.553484 -32.018822)
			(xy 32.635817 -32.038796) (xy 32.715879 -32.066505) (xy 32.792944 -32.1017) (xy 32.866314 -32.14406)
			(xy 32.935326 -32.193203) (xy 32.999354 -32.248684) (xy 33.057819 -32.309999) (xy 33.11019 -32.376595)
			(xy 33.155993 -32.447867) (xy 33.194815 -32.52317) (xy 33.226303 -32.601822) (xy 33.250171 -32.683112)
			(xy 33.266205 -32.766302) (xy 33.274258 -32.850639) (xy 33.274762 -32.893) (xy 33.274258 -32.935361)
			(xy 33.266205 -33.019698) (xy 33.250171 -33.102888) (xy 33.226303 -33.184178) (xy 33.194815 -33.26283)
			(xy 33.155993 -33.338133) (xy 33.11019 -33.409405) (xy 33.057819 -33.476001) (xy 32.999354 -33.537316)
			(xy 32.935326 -33.592797) (xy 32.866314 -33.64194) (xy 32.792944 -33.6843) (xy 32.715879 -33.719495)
			(xy 32.635817 -33.747204) (xy 32.579523 -33.760861) (xy 33.591242 -33.760861) (xy 33.591242 -33.676139)
			(xy 33.599295 -33.591802) (xy 33.615329 -33.508612) (xy 33.639197 -33.427322) (xy 33.670685 -33.34867)
			(xy 33.709507 -33.273367) (xy 33.75531 -33.202095) (xy 33.807681 -33.135499) (xy 33.866146 -33.074184)
			(xy 33.930174 -33.018703) (xy 33.999186 -32.96956) (xy 34.072556 -32.9272) (xy 34.149621 -32.892005)
			(xy 34.229683 -32.864296) (xy 34.312016 -32.844322) (xy 34.395875 -32.832265) (xy 34.4805 -32.828234)
			(xy 34.565125 -32.832265) (xy 34.648984 -32.844322) (xy 34.731317 -32.864296) (xy 34.811379 -32.892005)
			(xy 34.888444 -32.9272) (xy 34.961814 -32.96956) (xy 35.030826 -33.018703) (xy 35.094854 -33.074184)
			(xy 35.153319 -33.135499) (xy 35.20569 -33.202095) (xy 35.251493 -33.273367) (xy 35.290315 -33.34867)
			(xy 35.321803 -33.427322) (xy 35.345671 -33.508612) (xy 35.361705 -33.591802) (xy 35.369758 -33.676139)
			(xy 35.370262 -33.7185) (xy 35.369758 -33.760861) (xy 35.361705 -33.845198) (xy 35.345671 -33.928388)
			(xy 35.321803 -34.009678) (xy 35.290315 -34.08833) (xy 35.251493 -34.163633) (xy 35.20569 -34.234905)
			(xy 35.153319 -34.301501) (xy 35.094854 -34.362816) (xy 35.030826 -34.418297) (xy 34.961814 -34.46744)
			(xy 34.888444 -34.5098) (xy 34.811379 -34.544995) (xy 34.731317 -34.572704) (xy 34.648984 -34.592678)
			(xy 34.565125 -34.604735) (xy 34.4805 -34.608767) (xy 34.395875 -34.604735) (xy 34.312016 -34.592678)
			(xy 34.229683 -34.572704) (xy 34.149621 -34.544995) (xy 34.072556 -34.5098) (xy 33.999186 -34.46744)
			(xy 33.930174 -34.418297) (xy 33.866146 -34.362816) (xy 33.807681 -34.301501) (xy 33.75531 -34.234905)
			(xy 33.709507 -34.163633) (xy 33.670685 -34.08833) (xy 33.639197 -34.009678) (xy 33.615329 -33.928388)
			(xy 33.599295 -33.845198) (xy 33.591242 -33.760861) (xy 32.579523 -33.760861) (xy 32.553484 -33.767178)
			(xy 32.469625 -33.779235) (xy 32.385 -33.783267) (xy 32.300375 -33.779235) (xy 32.216516 -33.767178)
			(xy 32.134183 -33.747204) (xy 32.054121 -33.719495) (xy 31.977056 -33.6843) (xy 31.903686 -33.64194)
			(xy 31.834674 -33.592797) (xy 31.770646 -33.537316) (xy 31.712181 -33.476001) (xy 31.65981 -33.409405)
			(xy 31.614007 -33.338133) (xy 31.575185 -33.26283) (xy 31.543697 -33.184178) (xy 31.519829 -33.102888)
			(xy 31.503795 -33.019698) (xy 31.495742 -32.935361) (xy 0.509016 -32.935361) (xy 0.509016 -33.951361)
			(xy 18.414742 -33.951361) (xy 18.414742 -33.866639) (xy 18.422795 -33.782302) (xy 18.438829 -33.699112)
			(xy 18.462697 -33.617822) (xy 18.494185 -33.53917) (xy 18.533007 -33.463867) (xy 18.57881 -33.392595)
			(xy 18.631181 -33.325999) (xy 18.689646 -33.264684) (xy 18.753674 -33.209203) (xy 18.822686 -33.16006)
			(xy 18.896056 -33.1177) (xy 18.973121 -33.082505) (xy 19.053183 -33.054796) (xy 19.135516 -33.034822)
			(xy 19.219375 -33.022765) (xy 19.304 -33.018734) (xy 19.388625 -33.022765) (xy 19.472484 -33.034822)
			(xy 19.554817 -33.054796) (xy 19.634879 -33.082505) (xy 19.711944 -33.1177) (xy 19.785314 -33.16006)
			(xy 19.854326 -33.209203) (xy 19.918354 -33.264684) (xy 19.976819 -33.325999) (xy 20.02919 -33.392595)
			(xy 20.074993 -33.463867) (xy 20.113815 -33.53917) (xy 20.145303 -33.617822) (xy 20.169171 -33.699112)
			(xy 20.185205 -33.782302) (xy 20.193258 -33.866639) (xy 20.193762 -33.909) (xy 20.193258 -33.951361)
			(xy 20.185205 -34.035698) (xy 20.169171 -34.118888) (xy 20.145303 -34.200178) (xy 20.113815 -34.27883)
			(xy 20.074993 -34.354133) (xy 20.02919 -34.425405) (xy 19.976819 -34.492001) (xy 19.918354 -34.553316)
			(xy 19.854326 -34.608797) (xy 19.785314 -34.65794) (xy 19.711944 -34.7003) (xy 19.634879 -34.735495)
			(xy 19.554817 -34.763204) (xy 19.472484 -34.783178) (xy 19.388625 -34.795235) (xy 19.304 -34.799267)
			(xy 19.219375 -34.795235) (xy 19.135516 -34.783178) (xy 19.053183 -34.763204) (xy 18.973121 -34.735495)
			(xy 18.896056 -34.7003) (xy 18.822686 -34.65794) (xy 18.753674 -34.608797) (xy 18.689646 -34.553316)
			(xy 18.631181 -34.492001) (xy 18.57881 -34.425405) (xy 18.533007 -34.354133) (xy 18.494185 -34.27883)
			(xy 18.462697 -34.200178) (xy 18.438829 -34.118888) (xy 18.422795 -34.035698) (xy 18.414742 -33.951361)
			(xy 0.509016 -33.951361) (xy 0.509016 -38.649656) (xy 10.387584 -38.649656) (xy 10.388004 -38.611367)
			(xy 10.394607 -38.535073) (xy 10.407752 -38.45963) (xy 10.427342 -38.385599) (xy 10.439908 -38.349428)
			(xy 10.442583 -38.340997) (xy 10.442568 -38.323321) (xy 10.439908 -38.314884) (xy 10.427378 -38.278702)
			(xy 10.407801 -38.204671) (xy 10.39465 -38.129232) (xy 10.388022 -38.052944) (xy 10.387584 -38.014656)
			(xy 10.388134 -37.971531) (xy 10.396533 -37.885692) (xy 10.41321 -37.80107) (xy 10.438008 -37.718462)
			(xy 10.453878 -37.67836) (xy 10.457226 -37.668995) (xy 10.45721 -37.649124) (xy 10.453878 -37.639752)
			(xy 10.438017 -37.599647) (xy 10.413234 -37.517036) (xy 10.396554 -37.432416) (xy 10.388133 -37.34658)
			(xy 10.387584 -37.303456) (xy 10.38801 -37.262345) (xy 10.395602 -37.180474) (xy 10.410717 -37.099653)
			(xy 10.433225 -37.020571) (xy 10.462935 -36.943904) (xy 10.499593 -36.870306) (xy 10.542887 -36.800405)
			(xy 10.592446 -36.734797) (xy 10.647848 -36.674043) (xy 10.708621 -36.618661) (xy 10.774244 -36.569123)
			(xy 10.84416 -36.525852) (xy 10.91777 -36.489218) (xy 10.994446 -36.459533) (xy 11.073535 -36.43705)
			(xy 11.154361 -36.421962) (xy 11.236235 -36.414397) (xy 11.277346 -36.413948) (xy 11.323741 -36.414545)
			(xy 11.416029 -36.424185) (xy 11.506813 -36.443377) (xy 11.595107 -36.471912) (xy 11.637772 -36.490148)
			(xy 11.647714 -36.493954) (xy 11.668978 -36.493954) (xy 11.67892 -36.490148) (xy 11.721577 -36.471891)
			(xy 11.809871 -36.44335) (xy 11.900658 -36.42416) (xy 11.99295 -36.414531) (xy 12.039346 -36.413948)
			(xy 12.080453 -36.414426) (xy 12.162316 -36.42201) (xy 12.24313 -36.437114) (xy 12.322206 -36.459608)
			(xy 12.39887 -36.489302) (xy 12.472467 -36.525941) (xy 12.542371 -36.569214) (xy 12.607985 -36.61875)
			(xy 12.668749 -36.674129) (xy 12.724145 -36.734877) (xy 12.7737 -36.800476) (xy 12.816993 -36.870367)
			(xy 12.853654 -36.943954) (xy 12.88337 -37.020609) (xy 12.905887 -37.099679) (xy 12.921014 -37.180489)
			(xy 12.928622 -37.262349) (xy 12.929108 -37.303456) (xy 12.928563 -37.346581) (xy 12.920162 -37.432421)
			(xy 12.903484 -37.517042) (xy 12.878685 -37.59965) (xy 12.862814 -37.639752) (xy 12.859515 -37.64913)
			(xy 12.859499 -37.668989) (xy 12.862814 -37.67836) (xy 12.878678 -37.718463) (xy 12.903461 -37.801075)
			(xy 12.919776 -37.883846) (xy 36.848796 -37.883846) (xy 36.849168 -37.845561) (xy 36.855711 -37.769272)
			(xy 36.868797 -37.69383) (xy 36.888329 -37.619794) (xy 36.900866 -37.583618) (xy 36.903493 -37.575175)
			(xy 36.903508 -37.55751) (xy 36.900866 -37.549074) (xy 36.888354 -37.512891) (xy 36.868843 -37.438853)
			(xy 36.855759 -37.363413) (xy 36.8492 -37.287129) (xy 36.848796 -37.248846) (xy 36.849356 -37.207741)
			(xy 36.856936 -37.125882) (xy 36.872035 -37.045071) (xy 36.894525 -36.965997) (xy 36.924213 -36.889336)
			(xy 36.960847 -36.81574) (xy 37.004115 -36.745837) (xy 37.053646 -36.680225) (xy 37.109019 -36.619461)
			(xy 37.169761 -36.564064) (xy 37.235355 -36.514508) (xy 37.305241 -36.471214) (xy 37.378823 -36.434552)
			(xy 37.455473 -36.404834) (xy 37.534538 -36.382314) (xy 37.615343 -36.367183) (xy 37.697199 -36.359572)
			(xy 37.738304 -36.359084) (xy 37.784706 -36.359709) (xy 37.877004 -36.369399) (xy 37.967789 -36.388654)
			(xy 38.056074 -36.417262) (xy 38.09873 -36.435538) (xy 38.108672 -36.439344) (xy 38.129936 -36.439344)
			(xy 38.139878 -36.435538) (xy 38.182538 -36.417275) (xy 38.270827 -36.388682) (xy 38.36161 -36.369425)
			(xy 38.453903 -36.359713) (xy 38.500304 -36.359084) (xy 38.546706 -36.359709) (xy 38.639004 -36.369399)
			(xy 38.729789 -36.388654) (xy 38.818074 -36.417262) (xy 38.86073 -36.435538) (xy 38.870672 -36.439344)
			(xy 38.891936 -36.439344) (xy 38.901878 -36.435538) (xy 38.944538 -36.417275) (xy 39.032827 -36.388682)
			(xy 39.12361 -36.369425) (xy 39.215903 -36.359713) (xy 39.262304 -36.359084) (xy 39.303414 -36.359549)
			(xy 39.385284 -36.367137) (xy 39.466105 -36.382248) (xy 39.545186 -36.404753) (xy 39.621853 -36.43446)
			(xy 39.695451 -36.471115) (xy 39.765352 -36.514406) (xy 39.83096 -36.563962) (xy 39.891715 -36.619362)
			(xy 39.947097 -36.680133) (xy 39.996636 -36.745754) (xy 40.039907 -36.815668) (xy 40.076541 -36.889276)
			(xy 40.106227 -36.965951) (xy 40.12871 -37.045039) (xy 40.143798 -37.125863) (xy 40.151363 -37.207735)
			(xy 40.151812 -37.248846) (xy 40.151438 -37.287131) (xy 40.144895 -37.36342) (xy 40.131809 -37.438862)
			(xy 40.112279 -37.512898) (xy 40.099742 -37.549074) (xy 40.097068 -37.557505) (xy 40.097083 -37.575181)
			(xy 40.099742 -37.583618) (xy 40.112252 -37.619801) (xy 40.131764 -37.693839) (xy 40.144848 -37.769279)
			(xy 40.151408 -37.845563) (xy 40.151812 -37.883846) (xy 40.151431 -37.924955) (xy 40.143842 -38.006822)
			(xy 40.128733 -38.08764) (xy 40.106233 -38.166719) (xy 40.076534 -38.243386) (xy 40.039888 -38.316985)
			(xy 39.996609 -38.38689) (xy 39.947066 -38.452505) (xy 39.891681 -38.513269) (xy 39.830927 -38.568665)
			(xy 39.765321 -38.61822) (xy 39.695423 -38.661511) (xy 39.62183 -38.69817) (xy 39.545169 -38.727883)
			(xy 39.466094 -38.750397) (xy 39.385279 -38.76552) (xy 39.303413 -38.773124) (xy 39.262304 -38.773608)
			(xy 39.215902 -38.772981) (xy 39.123605 -38.763291) (xy 39.032819 -38.744038) (xy 38.944534 -38.71543)
			(xy 38.901878 -38.697154) (xy 38.891936 -38.693348) (xy 38.870672 -38.693348) (xy 38.86073 -38.697154)
			(xy 38.818068 -38.715414) (xy 38.729781 -38.744008) (xy 38.638998 -38.763266) (xy 38.546705 -38.772979)
			(xy 38.500304 -38.773608) (xy 38.453902 -38.772981) (xy 38.361605 -38.763291) (xy 38.270819 -38.744038)
			(xy 38.182534 -38.71543) (xy 38.139878 -38.697154) (xy 38.129936 -38.693348) (xy 38.108672 -38.693348)
			(xy 38.09873 -38.697154) (xy 38.056068 -38.715414) (xy 37.967781 -38.744008) (xy 37.876998 -38.763266)
			(xy 37.784705 -38.772979) (xy 37.738304 -38.773608) (xy 37.697193 -38.773144) (xy 37.615323 -38.765556)
			(xy 37.534502 -38.750446) (xy 37.455421 -38.727941) (xy 37.378754 -38.698235) (xy 37.305156 -38.66158)
			(xy 37.235254 -38.618289) (xy 37.169646 -38.568732) (xy 37.108891 -38.513332) (xy 37.053508 -38.452562)
			(xy 37.00397 -38.38694) (xy 36.960699 -38.317026) (xy 36.924064 -38.243417) (xy 36.894379 -38.166742)
			(xy 36.871897 -38.087654) (xy 36.856809 -38.006829) (xy 36.849245 -37.924957) (xy 36.848796 -37.883846)
			(xy 12.919776 -37.883846) (xy 12.92014 -37.885695) (xy 12.92856 -37.971532) (xy 12.929108 -38.014656)
			(xy 12.928692 -38.052946) (xy 12.922088 -38.12924) (xy 12.908941 -38.204682) (xy 12.889351 -38.278713)
			(xy 12.876784 -38.314884) (xy 12.874154 -38.323326) (xy 12.874139 -38.340992) (xy 12.876784 -38.349428)
			(xy 12.889317 -38.385609) (xy 12.908893 -38.459641) (xy 12.922043 -38.535079) (xy 12.928671 -38.611368)
			(xy 12.929108 -38.649656) (xy 12.928606 -38.690766) (xy 12.921022 -38.772635) (xy 12.905915 -38.853455)
			(xy 12.883413 -38.932536) (xy 12.85371 -39.009203) (xy 12.817058 -39.082801) (xy 12.77377 -39.152703)
			(xy 12.724216 -39.218311) (xy 12.668818 -39.279066) (xy 12.60805 -39.33445) (xy 12.54243 -39.383989)
			(xy 12.472518 -39.42726) (xy 12.398911 -39.463895) (xy 12.322237 -39.49358) (xy 12.243151 -39.516063)
			(xy 12.162327 -39.531151) (xy 12.080456 -39.538715) (xy 12.039346 -39.539164) (xy 11.992951 -39.538569)
			(xy 11.900663 -39.528928) (xy 11.809879 -39.509736) (xy 11.721585 -39.4812) (xy 11.67892 -39.462964)
			(xy 11.668978 -39.459158) (xy 11.647714 -39.459158) (xy 11.637772 -39.462964) (xy 11.595102 -39.481191)
			(xy 11.506813 -39.50974) (xy 11.41603 -39.528938) (xy 11.323741 -39.538577) (xy 11.277346 -39.539164)
			(xy 11.236239 -39.538691) (xy 11.154376 -39.531107) (xy 11.073562 -39.516002) (xy 10.994486 -39.493507)
			(xy 10.917822 -39.463813) (xy 10.844225 -39.427174) (xy 10.774321 -39.383901) (xy 10.708708 -39.334363)
			(xy 10.647944 -39.278985) (xy 10.592548 -39.218236) (xy 10.542992 -39.152637) (xy 10.499699 -39.082746)
			(xy 10.463039 -39.009158) (xy 10.433323 -38.932503) (xy 10.410805 -38.853433) (xy 10.395678 -38.772623)
			(xy 10.38807 -38.690763) (xy 10.387584 -38.649656) (xy 0.509016 -38.649656) (xy 0.509016 -44.263056)
			(xy 10.409936 -44.263056) (xy 10.410551 -44.216654) (xy 10.420245 -44.124356) (xy 10.439502 -44.033571)
			(xy 10.468113 -43.945286) (xy 10.48639 -43.90263) (xy 10.490221 -43.892696) (xy 10.490205 -43.871425)
			(xy 10.48639 -43.861482) (xy 10.468111 -43.818828) (xy 10.439523 -43.730537) (xy 10.42027 -43.639752)
			(xy 10.410563 -43.547458) (xy 10.409936 -43.501056) (xy 10.410389 -43.459945) (xy 10.417977 -43.378074)
			(xy 10.433088 -43.297253) (xy 10.455593 -43.218172) (xy 10.485301 -43.141504) (xy 10.521957 -43.067906)
			(xy 10.565248 -42.998004) (xy 10.614806 -42.932396) (xy 10.670207 -42.871641) (xy 10.730978 -42.816258)
			(xy 10.796601 -42.76672) (xy 10.866515 -42.723449) (xy 10.940124 -42.686815) (xy 11.0168 -42.65713)
			(xy 11.095889 -42.634648) (xy 11.176714 -42.619561) (xy 11.258587 -42.611997) (xy 11.299698 -42.611548)
			(xy 11.346094 -42.612127) (xy 11.438382 -42.621772) (xy 11.529166 -42.640969) (xy 11.617459 -42.669509)
			(xy 11.660124 -42.687748) (xy 11.670066 -42.691554) (xy 11.69133 -42.691554) (xy 11.701272 -42.687748)
			(xy 11.743936 -42.669507) (xy 11.832227 -42.640961) (xy 11.923012 -42.621767) (xy 12.015302 -42.612133)
			(xy 12.061698 -42.611548) (xy 12.102805 -42.612014) (xy 12.184668 -42.619599) (xy 12.265483 -42.634703)
			(xy 12.34456 -42.657198) (xy 12.421224 -42.686892) (xy 12.494822 -42.723532) (xy 12.564726 -42.766805)
			(xy 12.63034 -42.816342) (xy 12.691104 -42.871722) (xy 12.7465 -42.932471) (xy 12.796056 -42.998071)
			(xy 12.839349 -43.067963) (xy 12.876009 -43.141551) (xy 12.905724 -43.218207) (xy 12.928241 -43.297277)
			(xy 12.943367 -43.378088) (xy 12.950974 -43.459949) (xy 12.95146 -43.501056) (xy 12.95085 -43.547459)
			(xy 12.941154 -43.639756) (xy 12.921896 -43.730542) (xy 12.893284 -43.818826) (xy 12.875006 -43.861482)
			(xy 12.871227 -43.871432) (xy 12.87121 -43.892688) (xy 12.875006 -43.90263) (xy 12.893256 -43.945296)
			(xy 12.921852 -44.033582) (xy 12.941112 -44.124363) (xy 12.950829 -44.216655) (xy 12.95146 -44.263056)
			(xy 12.950994 -44.304167) (xy 12.95059 -44.308522) (xy 37.125148 -44.308522) (xy 37.125734 -44.262126)
			(xy 37.135377 -44.169838) (xy 37.154572 -44.079054) (xy 37.18311 -43.990761) (xy 37.201348 -43.948096)
			(xy 37.205143 -43.93815) (xy 37.205151 -43.91689) (xy 37.201348 -43.906948) (xy 37.183114 -43.864281)
			(xy 37.154566 -43.775991) (xy 37.13537 -43.685207) (xy 37.125734 -43.592918) (xy 37.125148 -43.546522)
			(xy 37.125734 -43.500126) (xy 37.135377 -43.407838) (xy 37.154572 -43.317054) (xy 37.18311 -43.228761)
			(xy 37.201348 -43.186096) (xy 37.205143 -43.17615) (xy 37.205151 -43.15489) (xy 37.201348 -43.144948)
			(xy 37.183114 -43.102281) (xy 37.154566 -43.013991) (xy 37.13537 -42.923207) (xy 37.125734 -42.830918)
			(xy 37.125148 -42.784522) (xy 37.125734 -42.738126) (xy 37.135377 -42.645838) (xy 37.154572 -42.555054)
			(xy 37.18311 -42.466761) (xy 37.201348 -42.424096) (xy 37.205143 -42.41415) (xy 37.205151 -42.39289)
			(xy 37.201348 -42.382948) (xy 37.183114 -42.340281) (xy 37.154566 -42.251991) (xy 37.13537 -42.161207)
			(xy 37.125734 -42.068918) (xy 37.125148 -42.022522) (xy 37.125652 -41.980174) (xy 37.133703 -41.89586)
			(xy 37.149732 -41.812694) (xy 37.173593 -41.731427) (xy 37.205072 -41.652797) (xy 37.243883 -41.577516)
			(xy 37.289673 -41.506264) (xy 37.342029 -41.439688) (xy 37.400477 -41.37839) (xy 37.464487 -41.322925)
			(xy 37.533479 -41.273796) (xy 37.606829 -41.231447) (xy 37.683872 -41.196263) (xy 37.763911 -41.168561)
			(xy 37.84622 -41.148593) (xy 37.930055 -41.13654) (xy 38.014656 -41.13251) (xy 38.099257 -41.13654)
			(xy 38.183092 -41.148593) (xy 38.265401 -41.168561) (xy 38.34544 -41.196263) (xy 38.422483 -41.231447)
			(xy 38.495833 -41.273796) (xy 38.564825 -41.322925) (xy 38.628835 -41.37839) (xy 38.687283 -41.439688)
			(xy 38.739639 -41.506264) (xy 38.785429 -41.577516) (xy 38.82424 -41.652797) (xy 38.855719 -41.731427)
			(xy 38.87958 -41.812694) (xy 38.895609 -41.89586) (xy 38.90366 -41.980174) (xy 38.904164 -42.022522)
			(xy 38.903557 -42.068917) (xy 38.89392 -42.161205) (xy 38.874731 -42.251989) (xy 38.846199 -42.340283)
			(xy 38.827964 -42.382948) (xy 38.824143 -42.392886) (xy 38.824151 -42.414154) (xy 38.827964 -42.424096)
			(xy 38.846213 -42.466756) (xy 38.874757 -42.555049) (xy 38.893949 -42.645835) (xy 38.90358 -42.738126)
			(xy 38.904164 -42.784522) (xy 38.903557 -42.830917) (xy 38.89392 -42.923205) (xy 38.874731 -43.013989)
			(xy 38.846199 -43.102283) (xy 38.827964 -43.144948) (xy 38.824143 -43.154886) (xy 38.824151 -43.176154)
			(xy 38.827964 -43.186096) (xy 38.846213 -43.228756) (xy 38.874757 -43.317049) (xy 38.893949 -43.407835)
			(xy 38.90358 -43.500126) (xy 38.904164 -43.546522) (xy 38.903557 -43.592917) (xy 38.89392 -43.685205)
			(xy 38.874731 -43.775989) (xy 38.846199 -43.864283) (xy 38.827964 -43.906948) (xy 38.824143 -43.916886)
			(xy 38.824151 -43.938154) (xy 38.827964 -43.948096) (xy 38.846213 -43.990756) (xy 38.874757 -44.079049)
			(xy 38.893949 -44.169835) (xy 38.90358 -44.262126) (xy 38.904164 -44.308522) (xy 38.90366 -44.35087)
			(xy 38.895609 -44.435184) (xy 38.87958 -44.51835) (xy 38.855719 -44.599617) (xy 38.82424 -44.678247)
			(xy 38.785429 -44.753528) (xy 38.739639 -44.82478) (xy 38.687283 -44.891356) (xy 38.628835 -44.952654)
			(xy 38.564825 -45.008119) (xy 38.495833 -45.057248) (xy 38.422483 -45.099597) (xy 38.34544 -45.134781)
			(xy 38.265401 -45.162483) (xy 38.183092 -45.182451) (xy 38.099257 -45.194504) (xy 38.014656 -45.198535)
			(xy 37.930055 -45.194504) (xy 37.84622 -45.182451) (xy 37.763911 -45.162483) (xy 37.683872 -45.134781)
			(xy 37.606829 -45.099597) (xy 37.533479 -45.057248) (xy 37.464487 -45.008119) (xy 37.400477 -44.952654)
			(xy 37.342029 -44.891356) (xy 37.289673 -44.82478) (xy 37.243883 -44.753528) (xy 37.205072 -44.678247)
			(xy 37.173593 -44.599617) (xy 37.149732 -44.51835) (xy 37.133703 -44.435184) (xy 37.125652 -44.35087)
			(xy 37.125148 -44.308522) (xy 12.95059 -44.308522) (xy 12.943406 -44.386037) (xy 12.928296 -44.466857)
			(xy 12.905791 -44.545939) (xy 12.876085 -44.622605) (xy 12.83943 -44.696204) (xy 12.796139 -44.766105)
			(xy 12.746583 -44.831713) (xy 12.691183 -44.892468) (xy 12.630412 -44.947851) (xy 12.564791 -44.99739)
			(xy 12.494877 -45.040661) (xy 12.421268 -45.077295) (xy 12.344593 -45.10698) (xy 12.265506 -45.129463)
			(xy 12.184681 -45.144551) (xy 12.102809 -45.152115) (xy 12.061698 -45.152564) (xy 12.015302 -45.151986)
			(xy 11.923014 -45.14234) (xy 11.83223 -45.123143) (xy 11.743937 -45.094603) (xy 11.701272 -45.076364)
			(xy 11.69133 -45.072558) (xy 11.670066 -45.072558) (xy 11.660124 -45.076364) (xy 11.617461 -45.094607)
			(xy 11.529169 -45.123152) (xy 11.438384 -45.142346) (xy 11.346094 -45.151979) (xy 11.299698 -45.152564)
			(xy 11.258591 -45.152089) (xy 11.176728 -45.144505) (xy 11.095914 -45.129401) (xy 11.016838 -45.106906)
			(xy 10.940174 -45.077212) (xy 10.866577 -45.040572) (xy 10.796673 -44.9973) (xy 10.73106 -44.947763)
			(xy 10.670296 -44.892384) (xy 10.6149 -44.831636) (xy 10.565344 -44.766036) (xy 10.522051 -44.696145)
			(xy 10.485391 -44.622558) (xy 10.455675 -44.545903) (xy 10.433157 -44.466833) (xy 10.41803 -44.386023)
			(xy 10.410422 -44.304163) (xy 10.409936 -44.263056) (xy 0.509016 -44.263056) (xy 0.509016 -46.391322)
			(xy 7.843012 -46.391322) (xy 7.843601 -46.344927) (xy 7.853244 -46.252638) (xy 7.872438 -46.161855)
			(xy 7.900975 -46.073561) (xy 7.919212 -46.030896) (xy 7.923003 -46.02095) (xy 7.923012 -45.99969)
			(xy 7.919212 -45.989748) (xy 7.900976 -45.947082) (xy 7.872429 -45.858791) (xy 7.853234 -45.768007)
			(xy 7.843598 -45.675718) (xy 7.843012 -45.629322) (xy 7.843516 -45.586974) (xy 7.851567 -45.50266)
			(xy 7.867596 -45.419494) (xy 7.891457 -45.338227) (xy 7.922936 -45.259597) (xy 7.961747 -45.184316)
			(xy 8.007537 -45.113064) (xy 8.059893 -45.046488) (xy 8.118341 -44.98519) (xy 8.182351 -44.929725)
			(xy 8.251343 -44.880596) (xy 8.324693 -44.838247) (xy 8.401736 -44.803063) (xy 8.481775 -44.775361)
			(xy 8.564084 -44.755393) (xy 8.647919 -44.74334) (xy 8.73252 -44.73931) (xy 8.817121 -44.74334) (xy 8.900956 -44.755393)
			(xy 8.983265 -44.775361) (xy 9.063304 -44.803063) (xy 9.140347 -44.838247) (xy 9.213697 -44.880596)
			(xy 9.282689 -44.929725) (xy 9.346699 -44.98519) (xy 9.405147 -45.046488) (xy 9.457503 -45.113064)
			(xy 9.503293 -45.184316) (xy 9.542104 -45.259597) (xy 9.573583 -45.338227) (xy 9.597444 -45.419494)
			(xy 9.613473 -45.50266) (xy 9.621524 -45.586974) (xy 9.622028 -45.629322) (xy 9.621416 -45.675717)
			(xy 9.611779 -45.768004) (xy 9.592592 -45.858788) (xy 9.564062 -45.947082) (xy 9.545828 -45.989748)
			(xy 9.542008 -45.999686) (xy 9.542017 -46.020954) (xy 9.545828 -46.030896) (xy 9.564081 -46.073555)
			(xy 9.592623 -46.161848) (xy 9.611813 -46.252635) (xy 9.621444 -46.344926) (xy 9.622028 -46.391322)
			(xy 9.621548 -46.434206) (xy 9.613284 -46.519576) (xy 9.596844 -46.603755) (xy 9.572382 -46.685961)
			(xy 9.540123 -46.765432) (xy 9.500367 -46.841431) (xy 9.453484 -46.913252) (xy 9.399908 -46.980229)
			(xy 9.340136 -47.04174) (xy 9.274724 -47.097215) (xy 9.204277 -47.146139) (xy 9.167114 -47.167546)
			(xy 9.154668 -47.174658) (xy 9.140698 -47.198788) (xy 9.143746 -47.317152) (xy 9.158478 -47.340774)
			(xy 9.171432 -47.347124) (xy 9.207964 -47.3659) (xy 9.277759 -47.409217) (xy 9.343264 -47.458783)
			(xy 9.403921 -47.514175) (xy 9.459215 -47.574923) (xy 9.508673 -47.640508) (xy 9.551877 -47.710373)
			(xy 9.588457 -47.783923) (xy 9.618102 -47.860531) (xy 9.640559 -47.939546) (xy 9.655638 -48.020294)
			(xy 9.663211 -48.102088) (xy 9.663684 -48.14316) (xy 9.663089 -48.189555) (xy 9.653448 -48.281843)
			(xy 9.634255 -48.372627) (xy 9.60572 -48.460921) (xy 9.587484 -48.503586) (xy 9.583703 -48.513536)
			(xy 9.583688 -48.534792) (xy 9.587484 -48.544734) (xy 9.605714 -48.587402) (xy 9.634262 -48.675692)
			(xy 9.65346 -48.766475) (xy 9.663097 -48.858764) (xy 9.663684 -48.90516) (xy 9.663201 -48.947324)
			(xy 9.655208 -49.031272) (xy 9.63931 -49.114087) (xy 9.615649 -49.195027) (xy 9.584436 -49.273366)
			(xy 9.545953 -49.348401) (xy 9.500544 -49.419458) (xy 9.448617 -49.485902) (xy 9.390637 -49.547135)
			(xy 9.327125 -49.602608) (xy 9.258649 -49.651824) (xy 9.222486 -49.67351) (xy 9.210802 -49.680368)
			(xy 9.197594 -49.703228) (xy 9.196324 -49.817782) (xy 9.209278 -49.840896) (xy 9.220962 -49.848008)
			(xy 9.256057 -49.86996) (xy 9.322433 -49.919432) (xy 9.383925 -49.974859) (xy 9.44 -50.03576) (xy 9.490173 -50.101608)
			(xy 9.53401 -50.171834) (xy 9.571132 -50.245829) (xy 9.601217 -50.322954) (xy 9.624005 -50.402541)
			(xy 9.639299 -50.4839) (xy 9.646967 -50.566329) (xy 9.647428 -50.607722) (xy 9.646816 -50.654117)
			(xy 9.637179 -50.746404) (xy 9.617992 -50.837188) (xy 9.589462 -50.925482) (xy 9.571228 -50.968148)
			(xy 9.567408 -50.978086) (xy 9.567417 -50.999354) (xy 9.571228 -51.009296) (xy 9.589481 -51.051955)
			(xy 9.618023 -51.140248) (xy 9.637213 -51.231035) (xy 9.646844 -51.323326) (xy 9.647428 -51.369722)
			(xy 9.646924 -51.41207) (xy 9.638873 -51.496384) (xy 9.622844 -51.57955) (xy 9.598983 -51.660817)
			(xy 9.567504 -51.739447) (xy 9.528693 -51.814728) (xy 9.482903 -51.88598) (xy 9.430547 -51.952556)
			(xy 9.372099 -52.013854) (xy 9.308089 -52.069319) (xy 9.239097 -52.118448) (xy 9.165747 -52.160797)
			(xy 9.088704 -52.195981) (xy 9.008665 -52.223683) (xy 8.926356 -52.243651) (xy 8.842521 -52.255704)
			(xy 8.75792 -52.259735) (xy 8.673319 -52.255704) (xy 8.589484 -52.243651) (xy 8.507175 -52.223683)
			(xy 8.427136 -52.195981) (xy 8.350093 -52.160797) (xy 8.276743 -52.118448) (xy 8.207751 -52.069319)
			(xy 8.143741 -52.013854) (xy 8.085293 -51.952556) (xy 8.032937 -51.88598) (xy 7.987147 -51.814728)
			(xy 7.948336 -51.739447) (xy 7.916857 -51.660817) (xy 7.892996 -51.57955) (xy 7.876967 -51.496384)
			(xy 7.868916 -51.41207) (xy 7.868412 -51.369722) (xy 7.869001 -51.323327) (xy 7.878644 -51.231038)
			(xy 7.897838 -51.140255) (xy 7.926375 -51.051961) (xy 7.944612 -51.009296) (xy 7.948403 -50.99935)
			(xy 7.948412 -50.97809) (xy 7.944612 -50.968148) (xy 7.926376 -50.925482) (xy 7.897829 -50.837191)
			(xy 7.878634 -50.746407) (xy 7.868998 -50.654118) (xy 7.868412 -50.607722) (xy 7.868883 -50.565558)
			(xy 7.876877 -50.48161) (xy 7.892777 -50.398794) (xy 7.916439 -50.317854) (xy 7.947653 -50.239515)
			(xy 7.986137 -50.16448) (xy 8.031547 -50.093423) (xy 8.083476 -50.02698) (xy 8.141457 -49.965747)
			(xy 8.20497 -49.910274) (xy 8.273447 -49.861058) (xy 8.30961 -49.839372) (xy 8.321294 -49.832514)
			(xy 8.334502 -49.809654) (xy 8.335772 -49.6951) (xy 8.322818 -49.671986) (xy 8.311134 -49.664874)
			(xy 8.276036 -49.642926) (xy 8.20966 -49.593453) (xy 8.148169 -49.538026) (xy 8.092093 -49.477125)
			(xy 8.04192 -49.411276) (xy 7.998083 -49.34105) (xy 7.960962 -49.267054) (xy 7.930877 -49.189929)
			(xy 7.908089 -49.110342) (xy 7.892796 -49.028982) (xy 7.885129 -48.946553) (xy 7.884668 -48.90516)
			(xy 7.885274 -48.858765) (xy 7.894913 -48.766477) (xy 7.914102 -48.675694) (xy 7.942634 -48.587399)
			(xy 7.960868 -48.544734) (xy 7.964699 -48.534799) (xy 7.964683 -48.513528) (xy 7.960868 -48.503586)
			(xy 7.942609 -48.46093) (xy 7.914069 -48.372635) (xy 7.89488 -48.281848) (xy 7.885251 -48.189557)
			(xy 7.884668 -48.14316) (xy 7.885135 -48.100275) (xy 7.893401 -48.014905) (xy 7.909842 -47.930726)
			(xy 7.934306 -47.84852) (xy 7.966567 -47.769049) (xy 8.006323 -47.69305) (xy 8.053208 -47.621229)
			(xy 8.106785 -47.554252) (xy 8.166558 -47.492741) (xy 8.231971 -47.437267) (xy 8.302419 -47.388343)
			(xy 8.339582 -47.366936) (xy 8.352028 -47.359824) (xy 8.365998 -47.335694) (xy 8.36295 -47.21733)
			(xy 8.348218 -47.193708) (xy 8.335264 -47.187358) (xy 8.298736 -47.168575) (xy 8.228941 -47.125258)
			(xy 8.163437 -47.075693) (xy 8.10278 -47.020301) (xy 8.047486 -46.959554) (xy 7.998027 -46.89397)
			(xy 7.954823 -46.824105) (xy 7.918243 -46.750556) (xy 7.888598 -46.673949) (xy 7.866139 -46.594935)
			(xy 7.851059 -46.514187) (xy 7.843486 -46.432394) (xy 7.843012 -46.391322) (xy 0.509016 -46.391322)
			(xy 0.509016 -53.448712) (xy 6.524752 -53.448712) (xy 6.52535 -53.402309) (xy 6.535049 -53.310011)
			(xy 6.554311 -53.219226) (xy 6.582926 -53.130941) (xy 6.601206 -53.088286) (xy 6.605004 -53.078341)
			(xy 6.605008 -53.05708) (xy 6.601206 -53.047138) (xy 6.582946 -53.004476) (xy 6.554353 -52.916188)
			(xy 6.535095 -52.825406) (xy 6.525382 -52.733113) (xy 6.524752 -52.686712) (xy 6.525256 -52.644351)
			(xy 6.533309 -52.560014) (xy 6.549343 -52.476824) (xy 6.573211 -52.395534) (xy 6.604699 -52.316882)
			(xy 6.643521 -52.241579) (xy 6.689324 -52.170307) (xy 6.741695 -52.103711) (xy 6.80016 -52.042396)
			(xy 6.864188 -51.986915) (xy 6.9332 -51.937772) (xy 7.00657 -51.895412) (xy 7.083635 -51.860217)
			(xy 7.163697 -51.832508) (xy 7.24603 -51.812534) (xy 7.329889 -51.800477) (xy 7.414514 -51.796446)
			(xy 7.499139 -51.800477) (xy 7.582998 -51.812534) (xy 7.665331 -51.832508) (xy 7.745393 -51.860217)
			(xy 7.822458 -51.895412) (xy 7.895828 -51.937772) (xy 7.96484 -51.986915) (xy 8.028868 -52.042396)
			(xy 8.087333 -52.103711) (xy 8.139704 -52.170307) (xy 8.185507 -52.241579) (xy 8.224329 -52.316882)
			(xy 8.255817 -52.395534) (xy 8.279685 -52.476824) (xy 8.295719 -52.560014) (xy 8.303772 -52.644351)
			(xy 8.304276 -52.686712) (xy 8.303649 -52.733114) (xy 8.293958 -52.825411) (xy 8.274705 -52.916197)
			(xy 8.265527 -52.944522) (xy 40.985948 -52.944522) (xy 40.986534 -52.898126) (xy 40.996177 -52.805838)
			(xy 41.015372 -52.715054) (xy 41.04391 -52.626761) (xy 41.062148 -52.584096) (xy 41.065943 -52.57415)
			(xy 41.065951 -52.55289) (xy 41.062148 -52.542948) (xy 41.043914 -52.500281) (xy 41.015366 -52.411991)
			(xy 40.99617 -52.321207) (xy 40.986534 -52.228918) (xy 40.985948 -52.182522) (xy 40.986456 -52.139301)
			(xy 40.99482 -52.053265) (xy 41.01149 -51.968446) (xy 41.036308 -51.885644) (xy 41.069042 -51.80564)
			(xy 41.109382 -51.729188) (xy 41.156948 -51.65701) (xy 41.21129 -51.589786) (xy 41.271897 -51.528151)
			(xy 41.304718 -51.500024) (xy 41.313354 -51.492912) (xy 41.322752 -51.473354) (xy 41.324276 -51.37404)
			(xy 41.31564 -51.353974) (xy 41.307258 -51.346608) (xy 41.276644 -51.318528) (xy 41.220205 -51.257563)
			(xy 41.169699 -51.1916) (xy 41.125564 -51.121215) (xy 41.088186 -51.04702) (xy 41.05789 -50.969663)
			(xy 41.034941 -50.889818) (xy 41.019538 -50.80818) (xy 41.011816 -50.725461) (xy 41.011348 -50.683922)
			(xy 41.011934 -50.637526) (xy 41.021577 -50.545238) (xy 41.040772 -50.454454) (xy 41.06931 -50.366161)
			(xy 41.087548 -50.323496) (xy 41.091343 -50.31355) (xy 41.091351 -50.29229) (xy 41.087548 -50.282348)
			(xy 41.069314 -50.239681) (xy 41.040766 -50.151391) (xy 41.02157 -50.060607) (xy 41.011934 -49.968318)
			(xy 41.011348 -49.921922) (xy 41.011872 -49.878278) (xy 41.020417 -49.79141) (xy 41.037428 -49.705796)
			(xy 41.062742 -49.622259) (xy 41.096114 -49.541602) (xy 41.137223 -49.464601) (xy 41.185676 -49.391996)
			(xy 41.241006 -49.324485) (xy 41.30268 -49.262716) (xy 41.370107 -49.207284) (xy 41.442639 -49.158721)
			(xy 41.519577 -49.117494) (xy 41.600183 -49.083999) (xy 41.641776 -49.070768) (xy 41.657524 -49.065942)
			(xy 41.677336 -49.040034) (xy 41.680892 -48.910748) (xy 41.662604 -48.883824) (xy 41.64711 -48.878236)
			(xy 41.60801 -48.863456) (xy 41.532505 -48.82758) (xy 41.460698 -48.784781) (xy 41.393222 -48.735435)
			(xy 41.330672 -48.679977) (xy 41.273599 -48.618897) (xy 41.222507 -48.552733) (xy 41.177846 -48.482069)
			(xy 41.14001 -48.407527) (xy 41.109332 -48.329765) (xy 41.086084 -48.249468) (xy 41.070469 -48.167345)
			(xy 41.062626 -48.084119) (xy 41.062148 -48.042322) (xy 41.062734 -47.995926) (xy 41.072377 -47.903638)
			(xy 41.091572 -47.812854) (xy 41.12011 -47.724561) (xy 41.138348 -47.681896) (xy 41.142143 -47.67195)
			(xy 41.142151 -47.65069) (xy 41.138348 -47.640748) (xy 41.120114 -47.598081) (xy 41.091566 -47.509791)
			(xy 41.07237 -47.419007) (xy 41.062734 -47.326718) (xy 41.062148 -47.280322) (xy 41.062652 -47.237974)
			(xy 41.070703 -47.15366) (xy 41.086732 -47.070494) (xy 41.110593 -46.989227) (xy 41.142072 -46.910597)
			(xy 41.180883 -46.835316) (xy 41.226673 -46.764064) (xy 41.279029 -46.697488) (xy 41.337477 -46.63619)
			(xy 41.401487 -46.580725) (xy 41.470479 -46.531596) (xy 41.543829 -46.489247) (xy 41.620872 -46.454063)
			(xy 41.700911 -46.426361) (xy 41.78322 -46.406393) (xy 41.867055 -46.39434) (xy 41.951656 -46.39031)
			(xy 42.036257 -46.39434) (xy 42.120092 -46.406393) (xy 42.202401 -46.426361) (xy 42.28244 -46.454063)
			(xy 42.359483 -46.489247) (xy 42.432833 -46.531596) (xy 42.501825 -46.580725) (xy 42.565835 -46.63619)
			(xy 42.624283 -46.697488) (xy 42.676639 -46.764064) (xy 42.722429 -46.835316) (xy 42.76124 -46.910597)
			(xy 42.792719 -46.989227) (xy 42.81658 -47.070494) (xy 42.832609 -47.15366) (xy 42.84066 -47.237974)
			(xy 42.841164 -47.280322) (xy 42.840557 -47.326717) (xy 42.83092 -47.419005) (xy 42.811731 -47.509789)
			(xy 42.783199 -47.598083) (xy 42.764964 -47.640748) (xy 42.761143 -47.650686) (xy 42.761151 -47.671954)
			(xy 42.764964 -47.681896) (xy 42.783213 -47.724556) (xy 42.811757 -47.812849) (xy 42.830949 -47.903635)
			(xy 42.84058 -47.995926) (xy 42.841164 -48.042322) (xy 42.840581 -48.085965) (xy 42.832041 -48.172831)
			(xy 42.815035 -48.258443) (xy 42.789727 -48.341979) (xy 42.756361 -48.422635) (xy 42.715256 -48.499635)
			(xy 42.666809 -48.57224) (xy 42.611484 -48.639752) (xy 42.549814 -48.701522) (xy 42.482391 -48.756955)
			(xy 42.409864 -48.805519) (xy 42.33293 -48.846748) (xy 42.252328 -48.880244) (xy 42.210736 -48.893476)
			(xy 42.194988 -48.898302) (xy 42.175176 -48.92421) (xy 42.17162 -49.053496) (xy 42.189908 -49.08042)
			(xy 42.205402 -49.086008) (xy 42.244519 -49.100744) (xy 42.320025 -49.136623) (xy 42.391833 -49.179426)
			(xy 42.45931 -49.228776) (xy 42.52186 -49.284237) (xy 42.578932 -49.345321) (xy 42.630023 -49.411489)
			(xy 42.674683 -49.482157) (xy 42.712517 -49.556702) (xy 42.743192 -49.634468) (xy 42.766437 -49.714768)
			(xy 42.782049 -49.796895) (xy 42.789888 -49.880123) (xy 42.790364 -49.921922) (xy 42.789757 -49.968317)
			(xy 42.78012 -50.060605) (xy 42.760931 -50.151389) (xy 42.732399 -50.239683) (xy 42.714164 -50.282348)
			(xy 42.710343 -50.292286) (xy 42.710351 -50.313554) (xy 42.714164 -50.323496) (xy 42.732413 -50.366156)
			(xy 42.760957 -50.454449) (xy 42.780149 -50.545235) (xy 42.78978 -50.637526) (xy 42.790364 -50.683922)
			(xy 42.789883 -50.727144) (xy 42.781515 -50.813181) (xy 42.764842 -50.898) (xy 42.740019 -50.980802)
			(xy 42.707282 -51.060807) (xy 42.666939 -51.137258) (xy 42.619371 -51.209436) (xy 42.565025 -51.276659)
			(xy 42.504416 -51.338294) (xy 42.471594 -51.36642) (xy 42.462958 -51.373532) (xy 42.45356 -51.39309)
			(xy 42.452036 -51.492404) (xy 42.460672 -51.51247) (xy 42.469054 -51.519836) (xy 42.499692 -51.547891)
			(xy 42.556129 -51.608859) (xy 42.606634 -51.674825) (xy 42.650766 -51.745214) (xy 42.688142 -51.819412)
			(xy 42.718435 -51.896773) (xy 42.741381 -51.976621) (xy 42.75678 -52.058261) (xy 42.764498 -52.140982)
			(xy 42.764964 -52.182522) (xy 42.764357 -52.228917) (xy 42.75472 -52.321205) (xy 42.735531 -52.411989)
			(xy 42.706999 -52.500283) (xy 42.688764 -52.542948) (xy 42.684943 -52.552886) (xy 42.684951 -52.574154)
			(xy 42.688764 -52.584096) (xy 42.707013 -52.626756) (xy 42.735557 -52.715049) (xy 42.754749 -52.805835)
			(xy 42.76438 -52.898126) (xy 42.764964 -52.944522) (xy 42.764411 -52.98961) (xy 42.75534 -53.079327)
			(xy 42.737232 -53.167664) (xy 42.710273 -53.253714) (xy 42.674742 -53.336593) (xy 42.631001 -53.415449)
			(xy 42.605706 -53.452776) (xy 42.596816 -53.465222) (xy 42.596054 -53.49494) (xy 42.660062 -53.600604)
			(xy 42.686732 -53.613558) (xy 42.701972 -53.611526) (xy 42.730168 -53.608102) (xy 42.786854 -53.604417)
			(xy 42.815256 -53.60416) (xy 42.856365 -53.604694) (xy 42.938232 -53.612278) (xy 43.019051 -53.627384)
			(xy 43.09813 -53.649885) (xy 43.174795 -53.679587) (xy 43.248392 -53.716237) (xy 43.318293 -53.759523)
			(xy 43.3839 -53.809075) (xy 43.444655 -53.864471) (xy 43.500038 -53.925237) (xy 43.549577 -53.990854)
			(xy 43.59285 -54.060763) (xy 43.629485 -54.134368) (xy 43.659172 -54.211039) (xy 43.681657 -54.290123)
			(xy 43.696747 -54.370944) (xy 43.704314 -54.452813) (xy 43.704764 -54.493922) (xy 43.704157 -54.540317)
			(xy 43.69452 -54.632605) (xy 43.675331 -54.723389) (xy 43.646799 -54.811683) (xy 43.628564 -54.854348)
			(xy 43.624743 -54.864286) (xy 43.624751 -54.885554) (xy 43.628564 -54.895496) (xy 43.646813 -54.938156)
			(xy 43.675357 -55.026449) (xy 43.694549 -55.117235) (xy 43.70418 -55.209526) (xy 43.704764 -55.255922)
			(xy 43.70426 -55.29827) (xy 43.696209 -55.382584) (xy 43.68018 -55.46575) (xy 43.656319 -55.547017)
			(xy 43.62484 -55.625647) (xy 43.586029 -55.700928) (xy 43.540239 -55.77218) (xy 43.487883 -55.838756)
			(xy 43.429435 -55.900054) (xy 43.365425 -55.955519) (xy 43.296433 -56.004648) (xy 43.223083 -56.046997)
			(xy 43.14604 -56.082181) (xy 43.066001 -56.109883) (xy 42.983692 -56.129851) (xy 42.899857 -56.141904)
			(xy 42.815256 -56.145935) (xy 42.730655 -56.141904) (xy 42.64682 -56.129851) (xy 42.564511 -56.109883)
			(xy 42.484472 -56.082181) (xy 42.407429 -56.046997) (xy 42.334079 -56.004648) (xy 42.265087 -55.955519)
			(xy 42.201077 -55.900054) (xy 42.142629 -55.838756) (xy 42.090273 -55.77218) (xy 42.044483 -55.700928)
			(xy 42.005672 -55.625647) (xy 41.974193 -55.547017) (xy 41.950332 -55.46575) (xy 41.934303 -55.382584)
			(xy 41.926252 -55.29827) (xy 41.925748 -55.255922) (xy 41.926334 -55.209526) (xy 41.935977 -55.117238)
			(xy 41.955172 -55.026454) (xy 41.98371 -54.938161) (xy 42.001948 -54.895496) (xy 42.005743 -54.88555)
			(xy 42.005751 -54.86429) (xy 42.001948 -54.854348) (xy 41.983714 -54.811681) (xy 41.955166 -54.723391)
			(xy 41.93597 -54.632607) (xy 41.926334 -54.540318) (xy 41.925748 -54.493922) (xy 41.92627 -54.448834)
			(xy 41.935347 -54.359116) (xy 41.95346 -54.270777) (xy 41.980425 -54.184727) (xy 42.015962 -54.101849)
			(xy 42.059708 -54.022994) (xy 42.085006 -53.985668) (xy 42.093896 -53.973222) (xy 42.094658 -53.943504)
			(xy 42.03065 -53.83784) (xy 42.00398 -53.824886) (xy 41.98874 -53.826918) (xy 41.960544 -53.830341)
			(xy 41.903858 -53.834027) (xy 41.875456 -53.834284) (xy 41.834344 -53.833889) (xy 41.752471 -53.826297)
			(xy 41.671648 -53.811182) (xy 41.592565 -53.788673) (xy 41.515897 -53.758962) (xy 41.442297 -53.722302)
			(xy 41.372395 -53.679007) (xy 41.306786 -53.629445) (xy 41.246032 -53.57404) (xy 41.190649 -53.513266)
			(xy 41.141111 -53.447639) (xy 41.097841 -53.377721) (xy 41.061208 -53.304109) (xy 41.031525 -53.22743)
			(xy 41.009044 -53.148338) (xy 40.993958 -53.06751) (xy 40.986396 -52.985634) (xy 40.985948 -52.944522)
			(xy 8.265527 -52.944522) (xy 8.246097 -53.004482) (xy 8.227822 -53.047138) (xy 8.224009 -53.057078)
			(xy 8.224013 -53.078344) (xy 8.227822 -53.088286) (xy 8.246092 -53.130944) (xy 8.274682 -53.219233)
			(xy 8.293937 -53.310017) (xy 8.303648 -53.402311) (xy 8.304276 -53.448712) (xy 8.303772 -53.491073)
			(xy 8.295719 -53.57541) (xy 8.279685 -53.6586) (xy 8.255817 -53.73989) (xy 8.224329 -53.818542) (xy 8.185507 -53.893845)
			(xy 8.139704 -53.965117) (xy 8.087333 -54.031713) (xy 8.028868 -54.093028) (xy 7.96484 -54.148509)
			(xy 7.895828 -54.197652) (xy 7.822458 -54.240012) (xy 7.745393 -54.275207) (xy 7.665331 -54.302916)
			(xy 7.582998 -54.32289) (xy 7.499139 -54.334947) (xy 7.414514 -54.338979) (xy 7.329889 -54.334947)
			(xy 7.24603 -54.32289) (xy 7.163697 -54.302916) (xy 7.083635 -54.275207) (xy 7.00657 -54.240012)
			(xy 6.9332 -54.197652) (xy 6.864188 -54.148509) (xy 6.80016 -54.093028) (xy 6.741695 -54.031713)
			(xy 6.689324 -53.965117) (xy 6.643521 -53.893845) (xy 6.604699 -53.818542) (xy 6.573211 -53.73989)
			(xy 6.549343 -53.6586) (xy 6.533309 -53.57541) (xy 6.525256 -53.491073) (xy 6.524752 -53.448712)
			(xy 0.509016 -53.448712) (xy 0.509016 -58.913776) (xy 2.815336 -58.913776) (xy 2.815734 -58.875486)
			(xy 2.822344 -58.799192) (xy 2.835496 -58.723749) (xy 2.855091 -58.649719) (xy 2.86766 -58.613548)
			(xy 2.870323 -58.605114) (xy 2.870315 -58.587441) (xy 2.86766 -58.579004) (xy 2.855117 -58.542826)
			(xy 2.835544 -58.468793) (xy 2.822397 -58.393354) (xy 2.815772 -58.317064) (xy 2.815336 -58.278776)
			(xy 2.815789 -58.237665) (xy 2.823377 -58.155794) (xy 2.838488 -58.074973) (xy 2.860993 -57.995892)
			(xy 2.890701 -57.919224) (xy 2.927357 -57.845626) (xy 2.970648 -57.775724) (xy 3.020206 -57.710116)
			(xy 3.075607 -57.649361) (xy 3.136378 -57.593978) (xy 3.202001 -57.54444) (xy 3.271915 -57.501169)
			(xy 3.345524 -57.464535) (xy 3.4222 -57.43485) (xy 3.501289 -57.412368) (xy 3.582114 -57.397281)
			(xy 3.663987 -57.389717) (xy 3.705098 -57.389268) (xy 3.744024 -57.38968) (xy 3.821581 -57.396458)
			(xy 3.898248 -57.409989) (xy 3.97344 -57.430169) (xy 4.010152 -57.443116) (xy 4.018701 -57.44588)
			(xy 4.036655 -57.44588) (xy 4.045204 -57.443116) (xy 4.081915 -57.430165) (xy 4.157107 -57.409985)
			(xy 4.233775 -57.396453) (xy 4.311332 -57.389672) (xy 4.350258 -57.389268) (xy 4.389185 -57.389662)
			(xy 4.466742 -57.396445) (xy 4.543409 -57.409981) (xy 4.6186 -57.430167) (xy 4.655312 -57.443116)
			(xy 4.663861 -57.44588) (xy 4.681815 -57.44588) (xy 4.690364 -57.443116) (xy 4.727079 -57.430176)
			(xy 4.802269 -57.409993) (xy 4.878936 -57.396458) (xy 4.956492 -57.389674) (xy 4.995418 -57.389268)
			(xy 5.036525 -57.389744) (xy 5.118388 -57.397329) (xy 5.199202 -57.412432) (xy 5.278278 -57.434927)
			(xy 5.354942 -57.464621) (xy 5.428539 -57.50126) (xy 5.498443 -57.544533) (xy 5.564057 -57.59407)
			(xy 5.624821 -57.649448) (xy 5.680217 -57.710196) (xy 5.729773 -57.775796) (xy 5.773065 -57.845687)
			(xy 5.809726 -57.919274) (xy 5.839442 -57.995929) (xy 5.861959 -58.074999) (xy 5.877086 -58.155809)
			(xy 5.884694 -58.237669) (xy 5.88518 -58.278776) (xy 5.884767 -58.317066) (xy 5.878161 -58.39336)
			(xy 5.865014 -58.468802) (xy 5.845423 -58.542833) (xy 5.832856 -58.579004) (xy 5.830217 -58.587444)
			(xy 5.830209 -58.605112) (xy 5.832856 -58.613548) (xy 5.839714 -58.63336) (xy 5.84454 -58.647838)
			(xy 5.868162 -58.666634) (xy 5.991098 -58.67781) (xy 6.017768 -58.663586) (xy 6.025134 -58.650378)
			(xy 6.046362 -58.612722) (xy 6.095116 -58.541331) (xy 6.150565 -58.475008) (xy 6.212188 -58.414376)
			(xy 6.279401 -58.360008) (xy 6.351572 -58.312417) (xy 6.428019 -58.272052) (xy 6.508022 -58.239294)
			(xy 6.590825 -58.214451) (xy 6.675647 -58.197758) (xy 6.761689 -58.189373) (xy 6.804914 -58.18886)
			(xy 6.843846 -58.189297) (xy 6.921408 -58.196139) (xy 6.998076 -58.209736) (xy 7.073261 -58.229982)
			(xy 7.109968 -58.242962) (xy 7.118517 -58.245726) (xy 7.136471 -58.245726) (xy 7.14502 -58.242962)
			(xy 7.181726 -58.229981) (xy 7.256913 -58.209741) (xy 7.333581 -58.196145) (xy 7.411142 -58.189298)
			(xy 7.450074 -58.18886) (xy 7.489005 -58.189309) (xy 7.566568 -58.196148) (xy 7.643235 -58.209741)
			(xy 7.718421 -58.229984) (xy 7.755128 -58.242962) (xy 7.763677 -58.245726) (xy 7.781631 -58.245726)
			(xy 7.79018 -58.242962) (xy 7.82689 -58.229993) (xy 7.902076 -58.209749) (xy 7.978742 -58.19615)
			(xy 8.056303 -58.1893) (xy 8.095234 -58.18886) (xy 8.136348 -58.189329) (xy 8.218226 -58.196917)
			(xy 8.299055 -58.212026) (xy 8.378144 -58.23453) (xy 8.45482 -58.264234) (xy 8.528428 -58.300887)
			(xy 8.59834 -58.344175) (xy 8.66396 -58.393729) (xy 8.724728 -58.449127) (xy 8.750967 -58.47791)
			(xy 9.058409 -58.47791) (xy 9.06244 -58.393309) (xy 9.074493 -58.309475) (xy 9.094461 -58.227165)
			(xy 9.122163 -58.147127) (xy 9.157347 -58.070084) (xy 9.199695 -57.996735) (xy 9.248824 -57.927743)
			(xy 9.304288 -57.863733) (xy 9.365586 -57.805286) (xy 9.432162 -57.75293) (xy 9.503414 -57.707139)
			(xy 9.578695 -57.668329) (xy 9.657325 -57.63685) (xy 9.73859 -57.612988) (xy 9.821756 -57.596959)
			(xy 9.90607 -57.588908) (xy 9.948418 -57.588404) (xy 9.994814 -57.588979) (xy 10.087102 -57.598627)
			(xy 10.177886 -57.617825) (xy 10.266179 -57.646365) (xy 10.308844 -57.664604) (xy 10.318786 -57.66841)
			(xy 10.34005 -57.66841) (xy 10.349992 -57.664604) (xy 10.392652 -57.646354) (xy 10.480945 -57.617811)
			(xy 10.571731 -57.59862) (xy 10.664022 -57.588988) (xy 10.710418 -57.588404) (xy 10.752003 -57.588903)
			(xy 10.834811 -57.596646) (xy 10.916535 -57.612083) (xy 10.996463 -57.635078) (xy 11.073896 -57.66543)
			(xy 11.148159 -57.702875) (xy 11.218604 -57.747086) (xy 11.284616 -57.797678) (xy 11.34562 -57.854208)
			(xy 11.401083 -57.916184) (xy 11.42619 -57.949338) (xy 11.433302 -57.959244) (xy 11.454892 -57.970166)
			(xy 11.561064 -57.969912) (xy 11.582654 -57.95899) (xy 11.589766 -57.949084) (xy 11.614799 -57.915623)
			(xy 11.670256 -57.853101) (xy 11.731334 -57.796058) (xy 11.797494 -57.744996) (xy 11.868153 -57.700367)
			(xy 11.942687 -57.662563) (xy 12.020439 -57.631918) (xy 12.100722 -57.608702) (xy 12.18283 -57.59312)
			(xy 12.266037 -57.58531) (xy 12.307824 -57.584848) (xy 12.354219 -57.585453) (xy 12.446507 -57.595091)
			(xy 12.537291 -57.61428) (xy 12.625585 -57.642813) (xy 12.66825 -57.661048) (xy 12.678192 -57.664854)
			(xy 12.699456 -57.664854) (xy 12.709398 -57.661048) (xy 12.752058 -57.642799) (xy 12.840351 -57.614255)
			(xy 12.931137 -57.595063) (xy 13.023428 -57.585432) (xy 13.069824 -57.584848) (xy 13.116219 -57.585453)
			(xy 13.208507 -57.595091) (xy 13.299291 -57.61428) (xy 13.387585 -57.642813) (xy 13.43025 -57.661048)
			(xy 13.440192 -57.664854) (xy 13.461456 -57.664854) (xy 13.471398 -57.661048) (xy 13.514058 -57.642799)
			(xy 13.602351 -57.614255) (xy 13.693137 -57.595063) (xy 13.785428 -57.585432) (xy 13.831824 -57.584848)
			(xy 13.872926 -57.585323) (xy 13.954781 -57.592908) (xy 14.035586 -57.608013) (xy 14.114652 -57.63051)
			(xy 14.191306 -57.660206) (xy 14.264893 -57.696848) (xy 14.334785 -57.740124) (xy 14.400386 -57.789663)
			(xy 14.461136 -57.845044) (xy 14.516517 -57.905794) (xy 14.566056 -57.971395) (xy 14.609332 -58.041287)
			(xy 14.645974 -58.114874) (xy 14.67567 -58.191528) (xy 14.698167 -58.270594) (xy 14.713272 -58.351399)
			(xy 14.720857 -58.433254) (xy 14.721332 -58.474356) (xy 14.720939 -58.514124) (xy 14.713894 -58.593347)
			(xy 14.699801 -58.671624) (xy 14.678774 -58.748329) (xy 14.650981 -58.822851) (xy 14.63421 -58.858912)
			(xy 14.629682 -58.869586) (xy 14.629806 -58.892745) (xy 14.634464 -58.903362) (xy 14.639471 -58.913776)
			(xy 34.212784 -58.913776) (xy 34.21322 -58.873695) (xy 34.220435 -58.79386) (xy 34.234805 -58.714997)
			(xy 34.256212 -58.637747) (xy 34.269934 -58.600086) (xy 34.27267 -58.591745) (xy 34.272943 -58.574209)
			(xy 34.270442 -58.565796) (xy 34.255367 -58.519464) (xy 34.234216 -58.42435) (xy 34.22359 -58.327495)
			(xy 34.222944 -58.278776) (xy 34.223444 -58.237675) (xy 34.23103 -58.155822) (xy 34.246136 -58.075019)
			(xy 34.268633 -57.995955) (xy 34.298329 -57.919303) (xy 34.33497 -57.845718) (xy 34.378244 -57.775828)
			(xy 34.427782 -57.710228) (xy 34.483162 -57.649479) (xy 34.543909 -57.594098) (xy 34.609508 -57.544558)
			(xy 34.679397 -57.501282) (xy 34.752981 -57.464639) (xy 34.829632 -57.434941) (xy 34.908696 -57.412442)
			(xy 34.989499 -57.397334) (xy 35.071351 -57.389745) (xy 35.112452 -57.389268) (xy 35.152022 -57.38968)
			(xy 35.23085 -57.396689) (xy 35.308744 -57.410674) (xy 35.385087 -57.431524) (xy 35.422332 -57.444894)
			(xy 35.431001 -57.447724) (xy 35.449223 -57.447724) (xy 35.457892 -57.444894) (xy 35.495135 -57.43152)
			(xy 35.57148 -57.410675) (xy 35.649374 -57.396694) (xy 35.728202 -57.389687) (xy 35.767772 -57.389268)
			(xy 35.806698 -57.389687) (xy 35.884255 -57.396463) (xy 35.960922 -57.409992) (xy 36.036113 -57.430171)
			(xy 36.072826 -57.443116) (xy 36.081375 -57.44588) (xy 36.099329 -57.44588) (xy 36.107878 -57.443116)
			(xy 36.144591 -57.430172) (xy 36.219782 -57.40999) (xy 36.296449 -57.396456) (xy 36.374006 -57.389673)
			(xy 36.412932 -57.389268) (xy 36.454034 -57.389736) (xy 36.535888 -57.397324) (xy 36.616693 -57.412431)
			(xy 36.695759 -57.434929) (xy 36.772411 -57.464627) (xy 36.845997 -57.50127) (xy 36.915889 -57.544546)
			(xy 36.981489 -57.594086) (xy 37.042238 -57.649467) (xy 37.097619 -57.710217) (xy 37.147159 -57.775818)
			(xy 37.190434 -57.84571) (xy 37.227077 -57.919296) (xy 37.256773 -57.995949) (xy 37.279271 -58.075015)
			(xy 37.294378 -58.15582) (xy 37.301964 -58.237674) (xy 37.30244 -58.278776) (xy 37.302073 -58.317061)
			(xy 37.295527 -58.39335) (xy 37.28244 -58.468792) (xy 37.262908 -58.542828) (xy 37.25037 -58.579004)
			(xy 37.24773 -58.587444) (xy 37.247722 -58.605112) (xy 37.25037 -58.613548) (xy 37.257228 -58.63336)
			(xy 37.262054 -58.647838) (xy 37.285676 -58.666634) (xy 37.408612 -58.67781) (xy 37.435282 -58.663586)
			(xy 37.442648 -58.650378) (xy 37.463866 -58.612716) (xy 37.51262 -58.541325) (xy 37.568071 -58.475001)
			(xy 37.629694 -58.41437) (xy 37.696909 -58.360002) (xy 37.769081 -58.312412) (xy 37.845529 -58.272047)
			(xy 37.925533 -58.23929) (xy 38.008337 -58.214448) (xy 38.09316 -58.197756) (xy 38.179203 -58.189372)
			(xy 38.222428 -58.18886) (xy 38.26136 -58.189292) (xy 38.338922 -58.196136) (xy 38.41559 -58.209734)
			(xy 38.490775 -58.229982) (xy 38.527482 -58.242962) (xy 38.536031 -58.245726) (xy 38.553985 -58.245726)
			(xy 38.562534 -58.242962) (xy 38.599239 -58.229977) (xy 38.674426 -58.209738) (xy 38.751094 -58.196144)
			(xy 38.828656 -58.189298) (xy 38.867588 -58.18886) (xy 38.90652 -58.189304) (xy 38.984082 -58.196145)
			(xy 39.060749 -58.209739) (xy 39.135935 -58.229984) (xy 39.172642 -58.242962) (xy 39.181191 -58.245726)
			(xy 39.199145 -58.245726) (xy 39.207694 -58.242962) (xy 39.244403 -58.229989) (xy 39.319589 -58.209746)
			(xy 39.396255 -58.196149) (xy 39.473817 -58.189299) (xy 39.512748 -58.18886) (xy 39.553858 -58.189307)
			(xy 39.635728 -58.196898) (xy 39.716548 -58.212013) (xy 39.795628 -58.234521) (xy 39.872294 -58.26423)
			(xy 39.945891 -58.300887) (xy 40.015792 -58.344179) (xy 40.081399 -58.393737) (xy 40.142153 -58.449138)
			(xy 40.197535 -58.509909) (xy 40.243351 -58.5706) (xy 40.517355 -58.5706) (xy 40.521387 -58.485978)
			(xy 40.533443 -58.402122) (xy 40.553416 -58.319791) (xy 40.581124 -58.239732) (xy 40.616317 -58.16267)
			(xy 40.658676 -58.089301) (xy 40.707817 -58.020291) (xy 40.763296 -57.956265) (xy 40.824609 -57.897802)
			(xy 40.891202 -57.845432) (xy 40.962471 -57.79963) (xy 41.037771 -57.760809) (xy 41.116421 -57.729321)
			(xy 41.197707 -57.705452) (xy 41.280894 -57.689418) (xy 41.365229 -57.681364) (xy 41.407588 -57.68086)
			(xy 41.44652 -57.681304) (xy 41.524082 -57.688145) (xy 41.600749 -57.701739) (xy 41.675935 -57.721984)
			(xy 41.712642 -57.734962) (xy 41.721191 -57.737726) (xy 41.739145 -57.737726) (xy 41.747694 -57.734962)
			(xy 41.784403 -57.721989) (xy 41.859589 -57.701746) (xy 41.936255 -57.688149) (xy 42.013817 -57.681299)
			(xy 42.052748 -57.68086) (xy 42.095109 -57.681344) (xy 42.179449 -57.689398) (xy 42.262641 -57.705431)
			(xy 42.343932 -57.7293) (xy 42.422586 -57.760789) (xy 42.497891 -57.799611) (xy 42.569164 -57.845415)
			(xy 42.635761 -57.897788) (xy 42.697078 -57.956253) (xy 42.75256 -58.020282) (xy 42.801704 -58.089296)
			(xy 42.844066 -58.162668) (xy 42.879261 -58.239734) (xy 42.906971 -58.319798) (xy 42.926945 -58.402132)
			(xy 42.939003 -58.485993) (xy 42.939828 -58.503312) (xy 44.667424 -58.503312) (xy 44.668008 -58.456916)
			(xy 44.677653 -58.364628) (xy 44.696848 -58.273844) (xy 44.725386 -58.185551) (xy 44.743624 -58.142886)
			(xy 44.74742 -58.132941) (xy 44.747425 -58.11168) (xy 44.743624 -58.101738) (xy 44.725385 -58.059073)
			(xy 44.696839 -57.970782) (xy 44.677644 -57.879998) (xy 44.66801 -57.787708) (xy 44.667424 -57.741312)
			(xy 44.667864 -57.700208) (xy 44.675448 -57.618351) (xy 44.690553 -57.537543) (xy 44.71305 -57.458473)
			(xy 44.742747 -57.381816) (xy 44.77939 -57.308227) (xy 44.822667 -57.238333) (xy 44.872209 -57.17273)
			(xy 44.927592 -57.111978) (xy 44.988345 -57.056596) (xy 45.053949 -57.007056) (xy 45.123845 -56.96378)
			(xy 45.197435 -56.927138) (xy 45.274092 -56.897443) (xy 45.353162 -56.874948) (xy 45.433971 -56.859845)
			(xy 45.515828 -56.852263) (xy 45.556932 -56.851804) (xy 45.603327 -56.85241) (xy 45.695615 -56.862048)
			(xy 45.786399 -56.881237) (xy 45.874693 -56.909769) (xy 45.917358 -56.928004) (xy 45.9273 -56.93181)
			(xy 45.948564 -56.93181) (xy 45.958506 -56.928004) (xy 46.001164 -56.909749) (xy 46.089458 -56.881208)
			(xy 46.180244 -56.862017) (xy 46.272536 -56.852387) (xy 46.318932 -56.851804) (xy 46.365327 -56.85241)
			(xy 46.457615 -56.862048) (xy 46.548399 -56.881237) (xy 46.636693 -56.909769) (xy 46.679358 -56.928004)
			(xy 46.6893 -56.93181) (xy 46.710564 -56.93181) (xy 46.720506 -56.928004) (xy 46.763164 -56.909749)
			(xy 46.851458 -56.881208) (xy 46.942244 -56.862017) (xy 47.034536 -56.852387) (xy 47.080932 -56.851804)
			(xy 47.122035 -56.852236) (xy 47.203891 -56.859824) (xy 47.284698 -56.874932) (xy 47.363766 -56.897432)
			(xy 47.44042 -56.927131) (xy 47.514008 -56.963775) (xy 47.5839 -57.007054) (xy 47.649501 -57.056596)
			(xy 47.710251 -57.11198) (xy 47.765632 -57.172733) (xy 47.815171 -57.238336) (xy 47.858446 -57.308231)
			(xy 47.895087 -57.38182) (xy 47.924782 -57.458476) (xy 47.947278 -57.537545) (xy 47.962382 -57.618352)
			(xy 47.969966 -57.700209) (xy 47.97044 -57.741312) (xy 47.969867 -57.787708) (xy 47.96022 -57.879997)
			(xy 47.941021 -57.970781) (xy 47.91248 -58.059074) (xy 47.89424 -58.101738) (xy 47.890426 -58.111678)
			(xy 47.890431 -58.132944) (xy 47.89424 -58.142886) (xy 47.912491 -58.185546) (xy 47.941033 -58.273839)
			(xy 47.960224 -58.364625) (xy 47.969856 -58.456916) (xy 47.97044 -58.503312) (xy 47.969945 -58.544414)
			(xy 47.962359 -58.626267) (xy 47.947254 -58.70707) (xy 47.924757 -58.786136) (xy 47.895062 -58.862788)
			(xy 47.858421 -58.936374) (xy 47.815146 -59.006265) (xy 47.765608 -59.071865) (xy 47.710229 -59.132614)
			(xy 47.64948 -59.187995) (xy 47.583881 -59.237535) (xy 47.513991 -59.280811) (xy 47.440406 -59.317454)
			(xy 47.363755 -59.347151) (xy 47.28469 -59.369649) (xy 47.203886 -59.384756) (xy 47.122034 -59.392344)
			(xy 47.080932 -59.39282) (xy 47.034537 -59.392225) (xy 46.942249 -59.382583) (xy 46.851465 -59.363391)
			(xy 46.763171 -59.334856) (xy 46.720506 -59.31662) (xy 46.710564 -59.312814) (xy 46.6893 -59.312814)
			(xy 46.679358 -59.31662) (xy 46.636692 -59.334855) (xy 46.548401 -59.363401) (xy 46.457617 -59.382597)
			(xy 46.365328 -59.392233) (xy 46.318932 -59.39282) (xy 46.272537 -59.392225) (xy 46.180249 -59.382583)
			(xy 46.089465 -59.363391) (xy 46.001171 -59.334856) (xy 45.958506 -59.31662) (xy 45.948564 -59.312814)
			(xy 45.9273 -59.312814) (xy 45.917358 -59.31662) (xy 45.874692 -59.334855) (xy 45.786401 -59.363401)
			(xy 45.695617 -59.382597) (xy 45.603328 -59.392233) (xy 45.556932 -59.39282) (xy 45.51583 -59.392317)
			(xy 45.433976 -59.384735) (xy 45.35317 -59.369633) (xy 45.274103 -59.347139) (xy 45.197449 -59.317446)
			(xy 45.123861 -59.280806) (xy 45.053968 -59.237533) (xy 44.988366 -59.187996) (xy 44.927615 -59.132616)
			(xy 44.872233 -59.071868) (xy 44.822692 -59.006268) (xy 44.779415 -58.936377) (xy 44.742772 -58.862792)
			(xy 44.713075 -58.786139) (xy 44.690577 -58.707073) (xy 44.675471 -58.626268) (xy 44.667885 -58.544414)
			(xy 44.667424 -58.503312) (xy 42.939828 -58.503312) (xy 42.943034 -58.57062) (xy 42.939003 -58.655247)
			(xy 42.926945 -58.739108) (xy 42.906971 -58.821442) (xy 42.879261 -58.901506) (xy 42.844066 -58.978572)
			(xy 42.801704 -59.051944) (xy 42.75256 -59.120958) (xy 42.697078 -59.184987) (xy 42.635761 -59.243452)
			(xy 42.569164 -59.295825) (xy 42.497891 -59.341629) (xy 42.422586 -59.380451) (xy 42.343932 -59.41194)
			(xy 42.262641 -59.435809) (xy 42.179449 -59.451842) (xy 42.095109 -59.459896) (xy 42.052748 -59.460384)
			(xy 42.013816 -59.459962) (xy 41.936253 -59.453116) (xy 41.859585 -59.439515) (xy 41.7844 -59.419264)
			(xy 41.747694 -59.406282) (xy 41.739145 -59.403518) (xy 41.721191 -59.403518) (xy 41.712642 -59.406282)
			(xy 41.67593 -59.419247) (xy 41.600745 -59.439491) (xy 41.52408 -59.453091) (xy 41.446519 -59.459943)
			(xy 41.407588 -59.460384) (xy 41.365229 -59.459836) (xy 41.280894 -59.451782) (xy 41.197707 -59.435748)
			(xy 41.116421 -59.411879) (xy 41.037771 -59.380391) (xy 40.962471 -59.34157) (xy 40.891202 -59.295768)
			(xy 40.824609 -59.243398) (xy 40.763296 -59.184935) (xy 40.707817 -59.120909) (xy 40.658676 -59.051899)
			(xy 40.616317 -58.97853) (xy 40.581124 -58.901468) (xy 40.553416 -58.821409) (xy 40.533443 -58.739078)
			(xy 40.521387 -58.655222) (xy 40.517355 -58.5706) (xy 40.243351 -58.5706) (xy 40.247073 -58.575531)
			(xy 40.290344 -58.645445) (xy 40.326979 -58.719053) (xy 40.356665 -58.795728) (xy 40.379149 -58.874815)
			(xy 40.394239 -58.955639) (xy 40.401806 -59.037511) (xy 40.402256 -59.078622) (xy 40.401872 -59.116906)
			(xy 40.395331 -59.193195) (xy 40.382249 -59.268637) (xy 40.362721 -59.342674) (xy 40.350186 -59.37885)
			(xy 40.347523 -59.387284) (xy 40.34753 -59.404957) (xy 40.350186 -59.413394) (xy 40.362687 -59.44958)
			(xy 40.382202 -59.523617) (xy 40.395289 -59.599056) (xy 40.401851 -59.675339) (xy 40.402256 -59.713622)
			(xy 40.401808 -59.754729) (xy 40.394222 -59.836593) (xy 40.379116 -59.917408) (xy 40.356619 -59.996485)
			(xy 40.326923 -60.073149) (xy 40.290282 -60.146747) (xy 40.247007 -60.216651) (xy 40.197469 -60.282264)
			(xy 40.142088 -60.343028) (xy 40.081338 -60.398424) (xy 40.015737 -60.44798) (xy 39.945844 -60.491272)
			(xy 39.872256 -60.527932) (xy 39.795599 -60.557647) (xy 39.716528 -60.580164) (xy 39.635717 -60.595291)
			(xy 39.553855 -60.602898) (xy 39.512748 -60.603384) (xy 39.473173 -60.602949) (xy 39.394338 -60.595875)
			(xy 39.316444 -60.581824) (xy 39.240107 -60.560907) (xy 39.202868 -60.547504) (xy 39.194199 -60.544674)
			(xy 39.175977 -60.544674) (xy 39.167308 -60.547504) (xy 39.130069 -60.560906) (xy 39.05373 -60.581811)
			(xy 38.975836 -60.595856) (xy 38.897003 -60.602929) (xy 38.857428 -60.603384) (xy 38.819138 -60.602969)
			(xy 38.742844 -60.596364) (xy 38.667402 -60.583217) (xy 38.593371 -60.563627) (xy 38.5572 -60.55106)
			(xy 38.548763 -60.548409) (xy 38.531093 -60.548409) (xy 38.522656 -60.55106) (xy 38.486477 -60.563601)
			(xy 38.412445 -60.583174) (xy 38.337005 -60.596322) (xy 38.260716 -60.602947) (xy 38.222428 -60.603384)
			(xy 38.181317 -60.602921) (xy 38.099446 -60.595335) (xy 38.018624 -60.580226) (xy 37.939542 -60.557723)
			(xy 37.862874 -60.528017) (xy 37.789275 -60.491363) (xy 37.719372 -60.448072) (xy 37.653763 -60.398515)
			(xy 37.593008 -60.343115) (xy 37.537625 -60.282344) (xy 37.488086 -60.216721) (xy 37.444816 -60.146807)
			(xy 37.408182 -60.073197) (xy 37.378498 -59.996521) (xy 37.356016 -59.917432) (xy 37.34093 -59.836606)
			(xy 37.333368 -59.754733) (xy 37.33292 -59.713622) (xy 37.333289 -59.675337) (xy 37.339834 -59.599048)
			(xy 37.352921 -59.523606) (xy 37.372453 -59.44957) (xy 37.38499 -59.413394) (xy 37.387629 -59.404954)
			(xy 37.387636 -59.387287) (xy 37.38499 -59.37885) (xy 37.378132 -59.359038) (xy 37.373306 -59.34456)
			(xy 37.349684 -59.325764) (xy 37.226748 -59.314588) (xy 37.200078 -59.328812) (xy 37.192712 -59.34202)
			(xy 37.17144 -59.379641) (xy 37.122666 -59.450996) (xy 37.067204 -59.517286) (xy 37.005575 -59.577885)
			(xy 36.93836 -59.632223) (xy 36.866194 -59.679787) (xy 36.789755 -59.720129) (xy 36.709765 -59.75287)
			(xy 36.626977 -59.7777) (xy 36.542171 -59.794386) (xy 36.456148 -59.802769) (xy 36.412932 -59.803284)
			(xy 36.373362 -59.802873) (xy 36.294534 -59.795863) (xy 36.21664 -59.781878) (xy 36.140297 -59.761028)
			(xy 36.103052 -59.747658) (xy 36.094383 -59.744828) (xy 36.076161 -59.744828) (xy 36.067492 -59.747658)
			(xy 36.030251 -59.761039) (xy 35.953906 -59.781882) (xy 35.876011 -59.795861) (xy 35.797182 -59.802865)
			(xy 35.757612 -59.803284) (xy 35.718043 -59.802849) (xy 35.639215 -59.795846) (xy 35.561321 -59.781868)
			(xy 35.484977 -59.761025) (xy 35.447732 -59.747658) (xy 35.439063 -59.744828) (xy 35.420841 -59.744828)
			(xy 35.412172 -59.747658) (xy 35.374923 -59.761016) (xy 35.298581 -59.781865) (xy 35.220688 -59.79585)
			(xy 35.141861 -59.802862) (xy 35.102292 -59.803284) (xy 35.061188 -59.802855) (xy 34.979331 -59.795269)
			(xy 34.898523 -59.780163) (xy 34.819453 -59.757665) (xy 34.742797 -59.727967) (xy 34.669208 -59.691322)
			(xy 34.599314 -59.648044) (xy 34.533711 -59.598502) (xy 34.47296 -59.543118) (xy 34.417578 -59.482364)
			(xy 34.368038 -59.41676) (xy 34.324762 -59.346864) (xy 34.28812 -59.273274) (xy 34.258425 -59.196616)
			(xy 34.23593 -59.117546) (xy 34.220826 -59.036738) (xy 34.213243 -58.95488) (xy 34.212784 -58.913776)
			(xy 14.639471 -58.913776) (xy 14.65219 -58.940231) (xy 14.68162 -59.016566) (xy 14.703921 -59.09528)
			(xy 14.718903 -59.175708) (xy 14.726441 -59.257172) (xy 14.72692 -59.298078) (xy 14.726481 -59.339194)
			(xy 14.718895 -59.421075) (xy 14.703786 -59.501906) (xy 14.681283 -59.580999) (xy 14.651579 -59.657678)
			(xy 14.614925 -59.731289) (xy 14.571636 -59.801203) (xy 14.52208 -59.866825) (xy 14.46668 -59.927594)
			(xy 14.40591 -59.982993) (xy 14.340287 -60.032547) (xy 14.270371 -60.075835) (xy 14.196759 -60.112487)
			(xy 14.12008 -60.14219) (xy 14.040987 -60.164691) (xy 13.960155 -60.179798) (xy 13.878274 -60.187381)
			(xy 13.837158 -60.18784) (xy 13.790755 -60.187227) (xy 13.698458 -60.177532) (xy 13.607673 -60.158275)
			(xy 13.519388 -60.129663) (xy 13.476732 -60.111386) (xy 13.46679 -60.10758) (xy 13.445526 -60.10758)
			(xy 13.435584 -60.111386) (xy 13.392929 -60.129663) (xy 13.304639 -60.158252) (xy 13.213854 -60.177505)
			(xy 13.12156 -60.187213) (xy 13.075158 -60.18784) (xy 13.028755 -60.187227) (xy 12.936458 -60.177532)
			(xy 12.845673 -60.158275) (xy 12.757388 -60.129663) (xy 12.714732 -60.111386) (xy 12.70479 -60.10758)
			(xy 12.683526 -60.10758) (xy 12.673584 -60.111386) (xy 12.630929 -60.129663) (xy 12.542639 -60.158252)
			(xy 12.451854 -60.177505) (xy 12.35956 -60.187213) (xy 12.313158 -60.18784) (xy 12.272044 -60.187369)
			(xy 12.190166 -60.179782) (xy 12.109337 -60.164672) (xy 12.030248 -60.142169) (xy 11.953572 -60.112464)
			(xy 11.879964 -60.075812) (xy 11.810052 -60.032524) (xy 11.744432 -59.98297) (xy 11.683665 -59.927573)
			(xy 11.628268 -59.866805) (xy 11.578714 -59.801185) (xy 11.535426 -59.731273) (xy 11.498774 -59.657664)
			(xy 11.46907 -59.580988) (xy 11.446567 -59.501899) (xy 11.431458 -59.42107) (xy 11.423871 -59.339192)
			(xy 11.423396 -59.298078) (xy 11.424158 -59.261502) (xy 11.42492 -59.246516) (xy 11.409934 -59.221116)
			(xy 11.301222 -59.16549) (xy 11.271758 -59.168284) (xy 11.260074 -59.177428) (xy 11.226474 -59.203173)
			(xy 11.155239 -59.24891) (xy 11.079981 -59.287669) (xy 11.001379 -59.319101) (xy 10.920146 -59.34292)
			(xy 10.837017 -59.358912) (xy 10.752745 -59.36693) (xy 10.710418 -59.36742) (xy 10.664023 -59.36683)
			(xy 10.571734 -59.357187) (xy 10.480951 -59.337993) (xy 10.392657 -59.309457) (xy 10.349992 -59.29122)
			(xy 10.34005 -59.287414) (xy 10.318786 -59.287414) (xy 10.308844 -59.29122) (xy 10.26618 -59.30946)
			(xy 10.177888 -59.338005) (xy 10.087104 -59.357199) (xy 9.994814 -59.366834) (xy 9.948418 -59.36742)
			(xy 9.90607 -59.366912) (xy 9.821756 -59.358861) (xy 9.73859 -59.342832) (xy 9.657325 -59.31897)
			(xy 9.578695 -59.287491) (xy 9.503414 -59.248681) (xy 9.432162 -59.20289) (xy 9.365586 -59.150534)
			(xy 9.304288 -59.092087) (xy 9.248824 -59.028077) (xy 9.199695 -58.959085) (xy 9.157347 -58.885736)
			(xy 9.122163 -58.808693) (xy 9.094461 -58.728655) (xy 9.074493 -58.646345) (xy 9.06244 -58.562511)
			(xy 9.058409 -58.47791) (xy 8.750967 -58.47791) (xy 8.780124 -58.509895) (xy 8.829678 -58.575515)
			(xy 8.872966 -58.645427) (xy 8.909618 -58.719035) (xy 8.939322 -58.795711) (xy 8.961825 -58.874801)
			(xy 8.976934 -58.95563) (xy 8.984521 -59.037508) (xy 8.984996 -59.078622) (xy 8.9846 -59.116912)
			(xy 8.97799 -59.193207) (xy 8.964838 -59.268649) (xy 8.945241 -59.342679) (xy 8.932672 -59.37885)
			(xy 8.930009 -59.387284) (xy 8.930017 -59.404957) (xy 8.932672 -59.413394) (xy 8.945223 -59.449569)
			(xy 8.964795 -59.523603) (xy 8.97794 -59.599043) (xy 8.984561 -59.675334) (xy 8.984996 -59.713622)
			(xy 8.984519 -59.754736) (xy 8.976932 -59.836614) (xy 8.961822 -59.917442) (xy 8.939319 -59.996531)
			(xy 8.909615 -60.073207) (xy 8.872963 -60.146814) (xy 8.829675 -60.216726) (xy 8.780122 -60.282346)
			(xy 8.724725 -60.343113) (xy 8.663957 -60.39851) (xy 8.598338 -60.448064) (xy 8.528426 -60.491352)
			(xy 8.454818 -60.528004) (xy 8.378143 -60.557709) (xy 8.299054 -60.580212) (xy 8.218226 -60.595322)
			(xy 8.136348 -60.602909) (xy 8.095234 -60.603384) (xy 8.055659 -60.602923) (xy 7.976826 -60.595857)
			(xy 7.898932 -60.581813) (xy 7.822594 -60.560904) (xy 7.785354 -60.547504) (xy 7.776685 -60.544674)
			(xy 7.758463 -60.544674) (xy 7.749794 -60.547504) (xy 7.712556 -60.56091) (xy 7.636217 -60.581814)
			(xy 7.558322 -60.595857) (xy 7.479489 -60.60293) (xy 7.439914 -60.603384) (xy 7.401624 -60.602973)
			(xy 7.32533 -60.596367) (xy 7.249888 -60.583219) (xy 7.175857 -60.563627) (xy 7.139686 -60.55106)
			(xy 7.131249 -60.548409) (xy 7.113579 -60.548409) (xy 7.105142 -60.55106) (xy 7.068965 -60.563605)
			(xy 6.994932 -60.583177) (xy 6.919492 -60.596324) (xy 6.843202 -60.602948) (xy 6.804914 -60.603384)
			(xy 6.763799 -60.602918) (xy 6.68192 -60.595331) (xy 6.601091 -60.580222) (xy 6.522 -60.557719) (xy 6.445324 -60.528014)
			(xy 6.371715 -60.491362) (xy 6.301801 -60.448074) (xy 6.236181 -60.39852) (xy 6.175412 -60.343122)
			(xy 6.120014 -60.282354) (xy 6.07046 -60.216734) (xy 6.027171 -60.146821) (xy 5.990518 -60.073212)
			(xy 5.960813 -59.996535) (xy 5.93831 -59.917445) (xy 5.9232 -59.836616) (xy 5.915613 -59.754737)
			(xy 5.915152 -59.713622) (xy 5.915563 -59.675332) (xy 5.922169 -59.599038) (xy 5.935317 -59.523596)
			(xy 5.954909 -59.449565) (xy 5.967476 -59.413394) (xy 5.970115 -59.404954) (xy 5.970122 -59.387287)
			(xy 5.967476 -59.37885) (xy 5.960618 -59.359038) (xy 5.955792 -59.34456) (xy 5.93217 -59.325764)
			(xy 5.809234 -59.314588) (xy 5.782564 -59.328812) (xy 5.775198 -59.34202) (xy 5.753936 -59.379647)
			(xy 5.705162 -59.451002) (xy 5.649698 -59.517292) (xy 5.588068 -59.577891) (xy 5.520852 -59.632228)
			(xy 5.448685 -59.679792) (xy 5.372245 -59.720134) (xy 5.292254 -59.752874) (xy 5.209465 -59.777703)
			(xy 5.124659 -59.794388) (xy 5.038634 -59.80277) (xy 4.995418 -59.803284) (xy 4.955849 -59.802847)
			(xy 4.877021 -59.795845) (xy 4.799127 -59.781867) (xy 4.722783 -59.761025) (xy 4.685538 -59.747658)
			(xy 4.676869 -59.744828) (xy 4.658647 -59.744828) (xy 4.649978 -59.747658) (xy 4.612728 -59.761014)
			(xy 4.536386 -59.781864) (xy 4.458494 -59.79585) (xy 4.379667 -59.802861) (xy 4.340098 -59.803284)
			(xy 4.301814 -59.802893) (xy 4.225525 -59.796354) (xy 4.150083 -59.783273) (xy 4.076046 -59.763748)
			(xy 4.03987 -59.751214) (xy 4.031433 -59.748563) (xy 4.013763 -59.748563) (xy 4.005326 -59.751214)
			(xy 3.969138 -59.763711) (xy 3.895102 -59.783226) (xy 3.819664 -59.796314) (xy 3.743381 -59.802878)
			(xy 3.705098 -59.803284) (xy 3.663991 -59.802809) (xy 3.582128 -59.795225) (xy 3.501314 -59.780121)
			(xy 3.422238 -59.757626) (xy 3.345574 -59.727932) (xy 3.271977 -59.691292) (xy 3.202073 -59.64802)
			(xy 3.13646 -59.598483) (xy 3.075696 -59.543104) (xy 3.0203 -59.482356) (xy 2.970744 -59.416756)
			(xy 2.927451 -59.346865) (xy 2.890791 -59.273278) (xy 2.861075 -59.196623) (xy 2.838557 -59.117553)
			(xy 2.82343 -59.036743) (xy 2.815822 -58.954883) (xy 2.815336 -58.913776) (xy 0.509016 -58.913776)
			(xy 0.509016 -62.54191) (xy 12.055609 -62.54191) (xy 12.05964 -62.457309) (xy 12.071693 -62.373475)
			(xy 12.091661 -62.291165) (xy 12.119363 -62.211127) (xy 12.154547 -62.134084) (xy 12.196895 -62.060735)
			(xy 12.246024 -61.991743) (xy 12.301488 -61.927733) (xy 12.362786 -61.869286) (xy 12.429362 -61.81693)
			(xy 12.500614 -61.771139) (xy 12.575895 -61.732329) (xy 12.654525 -61.70085) (xy 12.73579 -61.676988)
			(xy 12.818956 -61.660959) (xy 12.90327 -61.652908) (xy 12.945618 -61.652404) (xy 12.992014 -61.652979)
			(xy 13.084302 -61.662627) (xy 13.175086 -61.681825) (xy 13.263379 -61.710365) (xy 13.306044 -61.728604)
			(xy 13.315986 -61.73241) (xy 13.33725 -61.73241) (xy 13.347192 -61.728604) (xy 13.389852 -61.710354)
			(xy 13.478145 -61.681811) (xy 13.568931 -61.66262) (xy 13.661222 -61.652988) (xy 13.707618 -61.652404)
			(xy 13.754014 -61.652979) (xy 13.846302 -61.662627) (xy 13.937086 -61.681825) (xy 14.025379 -61.710365)
			(xy 14.068044 -61.728604) (xy 14.077986 -61.73241) (xy 14.09925 -61.73241) (xy 14.109192 -61.728604)
			(xy 14.151852 -61.710354) (xy 14.240145 -61.681811) (xy 14.330931 -61.66262) (xy 14.423222 -61.652988)
			(xy 14.469618 -61.652404) (xy 14.511967 -61.652888) (xy 14.596283 -61.660939) (xy 14.679451 -61.676968)
			(xy 14.760719 -61.70083) (xy 14.839351 -61.73231) (xy 14.914634 -61.771121) (xy 14.985887 -61.816912)
			(xy 15.035719 -61.8561) (xy 44.743084 -61.8561) (xy 44.747114 -61.771497) (xy 44.759168 -61.68766)
			(xy 44.779138 -61.605348) (xy 44.806841 -61.525307) (xy 44.842027 -61.448262) (xy 44.884377 -61.374911)
			(xy 44.933509 -61.305918) (xy 44.988976 -61.241907) (xy 45.050277 -61.183459) (xy 45.116856 -61.131103)
			(xy 45.18811 -61.085313) (xy 45.263395 -61.046503) (xy 45.342028 -61.015026) (xy 45.423297 -60.991166)
			(xy 45.506466 -60.975139) (xy 45.590782 -60.967091) (xy 45.633132 -60.966604) (xy 45.679527 -60.96721)
			(xy 45.771815 -60.976848) (xy 45.862599 -60.996037) (xy 45.950893 -61.024569) (xy 45.993558 -61.042804)
			(xy 46.0035 -61.04661) (xy 46.024764 -61.04661) (xy 46.034706 -61.042804) (xy 46.077364 -61.024549)
			(xy 46.165658 -60.996008) (xy 46.256444 -60.976817) (xy 46.348736 -60.967187) (xy 46.395132 -60.966604)
			(xy 46.441527 -60.96721) (xy 46.533815 -60.976848) (xy 46.624599 -60.996037) (xy 46.712893 -61.024569)
			(xy 46.755558 -61.042804) (xy 46.7655 -61.04661) (xy 46.786764 -61.04661) (xy 46.796706 -61.042804)
			(xy 46.839364 -61.024549) (xy 46.927658 -60.996008) (xy 47.018444 -60.976817) (xy 47.110736 -60.967187)
			(xy 47.157132 -60.966604) (xy 47.19948 -60.967085) (xy 47.283793 -60.975139) (xy 47.366958 -60.99117)
			(xy 47.448222 -61.015034) (xy 47.526851 -61.046515) (xy 47.602131 -61.085327) (xy 47.673381 -61.131119)
			(xy 47.739955 -61.183476) (xy 47.801252 -61.241924) (xy 47.856715 -61.305934) (xy 47.905843 -61.374926)
			(xy 47.94819 -61.448276) (xy 47.983373 -61.525319) (xy 48.011074 -61.605357) (xy 48.031041 -61.687666)
			(xy 48.043095 -61.7715) (xy 48.047125 -61.8561) (xy 48.043095 -61.9407) (xy 48.031041 -62.024534)
			(xy 48.011074 -62.106843) (xy 47.983373 -62.186881) (xy 47.94819 -62.263924) (xy 47.905843 -62.337274)
			(xy 47.856715 -62.406266) (xy 47.801252 -62.470276) (xy 47.739955 -62.528724) (xy 47.673381 -62.581081)
			(xy 47.602131 -62.626873) (xy 47.526851 -62.665685) (xy 47.448222 -62.697166) (xy 47.366958 -62.72103)
			(xy 47.283793 -62.737061) (xy 47.19948 -62.745115) (xy 47.157132 -62.74562) (xy 47.110737 -62.745025)
			(xy 47.018449 -62.735383) (xy 46.927665 -62.716191) (xy 46.839371 -62.687656) (xy 46.796706 -62.66942)
			(xy 46.786764 -62.665614) (xy 46.7655 -62.665614) (xy 46.755558 -62.66942) (xy 46.712892 -62.687655)
			(xy 46.624601 -62.716201) (xy 46.533817 -62.735397) (xy 46.441528 -62.745033) (xy 46.395132 -62.74562)
			(xy 46.348737 -62.745025) (xy 46.256449 -62.735383) (xy 46.165665 -62.716191) (xy 46.077371 -62.687656)
			(xy 46.034706 -62.66942) (xy 46.024764 -62.665614) (xy 46.0035 -62.665614) (xy 45.993558 -62.66942)
			(xy 45.950892 -62.687655) (xy 45.862601 -62.716201) (xy 45.771817 -62.735397) (xy 45.679528 -62.745033)
			(xy 45.633132 -62.74562) (xy 45.590782 -62.745109) (xy 45.506466 -62.737061) (xy 45.423297 -62.721034)
			(xy 45.342028 -62.697174) (xy 45.263395 -62.665697) (xy 45.18811 -62.626887) (xy 45.116856 -62.581097)
			(xy 45.050277 -62.528741) (xy 44.988976 -62.470293) (xy 44.933509 -62.406282) (xy 44.884377 -62.337289)
			(xy 44.842027 -62.263938) (xy 44.806841 -62.186893) (xy 44.779138 -62.106852) (xy 44.759168 -62.02454)
			(xy 44.747114 -61.940703) (xy 44.743084 -61.8561) (xy 15.035719 -61.8561) (xy 15.052465 -61.869269)
			(xy 15.113764 -61.927718) (xy 15.16923 -61.991729) (xy 15.21836 -62.060723) (xy 15.26071 -62.134074)
			(xy 15.295895 -62.211119) (xy 15.323597 -62.291159) (xy 15.343566 -62.37347) (xy 15.35562 -62.457307)
			(xy 15.35965 -62.54191) (xy 15.35562 -62.626513) (xy 15.343566 -62.71035) (xy 15.323597 -62.792661)
			(xy 15.295895 -62.872701) (xy 15.26071 -62.949746) (xy 15.21836 -63.023097) (xy 15.16923 -63.092091)
			(xy 15.113764 -63.156102) (xy 15.052465 -63.214551) (xy 14.985887 -63.266908) (xy 14.914634 -63.312699)
			(xy 14.839351 -63.35151) (xy 14.760719 -63.38299) (xy 14.679451 -63.406852) (xy 14.596283 -63.422881)
			(xy 14.511967 -63.430932) (xy 14.469618 -63.43142) (xy 14.423223 -63.43083) (xy 14.330934 -63.421187)
			(xy 14.240151 -63.401993) (xy 14.151857 -63.373457) (xy 14.109192 -63.35522) (xy 14.09925 -63.351414)
			(xy 14.077986 -63.351414) (xy 14.068044 -63.35522) (xy 14.02538 -63.37346) (xy 13.937088 -63.402005)
			(xy 13.846304 -63.421199) (xy 13.754014 -63.430834) (xy 13.707618 -63.43142) (xy 13.661223 -63.43083)
			(xy 13.568934 -63.421187) (xy 13.478151 -63.401993) (xy 13.389857 -63.373457) (xy 13.347192 -63.35522)
			(xy 13.33725 -63.351414) (xy 13.315986 -63.351414) (xy 13.306044 -63.35522) (xy 13.26338 -63.37346)
			(xy 13.175088 -63.402005) (xy 13.084304 -63.421199) (xy 12.992014 -63.430834) (xy 12.945618 -63.43142)
			(xy 12.90327 -63.430912) (xy 12.818956 -63.422861) (xy 12.73579 -63.406832) (xy 12.654525 -63.38297)
			(xy 12.575895 -63.351491) (xy 12.500614 -63.312681) (xy 12.429362 -63.26689) (xy 12.362786 -63.214534)
			(xy 12.301488 -63.156087) (xy 12.246024 -63.092077) (xy 12.196895 -63.023085) (xy 12.154547 -62.949736)
			(xy 12.119363 -62.872693) (xy 12.091661 -62.792655) (xy 12.071693 -62.710345) (xy 12.05964 -62.626511)
			(xy 12.055609 -62.54191) (xy 0.509016 -62.54191) (xy 0.509016 -80.067912) (xy 3.729228 -80.067912)
			(xy 3.729828 -80.021509) (xy 3.739526 -79.929211) (xy 3.758788 -79.838426) (xy 3.787403 -79.750141)
			(xy 3.805682 -79.707486) (xy 3.809481 -79.697542) (xy 3.809485 -79.67628) (xy 3.805682 -79.666338)
			(xy 3.787421 -79.623677) (xy 3.758828 -79.535389) (xy 3.739571 -79.444606) (xy 3.729858 -79.352313)
			(xy 3.729228 -79.305912) (xy 3.729694 -79.264802) (xy 3.737282 -79.182931) (xy 3.752393 -79.102111)
			(xy 3.774897 -79.02303) (xy 3.804604 -78.946363) (xy 3.841259 -78.872765) (xy 3.884549 -78.802863)
			(xy 3.934106 -78.737255) (xy 3.989506 -78.6765) (xy 4.050276 -78.621117) (xy 4.115898 -78.571579)
			(xy 4.185811 -78.528308) (xy 4.25942 -78.491673) (xy 4.336095 -78.461988) (xy 4.415182 -78.439506)
			(xy 4.496007 -78.424418) (xy 4.577879 -78.416853) (xy 4.61899 -78.416404) (xy 4.665386 -78.416989)
			(xy 4.757674 -78.426634) (xy 4.848458 -78.445829) (xy 4.936751 -78.474366) (xy 4.979416 -78.492604)
			(xy 4.989358 -78.49641) (xy 5.010622 -78.49641) (xy 5.020564 -78.492604) (xy 5.063228 -78.474363)
			(xy 5.15152 -78.445818) (xy 5.242304 -78.426624) (xy 5.334594 -78.416989) (xy 5.38099 -78.416404)
			(xy 5.427386 -78.416989) (xy 5.519674 -78.426634) (xy 5.610458 -78.445829) (xy 5.698751 -78.474366)
			(xy 5.741416 -78.492604) (xy 5.751358 -78.49641) (xy 5.772622 -78.49641) (xy 5.782564 -78.492604)
			(xy 5.825228 -78.474363) (xy 5.91352 -78.445818) (xy 6.004304 -78.426624) (xy 6.096594 -78.416989)
			(xy 6.14299 -78.416404) (xy 6.189386 -78.416989) (xy 6.281674 -78.426634) (xy 6.372458 -78.445829)
			(xy 6.460751 -78.474366) (xy 6.503416 -78.492604) (xy 6.513358 -78.49641) (xy 6.534622 -78.49641)
			(xy 6.544564 -78.492604) (xy 6.587228 -78.474363) (xy 6.67552 -78.445818) (xy 6.766304 -78.426624)
			(xy 6.858594 -78.416989) (xy 6.90499 -78.416404) (xy 6.946097 -78.416883) (xy 7.027959 -78.424467)
			(xy 7.108773 -78.439571) (xy 7.187849 -78.462065) (xy 7.264513 -78.491759) (xy 7.33811 -78.528398)
			(xy 7.408014 -78.571671) (xy 7.473627 -78.621208) (xy 7.534391 -78.676586) (xy 7.589787 -78.737334)
			(xy 7.639343 -78.802933) (xy 7.682636 -78.872824) (xy 7.719297 -78.946411) (xy 7.749013 -79.023066)
			(xy 7.77153 -79.102135) (xy 7.786658 -79.182945) (xy 7.794266 -79.264805) (xy 7.794752 -79.305912)
			(xy 7.794127 -79.352314) (xy 7.784436 -79.444611) (xy 7.765182 -79.535397) (xy 7.736574 -79.623682)
			(xy 7.718298 -79.666338) (xy 7.714486 -79.676278) (xy 7.714491 -79.697544) (xy 7.718298 -79.707486)
			(xy 7.736566 -79.750144) (xy 7.765157 -79.838434) (xy 7.784413 -79.929217) (xy 7.794124 -80.021511)
			(xy 7.794752 -80.067912) (xy 7.794289 -80.109023) (xy 7.786702 -80.190893) (xy 7.771591 -80.271713)
			(xy 7.757306 -80.32191) (xy 8.55498 -80.32191) (xy 8.55901 -80.237309) (xy 8.571063 -80.153474) (xy 8.591031 -80.071165)
			(xy 8.618733 -79.991127) (xy 8.653917 -79.914084) (xy 8.696266 -79.840734) (xy 8.745394 -79.771742)
			(xy 8.800859 -79.707732) (xy 8.862157 -79.649285) (xy 8.928733 -79.596929) (xy 8.999985 -79.551138)
			(xy 9.075266 -79.512328) (xy 9.153896 -79.480849) (xy 9.235162 -79.456988) (xy 9.318328 -79.440959)
			(xy 9.402642 -79.432908) (xy 9.44499 -79.432404) (xy 9.491386 -79.432989) (xy 9.583674 -79.442634)
			(xy 9.674458 -79.461829) (xy 9.762751 -79.490366) (xy 9.805416 -79.508604) (xy 9.815358 -79.51241)
			(xy 9.836622 -79.51241) (xy 9.846564 -79.508604) (xy 9.889228 -79.490363) (xy 9.97752 -79.461818)
			(xy 10.068304 -79.442624) (xy 10.160594 -79.432989) (xy 10.20699 -79.432404) (xy 10.249339 -79.432904)
			(xy 10.333652 -79.440955) (xy 10.416819 -79.456984) (xy 10.498085 -79.480846) (xy 10.576715 -79.512324)
			(xy 10.651997 -79.551135) (xy 10.723249 -79.596926) (xy 10.789826 -79.649282) (xy 10.851124 -79.70773)
			(xy 10.862798 -79.721202) (xy 11.170412 -79.721202) (xy 11.170819 -79.682912) (xy 11.177427 -79.606618)
			(xy 11.190576 -79.531176) (xy 11.210168 -79.457145) (xy 11.222736 -79.420974) (xy 11.225386 -79.412537)
			(xy 11.225387 -79.394867) (xy 11.222736 -79.38643) (xy 11.210188 -79.350254) (xy 11.190616 -79.27622)
			(xy 11.177471 -79.20078) (xy 11.170847 -79.12449) (xy 11.170412 -79.086202) (xy 11.170915 -79.045089)
			(xy 11.178501 -78.963212) (xy 11.19361 -78.882386) (xy 11.216112 -78.803298) (xy 11.245815 -78.726623)
			(xy 11.282466 -78.653016) (xy 11.325752 -78.583105) (xy 11.375304 -78.517486) (xy 11.430699 -78.456719)
			(xy 11.491464 -78.401322) (xy 11.557082 -78.351768) (xy 11.626992 -78.30848) (xy 11.700597 -78.271826)
			(xy 11.777271 -78.242121) (xy 11.856358 -78.219617) (xy 11.937185 -78.204505) (xy 12.019061 -78.196916)
			(xy 12.060174 -78.19644) (xy 12.099749 -78.196898) (xy 12.178583 -78.203964) (xy 12.256477 -78.218009)
			(xy 12.332814 -78.238919) (xy 12.370054 -78.25232) (xy 12.378723 -78.25515) (xy 12.396945 -78.25515)
			(xy 12.405614 -78.25232) (xy 12.442851 -78.238913) (xy 12.519191 -78.218009) (xy 12.597086 -78.203966)
			(xy 12.675919 -78.196894) (xy 12.715494 -78.19644) (xy 12.753784 -78.196847) (xy 12.830078 -78.203454)
			(xy 12.90552 -78.216603) (xy 12.979551 -78.236196) (xy 13.015722 -78.248764) (xy 13.024159 -78.251415)
			(xy 13.041829 -78.251415) (xy 13.050266 -78.248764) (xy 13.086443 -78.236218) (xy 13.160476 -78.216646)
			(xy 13.235916 -78.203499) (xy 13.312206 -78.196876) (xy 13.350494 -78.19644) (xy 13.391609 -78.196904)
			(xy 13.473488 -78.204491) (xy 13.554317 -78.2196) (xy 13.633408 -78.242103) (xy 13.710085 -78.271807)
			(xy 13.783694 -78.30846) (xy 13.853608 -78.351748) (xy 13.919229 -78.401302) (xy 13.979997 -78.4567)
			(xy 14.035395 -78.517468) (xy 14.08495 -78.583089) (xy 14.128238 -78.653002) (xy 14.164891 -78.726611)
			(xy 14.194596 -78.803288) (xy 14.217099 -78.882379) (xy 14.232209 -78.963208) (xy 14.239796 -79.045087)
			(xy 14.240256 -79.086202) (xy 14.239852 -79.124492) (xy 14.233244 -79.200786) (xy 14.220094 -79.276228)
			(xy 14.2005 -79.350259) (xy 14.187932 -79.38643) (xy 14.185281 -79.394866) (xy 14.185281 -79.412537)
			(xy 14.187932 -79.420974) (xy 14.19479 -79.440786) (xy 14.199616 -79.455264) (xy 14.223238 -79.47406)
			(xy 14.346174 -79.485236) (xy 14.372844 -79.471012) (xy 14.38021 -79.457804) (xy 14.401476 -79.420179)
			(xy 14.450249 -79.348823) (xy 14.505712 -79.282533) (xy 14.567341 -79.221933) (xy 14.634556 -79.167595)
			(xy 14.706723 -79.120031) (xy 14.783163 -79.079689) (xy 14.863154 -79.046949) (xy 14.945943 -79.02212)
			(xy 15.030749 -79.005436) (xy 15.116774 -78.997053) (xy 15.15999 -78.99654) (xy 15.199559 -78.996973)
			(xy 15.278387 -79.003976) (xy 15.356281 -79.017955) (xy 15.432625 -79.038799) (xy 15.46987 -79.052166)
			(xy 15.478539 -79.054996) (xy 15.496761 -79.054996) (xy 15.50543 -79.052166) (xy 15.542679 -79.038809)
			(xy 15.619021 -79.017959) (xy 15.696914 -79.003973) (xy 15.775741 -78.996962) (xy 15.81531 -78.99654)
			(xy 15.853594 -78.996928) (xy 15.929883 -79.003467) (xy 16.005325 -79.016549) (xy 16.079362 -79.036075)
			(xy 16.115538 -79.04861) (xy 16.123975 -79.051261) (xy 16.141645 -79.051261) (xy 16.150082 -79.04861)
			(xy 16.18627 -79.036112) (xy 16.260306 -79.016597) (xy 16.335744 -79.003509) (xy 16.412027 -78.996946)
			(xy 16.45031 -78.99654) (xy 16.491417 -78.997003) (xy 16.57328 -79.004588) (xy 16.654095 -79.019693)
			(xy 16.733171 -79.042189) (xy 16.809835 -79.071883) (xy 16.883433 -79.108524) (xy 16.953337 -79.151797)
			(xy 17.01895 -79.201335) (xy 17.079714 -79.256715) (xy 17.13511 -79.317464) (xy 17.184666 -79.383064)
			(xy 17.227958 -79.452956) (xy 17.264619 -79.526543) (xy 17.294334 -79.603199) (xy 17.316851 -79.68227)
			(xy 17.331978 -79.76308) (xy 17.339586 -79.844941) (xy 17.340072 -79.886048) (xy 17.339651 -79.924337)
			(xy 17.333047 -80.000631) (xy 17.321325 -80.067912) (xy 31.49092 -80.067912) (xy 31.491505 -80.021516)
			(xy 31.501149 -79.929228) (xy 31.520344 -79.838444) (xy 31.548882 -79.750151) (xy 31.56712 -79.707486)
			(xy 31.570917 -79.697541) (xy 31.570921 -79.67628) (xy 31.56712 -79.666338) (xy 31.548881 -79.623673)
			(xy 31.520335 -79.535382) (xy 31.50114 -79.444598) (xy 31.491506 -79.352308) (xy 31.49092 -79.305912)
			(xy 31.491364 -79.264808) (xy 31.498948 -79.182951) (xy 31.514053 -79.102143) (xy 31.53655 -79.023074)
			(xy 31.566246 -78.946417) (xy 31.602889 -78.872828) (xy 31.646166 -78.802934) (xy 31.695708 -78.737331)
			(xy 31.751091 -78.67658) (xy 31.811844 -78.621197) (xy 31.877447 -78.571657) (xy 31.947342 -78.528381)
			(xy 32.020932 -78.49174) (xy 32.097589 -78.462044) (xy 32.176659 -78.439549) (xy 32.257467 -78.424446)
			(xy 32.339324 -78.416863) (xy 32.380428 -78.416404) (xy 32.426823 -78.417011) (xy 32.519111 -78.426649)
			(xy 32.609894 -78.445838) (xy 32.698189 -78.474369) (xy 32.740854 -78.492604) (xy 32.750796 -78.49641)
			(xy 32.77206 -78.49641) (xy 32.782002 -78.492604) (xy 32.824661 -78.474351) (xy 32.912954 -78.445809)
			(xy 33.00374 -78.426618) (xy 33.096032 -78.416987) (xy 33.142428 -78.416404) (xy 33.188823 -78.417011)
			(xy 33.281111 -78.426649) (xy 33.371894 -78.445838) (xy 33.460189 -78.474369) (xy 33.502854 -78.492604)
			(xy 33.512796 -78.49641) (xy 33.53406 -78.49641) (xy 33.544002 -78.492604) (xy 33.586661 -78.474351)
			(xy 33.674954 -78.445809) (xy 33.76574 -78.426618) (xy 33.858032 -78.416987) (xy 33.904428 -78.416404)
			(xy 33.945531 -78.41684) (xy 34.027387 -78.424427) (xy 34.108193 -78.439535) (xy 34.187261 -78.462034)
			(xy 34.263916 -78.491733) (xy 34.337503 -78.528378) (xy 34.407396 -78.571656) (xy 34.472997 -78.621198)
			(xy 34.533747 -78.676581) (xy 34.589128 -78.737334) (xy 34.638667 -78.802937) (xy 34.681942 -78.872832)
			(xy 34.718583 -78.946421) (xy 34.748278 -79.023077) (xy 34.770774 -79.102145) (xy 34.785878 -79.182953)
			(xy 34.793462 -79.264809) (xy 34.793936 -79.305912) (xy 34.793355 -79.352308) (xy 34.783709 -79.444596)
			(xy 34.764512 -79.53538) (xy 34.735974 -79.623673) (xy 34.717736 -79.666338) (xy 34.713922 -79.676278)
			(xy 34.713927 -79.697544) (xy 34.717736 -79.707486) (xy 34.735986 -79.750146) (xy 34.764529 -79.838439)
			(xy 34.78372 -79.929225) (xy 34.793352 -80.021516) (xy 34.793936 -80.067912) (xy 34.793445 -80.109014)
			(xy 34.785859 -80.190867) (xy 34.770754 -80.271671) (xy 34.756462 -80.3219) (xy 36.316384 -80.3219)
			(xy 36.320414 -80.237297) (xy 36.332468 -80.15346) (xy 36.352437 -80.071149) (xy 36.38014 -79.991108)
			(xy 36.415326 -79.914064) (xy 36.457676 -79.840712) (xy 36.506808 -79.771719) (xy 36.562275 -79.707709)
			(xy 36.623575 -79.649261) (xy 36.690154 -79.596905) (xy 36.761408 -79.551114) (xy 36.836693 -79.512305)
			(xy 36.915325 -79.480827) (xy 36.996594 -79.456967) (xy 37.079763 -79.440939) (xy 37.164078 -79.432891)
			(xy 37.206428 -79.432404) (xy 37.252823 -79.433011) (xy 37.345111 -79.442649) (xy 37.435894 -79.461838)
			(xy 37.524189 -79.490369) (xy 37.566854 -79.508604) (xy 37.576796 -79.51241) (xy 37.59806 -79.51241)
			(xy 37.608002 -79.508604) (xy 37.650661 -79.490351) (xy 37.738954 -79.461809) (xy 37.82974 -79.442618)
			(xy 37.922032 -79.432987) (xy 37.968428 -79.432404) (xy 38.010776 -79.432885) (xy 38.095089 -79.440938)
			(xy 38.178254 -79.456969) (xy 38.259519 -79.480833) (xy 38.338148 -79.512314) (xy 38.413428 -79.551126)
			(xy 38.484679 -79.596917) (xy 38.551254 -79.649274) (xy 38.61255 -79.707723) (xy 38.624229 -79.721202)
			(xy 38.932104 -79.721202) (xy 38.932492 -79.682918) (xy 38.939031 -79.606629) (xy 38.952112 -79.531187)
			(xy 38.971639 -79.45715) (xy 38.984174 -79.420974) (xy 38.986823 -79.412537) (xy 38.986824 -79.394867)
			(xy 38.984174 -79.38643) (xy 38.97165 -79.350251) (xy 38.952142 -79.276212) (xy 38.939061 -79.200771)
			(xy 38.932506 -79.124485) (xy 38.932104 -79.086202) (xy 38.932614 -79.045096) (xy 38.940198 -78.963235)
			(xy 38.955301 -78.882423) (xy 38.977795 -78.803349) (xy 39.007487 -78.726686) (xy 39.044125 -78.65309)
			(xy 39.087395 -78.583188) (xy 39.13693 -78.517575) (xy 39.192306 -78.456811) (xy 39.253052 -78.401415)
			(xy 39.318648 -78.351859) (xy 39.388537 -78.308566) (xy 39.462121 -78.271904) (xy 39.538774 -78.242187)
			(xy 39.617841 -78.219668) (xy 39.698648 -78.204538) (xy 39.780506 -78.196928) (xy 39.821612 -78.19644)
			(xy 39.861187 -78.196886) (xy 39.940021 -78.203956) (xy 40.017915 -78.218004) (xy 40.094253 -78.238918)
			(xy 40.131492 -78.25232) (xy 40.140161 -78.25515) (xy 40.158383 -78.25515) (xy 40.167052 -78.25232)
			(xy 40.204295 -78.238931) (xy 40.280633 -78.218022) (xy 40.358526 -78.203974) (xy 40.437358 -78.196896)
			(xy 40.476932 -78.19644) (xy 40.515222 -78.196836) (xy 40.591516 -78.203446) (xy 40.666959 -78.216598)
			(xy 40.74099 -78.236195) (xy 40.77716 -78.248764) (xy 40.785597 -78.251415) (xy 40.803267 -78.251415)
			(xy 40.811704 -78.248764) (xy 40.847877 -78.236207) (xy 40.921912 -78.216638) (xy 40.997353 -78.203495)
			(xy 41.073644 -78.196874) (xy 41.111932 -78.19644) (xy 41.153045 -78.196822) (xy 41.234919 -78.204413)
			(xy 41.315743 -78.219528) (xy 41.394827 -78.242037) (xy 41.471496 -78.271748) (xy 41.545097 -78.308408)
			(xy 41.615 -78.351704) (xy 41.680609 -78.401267) (xy 41.741364 -78.456672) (xy 41.796747 -78.517448)
			(xy 41.846285 -78.583076) (xy 41.889554 -78.652995) (xy 41.926187 -78.726609) (xy 41.955869 -78.80329)
			(xy 41.978349 -78.882383) (xy 41.993433 -78.963212) (xy 42.000993 -79.045089) (xy 42.00144 -79.086202)
			(xy 42.001051 -79.124486) (xy 41.994512 -79.200775) (xy 41.981431 -79.276217) (xy 41.961905 -79.350254)
			(xy 41.94937 -79.38643) (xy 41.946717 -79.394866) (xy 41.946718 -79.412537) (xy 41.94937 -79.420974)
			(xy 41.956228 -79.440786) (xy 41.961054 -79.455264) (xy 41.984676 -79.47406) (xy 42.107612 -79.485236)
			(xy 42.134282 -79.471012) (xy 42.141648 -79.457804) (xy 42.162886 -79.420162) (xy 42.211662 -79.348806)
			(xy 42.267127 -79.282516) (xy 42.328759 -79.221917) (xy 42.395977 -79.16758) (xy 42.468148 -79.120017)
			(xy 42.54459 -79.079676) (xy 42.624584 -79.046938) (xy 42.707376 -79.022112) (xy 42.792184 -79.00543)
			(xy 42.878211 -78.997052) (xy 42.921428 -78.99654) (xy 42.960998 -78.996961) (xy 43.039826 -79.003968)
			(xy 43.117719 -79.01795) (xy 43.194063 -79.038797) (xy 43.231308 -79.052166) (xy 43.239977 -79.054996)
			(xy 43.258199 -79.054996) (xy 43.266868 -79.052166) (xy 43.304113 -79.038798) (xy 43.380457 -79.017951)
			(xy 43.458351 -79.003969) (xy 43.537179 -78.996961) (xy 43.576748 -78.99654) (xy 43.615033 -78.996917)
			(xy 43.691321 -79.003459) (xy 43.766764 -79.016544) (xy 43.8408 -79.036074) (xy 43.876976 -79.04861)
			(xy 43.885413 -79.051261) (xy 43.903083 -79.051261) (xy 43.91152 -79.04861) (xy 43.947704 -79.036101)
			(xy 44.021742 -79.016589) (xy 44.097181 -79.003504) (xy 44.173465 -78.996944) (xy 44.211748 -78.99654)
			(xy 44.252853 -78.996921) (xy 44.334711 -79.004511) (xy 44.41552 -79.019621) (xy 44.49459 -79.042123)
			(xy 44.571246 -79.071824) (xy 44.644835 -79.108472) (xy 44.714729 -79.151754) (xy 44.78033 -79.2013)
			(xy 44.841081 -79.256687) (xy 44.896462 -79.317443) (xy 44.946 -79.383051) (xy 44.989274 -79.452949)
			(xy 45.025914 -79.526542) (xy 45.055608 -79.603201) (xy 45.078101 -79.682274) (xy 45.093203 -79.763084)
			(xy 45.100784 -79.844943) (xy 45.101256 -79.886048) (xy 45.10088 -79.924333) (xy 45.094337 -80.000621)
			(xy 45.081252 -80.076064) (xy 45.061722 -80.1501) (xy 45.049186 -80.186276) (xy 45.04651 -80.194706)
			(xy 45.046525 -80.212383) (xy 45.049186 -80.22082) (xy 45.061695 -80.257004) (xy 45.081207 -80.331042)
			(xy 45.094292 -80.406481) (xy 45.100852 -80.482765) (xy 45.101256 -80.521048) (xy 45.100779 -80.56215)
			(xy 45.093191 -80.644003) (xy 45.078082 -80.724806) (xy 45.055583 -80.803871) (xy 45.025886 -80.880523)
			(xy 44.989243 -80.954108) (xy 44.945967 -81.023998) (xy 44.896427 -81.089598) (xy 44.841047 -81.150347)
			(xy 44.780298 -81.205727) (xy 44.714698 -81.255267) (xy 44.644808 -81.298543) (xy 44.571223 -81.335186)
			(xy 44.494571 -81.364883) (xy 44.415506 -81.387382) (xy 44.334703 -81.402491) (xy 44.25285 -81.410079)
			(xy 44.211748 -81.410556) (xy 44.172821 -81.410159) (xy 44.095264 -81.403376) (xy 44.018597 -81.389841)
			(xy 43.943406 -81.369656) (xy 43.906694 -81.356708) (xy 43.898145 -81.353944) (xy 43.880191 -81.353944)
			(xy 43.871642 -81.356708) (xy 43.834927 -81.369647) (xy 43.759737 -81.38983) (xy 43.68307 -81.403365)
			(xy 43.605514 -81.41015) (xy 43.566588 -81.410556) (xy 43.527662 -81.410147) (xy 43.450105 -81.403368)
			(xy 43.373438 -81.389836) (xy 43.298246 -81.369655) (xy 43.261534 -81.356708) (xy 43.252985 -81.353944)
			(xy 43.235031 -81.353944) (xy 43.226482 -81.356708) (xy 43.189773 -81.369664) (xy 43.11458 -81.389843)
			(xy 43.037912 -81.403373) (xy 42.960355 -81.410152) (xy 42.921428 -81.410556) (xy 42.880327 -81.410007)
			(xy 42.798477 -81.402425) (xy 42.717674 -81.387323) (xy 42.63861 -81.364831) (xy 42.561959 -81.335139)
			(xy 42.488374 -81.298501) (xy 42.418483 -81.255231) (xy 42.352883 -81.205696) (xy 42.292134 -81.15032)
			(xy 42.236752 -81.089575) (xy 42.187212 -81.023979) (xy 42.143936 -80.954092) (xy 42.107292 -80.880511)
			(xy 42.077594 -80.803862) (xy 42.055094 -80.7248) (xy 42.039986 -80.643999) (xy 42.032397 -80.562149)
			(xy 42.03192 -80.521048) (xy 42.032296 -80.482763) (xy 42.03884 -80.406475) (xy 42.051924 -80.331032)
			(xy 42.071454 -80.256996) (xy 42.08399 -80.22082) (xy 42.086616 -80.212377) (xy 42.086631 -80.194712)
			(xy 42.08399 -80.186276) (xy 42.077132 -80.166464) (xy 42.072306 -80.151986) (xy 42.048684 -80.13319)
			(xy 41.925748 -80.122014) (xy 41.899078 -80.136238) (xy 41.891712 -80.149446) (xy 41.87046 -80.187088)
			(xy 41.821708 -80.258477) (xy 41.76626 -80.3248) (xy 41.70464 -80.385432) (xy 41.637429 -80.4398)
			(xy 41.565261 -80.487392) (xy 41.488816 -80.527758) (xy 41.408816 -80.560518) (xy 41.326016 -80.585364)
			(xy 41.241196 -80.60206) (xy 41.155156 -80.610449) (xy 41.111932 -80.610964) (xy 41.073001 -80.610512)
			(xy 40.995439 -80.603674) (xy 40.918771 -80.590081) (xy 40.843585 -80.569839) (xy 40.806878 -80.556862)
			(xy 40.798329 -80.554098) (xy 40.780375 -80.554098) (xy 40.771826 -80.556862) (xy 40.735116 -80.569831)
			(xy 40.65993 -80.590074) (xy 40.583264 -80.603673) (xy 40.505703 -80.610524) (xy 40.466772 -80.610964)
			(xy 40.42784 -80.61053) (xy 40.350278 -80.603686) (xy 40.27361 -80.590089) (xy 40.198425 -80.569842)
			(xy 40.161718 -80.556862) (xy 40.153169 -80.554098) (xy 40.135215 -80.554098) (xy 40.126666 -80.556862)
			(xy 40.089961 -80.569848) (xy 40.014774 -80.590087) (xy 39.938106 -80.603681) (xy 39.860544 -80.610526)
			(xy 39.821612 -80.610964) (xy 39.7805 -80.610536) (xy 39.698628 -80.602949) (xy 39.617805 -80.587838)
			(xy 39.538721 -80.565333) (xy 39.462052 -80.535625) (xy 39.388452 -80.498968) (xy 39.318549 -80.455676)
			(xy 39.25294 -80.406116) (xy 39.192184 -80.350714) (xy 39.136801 -80.28994) (xy 39.087263 -80.224315)
			(xy 39.043992 -80.154398) (xy 39.007359 -80.080786) (xy 38.977676 -80.004108) (xy 38.955196 -79.925017)
			(xy 38.940112 -79.844189) (xy 38.932551 -79.762314) (xy 38.932104 -79.721202) (xy 38.624229 -79.721202)
			(xy 38.668014 -79.771733) (xy 38.717142 -79.840725) (xy 38.759489 -79.914075) (xy 38.794673 -79.991118)
			(xy 38.822374 -80.071156) (xy 38.842341 -80.153465) (xy 38.854395 -80.237299) (xy 38.858425 -80.3219)
			(xy 38.854395 -80.406501) (xy 38.842341 -80.490335) (xy 38.822374 -80.572644) (xy 38.794673 -80.652682)
			(xy 38.759489 -80.729725) (xy 38.717142 -80.803075) (xy 38.668014 -80.872067) (xy 38.61255 -80.936077)
			(xy 38.551254 -80.994526) (xy 38.484679 -81.046883) (xy 38.413428 -81.092674) (xy 38.338148 -81.131486)
			(xy 38.259519 -81.162967) (xy 38.178254 -81.186831) (xy 38.095089 -81.202862) (xy 38.010776 -81.210915)
			(xy 37.968428 -81.21142) (xy 37.922033 -81.210826) (xy 37.829745 -81.201184) (xy 37.738961 -81.181991)
			(xy 37.650667 -81.153456) (xy 37.608002 -81.13522) (xy 37.59806 -81.131414) (xy 37.576796 -81.131414)
			(xy 37.566854 -81.13522) (xy 37.524188 -81.153456) (xy 37.435897 -81.182002) (xy 37.345113 -81.201198)
			(xy 37.252824 -81.210834) (xy 37.206428 -81.21142) (xy 37.164078 -81.210909) (xy 37.079763 -81.202861)
			(xy 36.996594 -81.186833) (xy 36.915325 -81.162973) (xy 36.836693 -81.131495) (xy 36.761408 -81.092686)
			(xy 36.690154 -81.046895) (xy 36.623575 -80.994539) (xy 36.562274 -80.936091) (xy 36.506808 -80.872081)
			(xy 36.457676 -80.803088) (xy 36.415326 -80.729736) (xy 36.38014 -80.652692) (xy 36.352437 -80.572651)
			(xy 36.332468 -80.49034) (xy 36.320414 -80.406503) (xy 36.316384 -80.3219) (xy 34.756462 -80.3219)
			(xy 34.748257 -80.350736) (xy 34.718561 -80.427389) (xy 34.68192 -80.500975) (xy 34.638645 -80.570866)
			(xy 34.589107 -80.636466) (xy 34.533727 -80.697216) (xy 34.472978 -80.752597) (xy 34.407379 -80.802136)
			(xy 34.337489 -80.845412) (xy 34.263904 -80.882055) (xy 34.187252 -80.911752) (xy 34.108186 -80.93425)
			(xy 34.027383 -80.949357) (xy 33.94553 -80.956944) (xy 33.904428 -80.95742) (xy 33.858033 -80.956826)
			(xy 33.765745 -80.947184) (xy 33.674961 -80.927991) (xy 33.586667 -80.899456) (xy 33.544002 -80.88122)
			(xy 33.53406 -80.877414) (xy 33.512796 -80.877414) (xy 33.502854 -80.88122) (xy 33.460188 -80.899456)
			(xy 33.371897 -80.928002) (xy 33.281113 -80.947198) (xy 33.188824 -80.956834) (xy 33.142428 -80.95742)
			(xy 33.096033 -80.956826) (xy 33.003745 -80.947184) (xy 32.912961 -80.927991) (xy 32.824667 -80.899456)
			(xy 32.782002 -80.88122) (xy 32.77206 -80.877414) (xy 32.750796 -80.877414) (xy 32.740854 -80.88122)
			(xy 32.698188 -80.899456) (xy 32.609897 -80.928002) (xy 32.519113 -80.947198) (xy 32.426824 -80.956834)
			(xy 32.380428 -80.95742) (xy 32.339326 -80.956921) (xy 32.257471 -80.949339) (xy 32.176666 -80.934236)
			(xy 32.097599 -80.911742) (xy 32.020944 -80.882048) (xy 31.947357 -80.845408) (xy 31.877464 -80.802135)
			(xy 31.811862 -80.752597) (xy 31.751111 -80.697218) (xy 31.695728 -80.636469) (xy 31.646188 -80.570869)
			(xy 31.602911 -80.500978) (xy 31.566268 -80.427392) (xy 31.536571 -80.350739) (xy 31.514073 -80.271673)
			(xy 31.498967 -80.190868) (xy 31.491381 -80.109014) (xy 31.49092 -80.067912) (xy 17.321325 -80.067912)
			(xy 17.319903 -80.076074) (xy 17.300314 -80.150105) (xy 17.287748 -80.186276) (xy 17.285073 -80.194707)
			(xy 17.285089 -80.212383) (xy 17.287748 -80.22082) (xy 17.300282 -80.257001) (xy 17.319857 -80.331033)
			(xy 17.333007 -80.406471) (xy 17.339634 -80.48276) (xy 17.340072 -80.521048) (xy 17.339693 -80.56216)
			(xy 17.332101 -80.644034) (xy 17.316985 -80.724858) (xy 17.294475 -80.803942) (xy 17.264763 -80.880611)
			(xy 17.228102 -80.954211) (xy 17.184806 -81.024113) (xy 17.135243 -81.089722) (xy 17.079838 -81.150477)
			(xy 17.019062 -81.205859) (xy 16.953434 -81.255397) (xy 16.883515 -81.298667) (xy 16.809901 -81.335299)
			(xy 16.733221 -81.364983) (xy 16.654129 -81.387462) (xy 16.573299 -81.402547) (xy 16.491423 -81.410109)
			(xy 16.45031 -81.410556) (xy 16.411384 -81.410141) (xy 16.333827 -81.403363) (xy 16.25716 -81.389833)
			(xy 16.181969 -81.369654) (xy 16.145256 -81.356708) (xy 16.136707 -81.353944) (xy 16.118753 -81.353944)
			(xy 16.110204 -81.356708) (xy 16.073493 -81.369658) (xy 15.998301 -81.389838) (xy 15.921633 -81.40337)
			(xy 15.844076 -81.410151) (xy 15.80515 -81.410556) (xy 15.766223 -81.410159) (xy 15.688666 -81.403376)
			(xy 15.611999 -81.389841) (xy 15.536808 -81.369656) (xy 15.500096 -81.356708) (xy 15.491547 -81.353944)
			(xy 15.473593 -81.353944) (xy 15.465044 -81.356708) (xy 15.428329 -81.369647) (xy 15.353138 -81.38983)
			(xy 15.276472 -81.403365) (xy 15.198916 -81.41015) (xy 15.15999 -81.410556) (xy 15.118883 -81.410097)
			(xy 15.037019 -81.402512) (xy 14.956205 -81.387407) (xy 14.877128 -81.364911) (xy 14.800464 -81.335216)
			(xy 14.726866 -81.298576) (xy 14.656962 -81.255302) (xy 14.591348 -81.205764) (xy 14.530584 -81.150384)
			(xy 14.475188 -81.089635) (xy 14.425633 -81.024034) (xy 14.38234 -80.954142) (xy 14.34568 -80.880554)
			(xy 14.315965 -80.803898) (xy 14.293448 -80.724827) (xy 14.278321 -80.644016) (xy 14.270714 -80.562155)
			(xy 14.270228 -80.521048) (xy 14.270648 -80.482759) (xy 14.277252 -80.406465) (xy 14.290397 -80.331022)
			(xy 14.309986 -80.256991) (xy 14.322552 -80.22082) (xy 14.325179 -80.212377) (xy 14.325194 -80.194712)
			(xy 14.322552 -80.186276) (xy 14.315694 -80.166464) (xy 14.310868 -80.151986) (xy 14.287246 -80.13319)
			(xy 14.16431 -80.122014) (xy 14.13764 -80.136238) (xy 14.130274 -80.149446) (xy 14.10905 -80.187104)
			(xy 14.060295 -80.258494) (xy 14.004844 -80.324817) (xy 13.943222 -80.385448) (xy 13.876007 -80.439815)
			(xy 13.803836 -80.487406) (xy 13.727389 -80.527771) (xy 13.647386 -80.560529) (xy 13.564583 -80.585372)
			(xy 13.479761 -80.602065) (xy 13.393719 -80.610451) (xy 13.350494 -80.610964) (xy 13.311562 -80.610524)
			(xy 13.234 -80.603682) (xy 13.157333 -80.590086) (xy 13.082147 -80.569841) (xy 13.04544 -80.556862)
			(xy 13.036891 -80.554098) (xy 13.018937 -80.554098) (xy 13.010388 -80.556862) (xy 12.973681 -80.569842)
			(xy 12.898495 -80.590082) (xy 12.821827 -80.603678) (xy 12.744265 -80.610525) (xy 12.705334 -80.610964)
			(xy 12.666403 -80.610512) (xy 12.588841 -80.603673) (xy 12.512173 -80.590081) (xy 12.436987 -80.569839)
			(xy 12.40028 -80.556862) (xy 12.391731 -80.554098) (xy 12.373777 -80.554098) (xy 12.365228 -80.556862)
			(xy 12.328517 -80.56983) (xy 12.253332 -80.590074) (xy 12.176666 -80.603673) (xy 12.099105 -80.610524)
			(xy 12.060174 -80.610964) (xy 12.019059 -80.610512) (xy 11.937181 -80.602923) (xy 11.856352 -80.587811)
			(xy 11.777263 -80.565306) (xy 11.700587 -80.5356) (xy 11.626979 -80.498945) (xy 11.557067 -80.455656)
			(xy 11.491448 -80.406101) (xy 11.430681 -80.350703) (xy 11.375284 -80.289934) (xy 11.32573 -80.224313)
			(xy 11.282443 -80.1544) (xy 11.245791 -80.080791) (xy 11.216086 -80.004114) (xy 11.193584 -79.925024)
			(xy 11.178474 -79.844195) (xy 11.170887 -79.762317) (xy 11.170412 -79.721202) (xy 10.862798 -79.721202)
			(xy 10.906589 -79.77174) (xy 10.955718 -79.840732) (xy 10.998066 -79.914082) (xy 11.033251 -79.991125)
			(xy 11.060953 -80.071164) (xy 11.080921 -80.153474) (xy 11.092974 -80.237309) (xy 11.097005 -80.32191)
			(xy 11.092974 -80.406511) (xy 11.080921 -80.490346) (xy 11.060953 -80.572656) (xy 11.033251 -80.652695)
			(xy 10.998066 -80.729738) (xy 10.955718 -80.803088) (xy 10.906589 -80.87208) (xy 10.851124 -80.93609)
			(xy 10.789826 -80.994538) (xy 10.723249 -81.046894) (xy 10.651997 -81.092685) (xy 10.576715 -81.131496)
			(xy 10.498085 -81.162974) (xy 10.416819 -81.186836) (xy 10.333652 -81.202865) (xy 10.249339 -81.210916)
			(xy 10.20699 -81.21142) (xy 10.160594 -81.21084) (xy 10.068306 -81.201194) (xy 9.977522 -81.181997)
			(xy 9.889229 -81.153458) (xy 9.846564 -81.13522) (xy 9.836622 -81.131414) (xy 9.815358 -81.131414)
			(xy 9.805416 -81.13522) (xy 9.762755 -81.153469) (xy 9.674462 -81.182012) (xy 9.583677 -81.201204)
			(xy 9.491386 -81.210836) (xy 9.44499 -81.21142) (xy 9.402642 -81.210912) (xy 9.318328 -81.202861)
			(xy 9.235162 -81.186832) (xy 9.153896 -81.162971) (xy 9.075266 -81.131492) (xy 8.999985 -81.092682)
			(xy 8.928733 -81.046891) (xy 8.862157 -80.994535) (xy 8.800859 -80.936088) (xy 8.745394 -80.872078)
			(xy 8.696266 -80.803086) (xy 8.653917 -80.729736) (xy 8.618733 -80.652693) (xy 8.591031 -80.572655)
			(xy 8.571063 -80.490346) (xy 8.55901 -80.406511) (xy 8.55498 -80.32191) (xy 7.757306 -80.32191) (xy 7.749086 -80.350795)
			(xy 7.719379 -80.427461) (xy 7.682723 -80.50106) (xy 7.639433 -80.570961) (xy 7.589876 -80.636569)
			(xy 7.534476 -80.697324) (xy 7.473705 -80.752707) (xy 7.408083 -80.802245) (xy 7.338169 -80.845516)
			(xy 7.264561 -80.882151) (xy 7.187885 -80.911836) (xy 7.108798 -80.934318) (xy 7.027973 -80.949406)
			(xy 6.946101 -80.956971) (xy 6.90499 -80.95742) (xy 6.858594 -80.95684) (xy 6.766306 -80.947194)
			(xy 6.675522 -80.927997) (xy 6.587229 -80.899458) (xy 6.544564 -80.88122) (xy 6.534622 -80.877414)
			(xy 6.513358 -80.877414) (xy 6.503416 -80.88122) (xy 6.460755 -80.899469) (xy 6.372462 -80.928012)
			(xy 6.281677 -80.947204) (xy 6.189386 -80.956836) (xy 6.14299 -80.95742) (xy 6.096594 -80.95684)
			(xy 6.004306 -80.947194) (xy 5.913522 -80.927997) (xy 5.825229 -80.899458) (xy 5.782564 -80.88122)
			(xy 5.772622 -80.877414) (xy 5.751358 -80.877414) (xy 5.741416 -80.88122) (xy 5.698755 -80.899469)
			(xy 5.610462 -80.928012) (xy 5.519677 -80.947204) (xy 5.427386 -80.956836) (xy 5.38099 -80.95742)
			(xy 5.334594 -80.95684) (xy 5.242306 -80.947194) (xy 5.151522 -80.927997) (xy 5.063229 -80.899458)
			(xy 5.020564 -80.88122) (xy 5.010622 -80.877414) (xy 4.989358 -80.877414) (xy 4.979416 -80.88122)
			(xy 4.936755 -80.899469) (xy 4.848462 -80.928012) (xy 4.757677 -80.947204) (xy 4.665386 -80.956836)
			(xy 4.61899 -80.95742) (xy 4.577883 -80.956947) (xy 4.49602 -80.949363) (xy 4.415206 -80.934259)
			(xy 4.33613 -80.911764) (xy 4.259466 -80.88207) (xy 4.185868 -80.845431) (xy 4.115964 -80.802158)
			(xy 4.05035 -80.752621) (xy 3.989587 -80.697242) (xy 3.93419 -80.636493) (xy 3.884635 -80.570894)
			(xy 3.841342 -80.501002) (xy 3.804682 -80.427415) (xy 3.774966 -80.35076) (xy 3.752449 -80.27169)
			(xy 3.737322 -80.19088) (xy 3.729714 -80.109019) (xy 3.729228 -80.067912) (xy 0.509016 -80.067912)
			(xy 0.509016 -84.385912) (xy 39.460424 -84.385912) (xy 39.461008 -84.339516) (xy 39.470653 -84.247228)
			(xy 39.489848 -84.156444) (xy 39.518386 -84.068151) (xy 39.536624 -84.025486) (xy 39.54042 -84.015541)
			(xy 39.540425 -83.99428) (xy 39.536624 -83.984338) (xy 39.518385 -83.941673) (xy 39.489839 -83.853382)
			(xy 39.470644 -83.762598) (xy 39.46101 -83.670308) (xy 39.460424 -83.623912) (xy 39.460928 -83.581564)
			(xy 39.468979 -83.49725) (xy 39.485008 -83.414084) (xy 39.508869 -83.332817) (xy 39.540348 -83.254187)
			(xy 39.579159 -83.178906) (xy 39.624949 -83.107654) (xy 39.677305 -83.041078) (xy 39.735753 -82.97978)
			(xy 39.799763 -82.924315) (xy 39.868755 -82.875186) (xy 39.942105 -82.832837) (xy 40.019148 -82.797653)
			(xy 40.099187 -82.769951) (xy 40.181496 -82.749983) (xy 40.265331 -82.73793) (xy 40.349932 -82.7339)
			(xy 40.434533 -82.73793) (xy 40.518368 -82.749983) (xy 40.600677 -82.769951) (xy 40.680716 -82.797653)
			(xy 40.757759 -82.832837) (xy 40.831109 -82.875186) (xy 40.900101 -82.924315) (xy 40.964111 -82.97978)
			(xy 41.022559 -83.041078) (xy 41.074915 -83.107654) (xy 41.120705 -83.178906) (xy 41.159516 -83.254187)
			(xy 41.190995 -83.332817) (xy 41.214856 -83.414084) (xy 41.230885 -83.49725) (xy 41.238936 -83.581564)
			(xy 41.23944 -83.623912) (xy 41.238867 -83.670308) (xy 41.22922 -83.762597) (xy 41.210021 -83.853381)
			(xy 41.18148 -83.941674) (xy 41.16324 -83.984338) (xy 41.159426 -83.994278) (xy 41.159431 -84.015544)
			(xy 41.16324 -84.025486) (xy 41.181491 -84.068146) (xy 41.210033 -84.156439) (xy 41.229224 -84.247225)
			(xy 41.238856 -84.339516) (xy 41.23944 -84.385912) (xy 41.238936 -84.42826) (xy 41.230885 -84.512574)
			(xy 41.214856 -84.59574) (xy 41.190995 -84.677007) (xy 41.159516 -84.755637) (xy 41.120705 -84.830918)
			(xy 41.074915 -84.90217) (xy 41.022559 -84.968746) (xy 40.964111 -85.030044) (xy 40.900101 -85.085509)
			(xy 40.831109 -85.134638) (xy 40.757759 -85.176987) (xy 40.680716 -85.212171) (xy 40.600677 -85.239873)
			(xy 40.518368 -85.259841) (xy 40.434533 -85.271894) (xy 40.349932 -85.275925) (xy 40.265331 -85.271894)
			(xy 40.181496 -85.259841) (xy 40.099187 -85.239873) (xy 40.019148 -85.212171) (xy 39.942105 -85.176987)
			(xy 39.868755 -85.134638) (xy 39.799763 -85.085509) (xy 39.735753 -85.030044) (xy 39.677305 -84.968746)
			(xy 39.624949 -84.90217) (xy 39.579159 -84.830918) (xy 39.540348 -84.755637) (xy 39.508869 -84.677007)
			(xy 39.485008 -84.59574) (xy 39.468979 -84.512574) (xy 39.460928 -84.42826) (xy 39.460424 -84.385912)
			(xy 0.509016 -84.385912) (xy 0.509016 -89.153238) (xy 12.572492 -89.153238) (xy 12.572861 -89.114953)
			(xy 12.579406 -89.038664) (xy 12.592493 -88.963222) (xy 12.612024 -88.889186) (xy 12.624562 -88.85301)
			(xy 12.627193 -88.844568) (xy 12.627206 -88.826902) (xy 12.624562 -88.818466) (xy 12.612047 -88.782284)
			(xy 12.592537 -88.708246) (xy 12.579454 -88.632806) (xy 12.572895 -88.556521) (xy 12.572492 -88.518238)
			(xy 12.572861 -88.479953) (xy 12.579406 -88.403664) (xy 12.592493 -88.328222) (xy 12.612024 -88.254186)
			(xy 12.624562 -88.21801) (xy 12.627193 -88.209568) (xy 12.627206 -88.191902) (xy 12.624562 -88.183466)
			(xy 12.612047 -88.147284) (xy 12.592537 -88.073246) (xy 12.579454 -87.997806) (xy 12.572895 -87.921521)
			(xy 12.572492 -87.883238) (xy 12.573026 -87.842034) (xy 12.580643 -87.759979) (xy 12.595814 -87.678979)
			(xy 12.618411 -87.59973) (xy 12.64824 -87.52291) (xy 12.685044 -87.449177) (xy 12.728508 -87.379163)
			(xy 12.778261 -87.313469) (xy 12.833875 -87.252657) (xy 12.894874 -87.197247) (xy 12.960735 -87.147716)
			(xy 13.030895 -87.104488) (xy 13.104751 -87.067932) (xy 13.181671 -87.038362) (xy 13.221208 -87.02675)
			(xy 13.231515 -87.023234) (xy 13.248152 -87.009222) (xy 13.257547 -86.989605) (xy 13.258292 -86.978744)
			(xy 13.259547 -86.93559) (xy 13.26949 -86.849826) (xy 13.287695 -86.765428) (xy 13.313992 -86.68319)
			(xy 13.348131 -86.603888) (xy 13.389793 -86.528265) (xy 13.438585 -86.457035) (xy 13.494049 -86.390867)
			(xy 13.555662 -86.330383) (xy 13.622845 -86.276153) (xy 13.694966 -86.228687) (xy 13.771346 -86.188431)
			(xy 13.851267 -86.155764) (xy 13.933976 -86.130994) (xy 14.018696 -86.114353) (xy 14.10463 -86.105998)
			(xy 14.1478 -86.105492) (xy 14.188902 -86.105967) (xy 14.270757 -86.113552) (xy 14.351562 -86.128657)
			(xy 14.430629 -86.151153) (xy 14.507283 -86.180849) (xy 14.58087 -86.217491) (xy 14.650762 -86.260766)
			(xy 14.716363 -86.310306) (xy 14.722951 -86.316312) (xy 35.838892 -86.316312) (xy 35.839383 -86.274361)
			(xy 35.847275 -86.19083) (xy 35.86299 -86.108412) (xy 35.886388 -86.027838) (xy 35.901376 -85.988652)
			(xy 35.904581 -85.979525) (xy 35.904565 -85.960194) (xy 35.901376 -85.95106) (xy 35.886389 -85.911873)
			(xy 35.862968 -85.831304) (xy 35.847246 -85.748886) (xy 35.839364 -85.665352) (xy 35.838892 -85.6234)
			(xy 35.839396 -85.581052) (xy 35.847447 -85.496738) (xy 35.863476 -85.413572) (xy 35.887337 -85.332305)
			(xy 35.918816 -85.253675) (xy 35.957627 -85.178394) (xy 36.003417 -85.107142) (xy 36.055773 -85.040566)
			(xy 36.114221 -84.979268) (xy 36.178231 -84.923803) (xy 36.247223 -84.874674) (xy 36.320573 -84.832325)
			(xy 36.397616 -84.797141) (xy 36.477655 -84.769439) (xy 36.559964 -84.749471) (xy 36.643799 -84.737418)
			(xy 36.7284 -84.733388) (xy 36.813001 -84.737418) (xy 36.896836 -84.749471) (xy 36.979145 -84.769439)
			(xy 37.059184 -84.797141) (xy 37.136227 -84.832325) (xy 37.209577 -84.874674) (xy 37.278569 -84.923803)
			(xy 37.342579 -84.979268) (xy 37.401027 -85.040566) (xy 37.453383 -85.107142) (xy 37.499173 -85.178394)
			(xy 37.537984 -85.253675) (xy 37.569463 -85.332305) (xy 37.593324 -85.413572) (xy 37.609353 -85.496738)
			(xy 37.617404 -85.581052) (xy 37.617908 -85.6234) (xy 37.617421 -85.665351) (xy 37.609528 -85.748882)
			(xy 37.593812 -85.8313) (xy 37.570412 -85.911874) (xy 37.555424 -85.95106) (xy 37.552267 -85.9602)
			(xy 37.552252 -85.979519) (xy 37.555424 -85.988652) (xy 37.570414 -86.027838) (xy 37.593835 -86.108407)
			(xy 37.609556 -86.190826) (xy 37.617436 -86.27436) (xy 37.617908 -86.316312) (xy 37.617404 -86.35866)
			(xy 37.609353 -86.442974) (xy 37.593324 -86.52614) (xy 37.569463 -86.607407) (xy 37.537984 -86.686037)
			(xy 37.499173 -86.761318) (xy 37.453383 -86.83257) (xy 37.401027 -86.899146) (xy 37.342579 -86.960444)
			(xy 37.278569 -87.015909) (xy 37.209577 -87.065038) (xy 37.136227 -87.107387) (xy 37.059184 -87.142571)
			(xy 36.979145 -87.170273) (xy 36.896836 -87.190241) (xy 36.813001 -87.202294) (xy 36.7284 -87.206325)
			(xy 36.643799 -87.202294) (xy 36.559964 -87.190241) (xy 36.477655 -87.170273) (xy 36.397616 -87.142571)
			(xy 36.320573 -87.107387) (xy 36.247223 -87.065038) (xy 36.178231 -87.015909) (xy 36.114221 -86.960444)
			(xy 36.055773 -86.899146) (xy 36.003417 -86.83257) (xy 35.957627 -86.761318) (xy 35.918816 -86.686037)
			(xy 35.887337 -86.607407) (xy 35.863476 -86.52614) (xy 35.847447 -86.442974) (xy 35.839396 -86.35866)
			(xy 35.838892 -86.316312) (xy 14.722951 -86.316312) (xy 14.777113 -86.365687) (xy 14.832494 -86.426437)
			(xy 14.882034 -86.492038) (xy 14.925309 -86.56193) (xy 14.961951 -86.635517) (xy 14.991647 -86.712171)
			(xy 15.014143 -86.791238) (xy 15.029248 -86.872043) (xy 15.036833 -86.953898) (xy 15.037308 -86.995)
			(xy 15.036809 -87.036205) (xy 15.029189 -87.118261) (xy 15.014014 -87.199261) (xy 14.991413 -87.278511)
			(xy 14.961582 -87.355332) (xy 14.924775 -87.429064) (xy 14.881308 -87.499078) (xy 14.831553 -87.564772)
			(xy 14.775936 -87.625584) (xy 14.714935 -87.680993) (xy 14.649071 -87.730524) (xy 14.578909 -87.773752)
			(xy 14.505051 -87.810307) (xy 14.428129 -87.839876) (xy 14.388592 -87.851488) (xy 14.378272 -87.854974)
			(xy 14.361634 -87.868997) (xy 14.352246 -87.888628) (xy 14.351508 -87.899494) (xy 14.349967 -87.947817)
			(xy 14.337717 -88.043725) (xy 14.315149 -88.137742) (xy 14.299438 -88.183466) (xy 14.296768 -88.191898)
			(xy 14.296781 -88.209573) (xy 14.299438 -88.21801) (xy 14.311946 -88.254194) (xy 14.331458 -88.328232)
			(xy 14.344543 -88.403671) (xy 14.351104 -88.479955) (xy 14.351508 -88.518238) (xy 14.351132 -88.556523)
			(xy 14.344589 -88.632811) (xy 14.331504 -88.708254) (xy 14.311975 -88.78229) (xy 14.299438 -88.818466)
			(xy 14.296768 -88.826898) (xy 14.296781 -88.844573) (xy 14.299438 -88.85301) (xy 14.311946 -88.889194)
			(xy 14.331458 -88.963232) (xy 14.344543 -89.038671) (xy 14.351104 -89.114955) (xy 14.351508 -89.153238)
			(xy 14.351004 -89.195586) (xy 14.342953 -89.2799) (xy 14.328055 -89.3572) (xy 37.185092 -89.3572)
			(xy 37.185578 -89.314532) (xy 37.193723 -89.229587) (xy 37.209955 -89.14581) (xy 37.234128 -89.06397)
			(xy 37.249608 -89.024206) (xy 37.252896 -89.014962) (xy 37.252881 -88.995357) (xy 37.249608 -88.986106)
			(xy 37.234119 -88.946345) (xy 37.209928 -88.864509) (xy 37.193695 -88.78073) (xy 37.185569 -88.695781)
			(xy 37.185092 -88.653112) (xy 37.185583 -88.611161) (xy 37.193475 -88.52763) (xy 37.20919 -88.445212)
			(xy 37.232588 -88.364638) (xy 37.247576 -88.325452) (xy 37.250781 -88.316325) (xy 37.250765 -88.296994)
			(xy 37.247576 -88.28786) (xy 37.232589 -88.248673) (xy 37.209168 -88.168104) (xy 37.193446 -88.085686)
			(xy 37.185564 -88.002152) (xy 37.185092 -87.9602) (xy 37.185596 -87.917852) (xy 37.193647 -87.833538)
			(xy 37.209676 -87.750372) (xy 37.233537 -87.669105) (xy 37.265016 -87.590475) (xy 37.303827 -87.515194)
			(xy 37.349617 -87.443942) (xy 37.401973 -87.377366) (xy 37.460421 -87.316068) (xy 37.524431 -87.260603)
			(xy 37.593423 -87.211474) (xy 37.666773 -87.169125) (xy 37.743816 -87.133941) (xy 37.823855 -87.106239)
			(xy 37.906164 -87.086271) (xy 37.989999 -87.074218) (xy 38.0746 -87.070188) (xy 38.159201 -87.074218)
			(xy 38.243036 -87.086271) (xy 38.325345 -87.106239) (xy 38.405384 -87.133941) (xy 38.482427 -87.169125)
			(xy 38.555777 -87.211474) (xy 38.624769 -87.260603) (xy 38.688779 -87.316068) (xy 38.747227 -87.377366)
			(xy 38.799583 -87.443942) (xy 38.845373 -87.515194) (xy 38.884184 -87.590475) (xy 38.915663 -87.669105)
			(xy 38.939524 -87.750372) (xy 38.955553 -87.833538) (xy 38.963604 -87.917852) (xy 38.964108 -87.9602)
			(xy 38.963621 -88.002151) (xy 38.955728 -88.085682) (xy 38.940012 -88.1681) (xy 38.916612 -88.248674)
			(xy 38.901624 -88.28786) (xy 38.898467 -88.297) (xy 38.898452 -88.316319) (xy 38.901624 -88.325452)
			(xy 38.916614 -88.364638) (xy 38.940035 -88.445207) (xy 38.955756 -88.527626) (xy 38.963636 -88.61116)
			(xy 38.964108 -88.653112) (xy 38.963625 -88.69578) (xy 38.95548 -88.780726) (xy 38.939246 -88.864503)
			(xy 38.915073 -88.946342) (xy 38.899592 -88.986106) (xy 38.896352 -88.995364) (xy 38.896337 -89.014956)
			(xy 38.899592 -89.024206) (xy 38.915085 -89.063966) (xy 38.939275 -89.145802) (xy 38.955507 -89.229582)
			(xy 38.963632 -89.314531) (xy 38.964108 -89.3572) (xy 38.963604 -89.399548) (xy 38.955553 -89.483862)
			(xy 38.939524 -89.567028) (xy 38.915663 -89.648295) (xy 38.884184 -89.726925) (xy 38.845373 -89.802206)
			(xy 38.799583 -89.873458) (xy 38.747227 -89.940034) (xy 38.688779 -90.001332) (xy 38.624769 -90.056797)
			(xy 38.555777 -90.105926) (xy 38.482427 -90.148275) (xy 38.405384 -90.183459) (xy 38.325345 -90.211161)
			(xy 38.243036 -90.231129) (xy 38.159201 -90.243182) (xy 38.0746 -90.247213) (xy 37.989999 -90.243182)
			(xy 37.906164 -90.231129) (xy 37.823855 -90.211161) (xy 37.743816 -90.183459) (xy 37.666773 -90.148275)
			(xy 37.593423 -90.105926) (xy 37.524431 -90.056797) (xy 37.460421 -90.001332) (xy 37.401973 -89.940034)
			(xy 37.349617 -89.873458) (xy 37.303827 -89.802206) (xy 37.265016 -89.726925) (xy 37.233537 -89.648295)
			(xy 37.209676 -89.567028) (xy 37.193647 -89.483862) (xy 37.185596 -89.399548) (xy 37.185092 -89.3572)
			(xy 14.328055 -89.3572) (xy 14.326924 -89.363066) (xy 14.303063 -89.444333) (xy 14.271584 -89.522963)
			(xy 14.232773 -89.598244) (xy 14.186983 -89.669496) (xy 14.134627 -89.736072) (xy 14.076179 -89.79737)
			(xy 14.012169 -89.852835) (xy 13.943177 -89.901964) (xy 13.869827 -89.944313) (xy 13.792784 -89.979497)
			(xy 13.712745 -90.007199) (xy 13.630436 -90.027167) (xy 13.546601 -90.03922) (xy 13.462 -90.043251)
			(xy 13.377399 -90.03922) (xy 13.293564 -90.027167) (xy 13.211255 -90.007199) (xy 13.131216 -89.979497)
			(xy 13.054173 -89.944313) (xy 12.980823 -89.901964) (xy 12.911831 -89.852835) (xy 12.847821 -89.79737)
			(xy 12.789373 -89.736072) (xy 12.737017 -89.669496) (xy 12.691227 -89.598244) (xy 12.652416 -89.522963)
			(xy 12.620937 -89.444333) (xy 12.597076 -89.363066) (xy 12.581047 -89.2799) (xy 12.572996 -89.195586)
			(xy 12.572492 -89.153238) (xy 0.509016 -89.153238) (xy 0.509016 -91.878912) (xy 3.555492 -91.878912)
			(xy 3.556079 -91.832517) (xy 3.565723 -91.740228) (xy 3.584918 -91.649445) (xy 3.613455 -91.561151)
			(xy 3.631692 -91.518486) (xy 3.63549 -91.508542) (xy 3.635495 -91.48728) (xy 3.631692 -91.477338)
			(xy 3.613451 -91.434674) (xy 3.584906 -91.346382) (xy 3.565712 -91.255598) (xy 3.556077 -91.163308)
			(xy 3.555492 -91.116912) (xy 3.555964 -91.075809) (xy 3.563548 -90.993954) (xy 3.578652 -90.913147)
			(xy 3.601148 -90.834079) (xy 3.630843 -90.757424) (xy 3.667485 -90.683836) (xy 3.71076 -90.613943)
			(xy 3.7603 -90.548341) (xy 3.815681 -90.487589) (xy 3.876432 -90.432207) (xy 3.942033 -90.382667)
			(xy 4.011926 -90.339391) (xy 4.085513 -90.302748) (xy 4.162168 -90.273052) (xy 4.241236 -90.250555)
			(xy 4.322042 -90.235449) (xy 4.403897 -90.227864) (xy 4.445 -90.227404) (xy 4.491396 -90.227986)
			(xy 4.583684 -90.237631) (xy 4.674468 -90.256827) (xy 4.762761 -90.285366) (xy 4.805426 -90.303604)
			(xy 4.815368 -90.30741) (xy 4.836632 -90.30741) (xy 4.846574 -90.303604) (xy 4.889236 -90.28536)
			(xy 4.977529 -90.256816) (xy 5.068314 -90.237622) (xy 5.160604 -90.227989) (xy 5.207 -90.227404)
			(xy 5.253396 -90.227986) (xy 5.345684 -90.237631) (xy 5.436468 -90.256827) (xy 5.524761 -90.285366)
			(xy 5.567426 -90.303604) (xy 5.577368 -90.30741) (xy 5.598632 -90.30741) (xy 5.608574 -90.303604)
			(xy 5.651236 -90.28536) (xy 5.739529 -90.256816) (xy 5.830314 -90.237622) (xy 5.922604 -90.227989)
			(xy 5.969 -90.227404) (xy 6.015396 -90.227986) (xy 6.107684 -90.237631) (xy 6.198468 -90.256827)
			(xy 6.286761 -90.285366) (xy 6.329426 -90.303604) (xy 6.339368 -90.30741) (xy 6.360632 -90.30741)
			(xy 6.370574 -90.303604) (xy 6.413236 -90.28536) (xy 6.501529 -90.256816) (xy 6.592314 -90.237622)
			(xy 6.684604 -90.227989) (xy 6.731 -90.227404) (xy 6.772103 -90.227862) (xy 6.853959 -90.235447)
			(xy 6.934766 -90.250553) (xy 7.013834 -90.27305) (xy 7.090489 -90.302746) (xy 7.164077 -90.339389)
			(xy 7.233971 -90.382665) (xy 7.299573 -90.432205) (xy 7.360324 -90.487587) (xy 7.415706 -90.548339)
			(xy 7.465246 -90.613941) (xy 7.508522 -90.683834) (xy 7.545165 -90.757423) (xy 7.574861 -90.834078)
			(xy 7.597358 -90.913146) (xy 7.612463 -90.993953) (xy 7.620048 -91.075809) (xy 7.620508 -91.116912)
			(xy 7.619929 -91.163308) (xy 7.610283 -91.255596) (xy 7.591086 -91.34638) (xy 7.562546 -91.434673)
			(xy 7.544308 -91.477338) (xy 7.540495 -91.487278) (xy 7.5405 -91.508544) (xy 7.544308 -91.518486)
			(xy 7.562557 -91.561147) (xy 7.5911 -91.64944) (xy 7.610292 -91.740225) (xy 7.619924 -91.832516)
			(xy 7.620508 -91.878912) (xy 7.620045 -91.920015) (xy 7.612459 -92.001869) (xy 7.597353 -92.082675)
			(xy 7.574855 -92.161742) (xy 7.545158 -92.238396) (xy 7.508516 -92.311983) (xy 7.465239 -92.381875)
			(xy 7.415699 -92.447476) (xy 7.360317 -92.508226) (xy 7.299566 -92.563607) (xy 7.233965 -92.613146)
			(xy 7.164072 -92.656421) (xy 7.090485 -92.693063) (xy 7.01383 -92.722759) (xy 6.934763 -92.745255)
			(xy 6.853957 -92.76036) (xy 6.772103 -92.767945) (xy 6.731 -92.76842) (xy 6.684604 -92.767836) (xy 6.592316 -92.758191)
			(xy 6.501532 -92.738996) (xy 6.413239 -92.710458) (xy 6.370574 -92.69222) (xy 6.360632 -92.688414)
			(xy 6.339368 -92.688414) (xy 6.329426 -92.69222) (xy 6.286764 -92.710466) (xy 6.198472 -92.739009)
			(xy 6.107686 -92.758202) (xy 6.015396 -92.767835) (xy 5.969 -92.76842) (xy 5.922604 -92.767836) (xy 5.830316 -92.758191)
			(xy 5.739532 -92.738996) (xy 5.651239 -92.710458) (xy 5.608574 -92.69222) (xy 5.598632 -92.688414)
			(xy 5.577368 -92.688414) (xy 5.567426 -92.69222) (xy 5.524764 -92.710466) (xy 5.436472 -92.739009)
			(xy 5.345686 -92.758202) (xy 5.253396 -92.767835) (xy 5.207 -92.76842) (xy 5.160604 -92.767836) (xy 5.068316 -92.758191)
			(xy 4.977532 -92.738996) (xy 4.889239 -92.710458) (xy 4.846574 -92.69222) (xy 4.836632 -92.688414)
			(xy 4.815368 -92.688414) (xy 4.805426 -92.69222) (xy 4.762764 -92.710466) (xy 4.674472 -92.739009)
			(xy 4.583686 -92.758202) (xy 4.491396 -92.767835) (xy 4.445 -92.76842) (xy 4.403898 -92.767943) (xy 4.322043 -92.760358)
			(xy 4.241238 -92.745253) (xy 4.162171 -92.722757) (xy 4.085518 -92.693061) (xy 4.011931 -92.656419)
			(xy 3.942039 -92.613144) (xy 3.876438 -92.563605) (xy 3.815688 -92.508224) (xy 3.760307 -92.447474)
			(xy 3.710767 -92.381873) (xy 3.667492 -92.311981) (xy 3.63085 -92.238394) (xy 3.601154 -92.16174)
			(xy 3.578657 -92.082674) (xy 3.563552 -92.001869) (xy 3.555967 -91.920014) (xy 3.555492 -91.878912)
			(xy 0.509016 -91.878912) (xy 0.509016 -93.979238) (xy 12.572492 -93.979238) (xy 12.572861 -93.940953)
			(xy 12.579406 -93.864664) (xy 12.592493 -93.789222) (xy 12.612024 -93.715186) (xy 12.624562 -93.67901)
			(xy 12.627193 -93.670568) (xy 12.627206 -93.652902) (xy 12.624562 -93.644466) (xy 12.612047 -93.608284)
			(xy 12.592537 -93.534246) (xy 12.579454 -93.458806) (xy 12.572895 -93.382521) (xy 12.572492 -93.344238)
			(xy 12.572861 -93.305953) (xy 12.579406 -93.229664) (xy 12.592493 -93.154222) (xy 12.612024 -93.080186)
			(xy 12.624562 -93.04401) (xy 12.627193 -93.035568) (xy 12.627206 -93.017902) (xy 12.624562 -93.009466)
			(xy 12.612047 -92.973284) (xy 12.592537 -92.899246) (xy 12.579454 -92.823806) (xy 12.572895 -92.747521)
			(xy 12.572492 -92.709238) (xy 12.572996 -92.66689) (xy 12.581047 -92.582576) (xy 12.597076 -92.49941)
			(xy 12.620937 -92.418143) (xy 12.652416 -92.339513) (xy 12.691227 -92.264232) (xy 12.737017 -92.19298)
			(xy 12.789373 -92.126404) (xy 12.847821 -92.065106) (xy 12.911831 -92.009641) (xy 12.980823 -91.960512)
			(xy 13.054173 -91.918163) (xy 13.131216 -91.882979) (xy 13.211255 -91.855277) (xy 13.293564 -91.835309)
			(xy 13.377399 -91.823256) (xy 13.462 -91.819226) (xy 13.546601 -91.823256) (xy 13.630436 -91.835309)
			(xy 13.712745 -91.855277) (xy 13.792784 -91.882979) (xy 13.869827 -91.918163) (xy 13.943177 -91.960512)
			(xy 14.012169 -92.009641) (xy 14.076179 -92.065106) (xy 14.134627 -92.126404) (xy 14.186983 -92.19298)
			(xy 14.232773 -92.264232) (xy 14.271584 -92.339513) (xy 14.303063 -92.418143) (xy 14.326924 -92.49941)
			(xy 14.342953 -92.582576) (xy 14.351004 -92.66689) (xy 14.351508 -92.709238) (xy 14.351132 -92.747523)
			(xy 14.344589 -92.823811) (xy 14.331504 -92.899254) (xy 14.311975 -92.97329) (xy 14.299438 -93.009466)
			(xy 14.296768 -93.017898) (xy 14.296781 -93.035573) (xy 14.299438 -93.04401) (xy 14.311946 -93.080194)
			(xy 14.331458 -93.154232) (xy 14.344543 -93.229671) (xy 14.351104 -93.305955) (xy 14.351508 -93.344238)
			(xy 14.351132 -93.382523) (xy 14.344589 -93.458811) (xy 14.331504 -93.534254) (xy 14.311975 -93.60829)
			(xy 14.299438 -93.644466) (xy 14.296768 -93.652898) (xy 14.296781 -93.670573) (xy 14.299438 -93.67901)
			(xy 14.311946 -93.715194) (xy 14.331458 -93.789232) (xy 14.344543 -93.864671) (xy 14.351104 -93.940955)
			(xy 14.351508 -93.979238) (xy 14.351004 -94.021586) (xy 14.347699 -94.0562) (xy 37.185092 -94.0562)
			(xy 37.185578 -94.013532) (xy 37.193723 -93.928587) (xy 37.209955 -93.84481) (xy 37.234128 -93.76297)
			(xy 37.249608 -93.723206) (xy 37.252896 -93.713962) (xy 37.252881 -93.694357) (xy 37.249608 -93.685106)
			(xy 37.234119 -93.645345) (xy 37.209928 -93.563509) (xy 37.193695 -93.47973) (xy 37.185569 -93.394781)
			(xy 37.185092 -93.352112) (xy 37.185526 -93.311974) (xy 37.19274 -93.232022) (xy 37.207128 -93.153046)
			(xy 37.228573 -93.075687) (xy 37.256901 -93.000575) (xy 37.273992 -92.964254) (xy 37.278542 -92.95367)
			(xy 37.278524 -92.930651) (xy 37.273992 -92.920058) (xy 37.256885 -92.883745) (xy 37.228557 -92.808631)
			(xy 37.207114 -92.731271) (xy 37.19273 -92.652292) (xy 37.185523 -92.572339) (xy 37.185092 -92.5322)
			(xy 37.185596 -92.489852) (xy 37.193647 -92.405538) (xy 37.209676 -92.322372) (xy 37.233537 -92.241105)
			(xy 37.265016 -92.162475) (xy 37.303827 -92.087194) (xy 37.349617 -92.015942) (xy 37.401973 -91.949366)
			(xy 37.460421 -91.888068) (xy 37.524431 -91.832603) (xy 37.593423 -91.783474) (xy 37.666773 -91.741125)
			(xy 37.743816 -91.705941) (xy 37.823855 -91.678239) (xy 37.906164 -91.658271) (xy 37.989999 -91.646218)
			(xy 38.0746 -91.642188) (xy 38.159201 -91.646218) (xy 38.243036 -91.658271) (xy 38.325345 -91.678239)
			(xy 38.405384 -91.705941) (xy 38.482427 -91.741125) (xy 38.555777 -91.783474) (xy 38.624769 -91.832603)
			(xy 38.688779 -91.888068) (xy 38.747227 -91.949366) (xy 38.799583 -92.015942) (xy 38.803258 -92.02166)
			(xy 44.032424 -92.02166) (xy 44.032804 -91.983375) (xy 44.039346 -91.907087) (xy 44.05243 -91.831644)
			(xy 44.071958 -91.757608) (xy 44.084494 -91.721432) (xy 44.087163 -91.713) (xy 44.08715 -91.695325)
			(xy 44.084494 -91.686888) (xy 44.071987 -91.650704) (xy 44.052474 -91.576666) (xy 44.039389 -91.501227)
			(xy 44.032828 -91.424943) (xy 44.032424 -91.38666) (xy 44.032829 -91.345556) (xy 44.040417 -91.263699)
			(xy 44.055527 -91.182891) (xy 44.078027 -91.103822) (xy 44.107728 -91.027166) (xy 44.144374 -90.953578)
			(xy 44.187654 -90.883685) (xy 44.237198 -90.818084) (xy 44.292584 -90.757333) (xy 44.353339 -90.701952)
			(xy 44.418945 -90.652413) (xy 44.488841 -90.609139) (xy 44.562432 -90.572499) (xy 44.63909 -90.542805)
			(xy 44.718161 -90.52031) (xy 44.79897 -90.505207) (xy 44.880828 -90.497625) (xy 44.921932 -90.497152)
			(xy 44.968327 -90.497754) (xy 45.060615 -90.507393) (xy 45.151399 -90.526583) (xy 45.239693 -90.555116)
			(xy 45.282358 -90.573352) (xy 45.2923 -90.577158) (xy 45.313564 -90.577158) (xy 45.323506 -90.573352)
			(xy 45.366163 -90.555094) (xy 45.454457 -90.526554) (xy 45.545244 -90.507365) (xy 45.637536 -90.497735)
			(xy 45.683932 -90.497152) (xy 45.730327 -90.497754) (xy 45.822615 -90.507393) (xy 45.913399 -90.526583)
			(xy 46.001693 -90.555116) (xy 46.044358 -90.573352) (xy 46.0543 -90.577158) (xy 46.075564 -90.577158)
			(xy 46.085506 -90.573352) (xy 46.128163 -90.555094) (xy 46.216457 -90.526554) (xy 46.307244 -90.507365)
			(xy 46.399536 -90.497735) (xy 46.445932 -90.497152) (xy 46.492327 -90.497754) (xy 46.584615 -90.507393)
			(xy 46.675399 -90.526583) (xy 46.763693 -90.555116) (xy 46.806358 -90.573352) (xy 46.8163 -90.577158)
			(xy 46.837564 -90.577158) (xy 46.847506 -90.573352) (xy 46.890163 -90.555094) (xy 46.978457 -90.526554)
			(xy 47.069244 -90.507365) (xy 47.161536 -90.497735) (xy 47.207932 -90.497152) (xy 47.249034 -90.497636)
			(xy 47.330887 -90.505223) (xy 47.41169 -90.52033) (xy 47.490755 -90.542828) (xy 47.567408 -90.572525)
			(xy 47.640993 -90.609167) (xy 47.710884 -90.652442) (xy 47.776483 -90.701981) (xy 47.837233 -90.757362)
			(xy 47.892614 -90.81811) (xy 47.942153 -90.88371) (xy 47.985429 -90.9536) (xy 48.022072 -91.027185)
			(xy 48.051769 -91.103837) (xy 48.074268 -91.182902) (xy 48.089375 -91.263705) (xy 48.096964 -91.345558)
			(xy 48.09744 -91.38666) (xy 48.097068 -91.424945) (xy 48.090524 -91.501234) (xy 48.077438 -91.576676)
			(xy 48.057907 -91.650712) (xy 48.04537 -91.686888) (xy 48.042738 -91.69533) (xy 48.042725 -91.712996)
			(xy 48.04537 -91.721432) (xy 48.057886 -91.757614) (xy 48.077395 -91.831652) (xy 48.090478 -91.907092)
			(xy 48.097037 -91.983377) (xy 48.09744 -92.02166) (xy 48.09691 -92.062762) (xy 48.089329 -92.144614)
			(xy 48.074227 -92.225418) (xy 48.051735 -92.304484) (xy 48.022043 -92.381138) (xy 47.985405 -92.454725)
			(xy 47.942134 -92.524617) (xy 47.892598 -92.590218) (xy 47.83722 -92.65097) (xy 47.776474 -92.706352)
			(xy 47.710876 -92.755893) (xy 47.640988 -92.79917) (xy 47.567404 -92.835814) (xy 47.490753 -92.865512)
			(xy 47.411689 -92.888011) (xy 47.330886 -92.903119) (xy 47.249034 -92.910706) (xy 47.207932 -92.911168)
			(xy 47.161537 -92.910577) (xy 47.069248 -92.900935) (xy 46.978465 -92.881741) (xy 46.890171 -92.853205)
			(xy 46.847506 -92.834968) (xy 46.837564 -92.831162) (xy 46.8163 -92.831162) (xy 46.806358 -92.834968)
			(xy 46.76369 -92.8532) (xy 46.6754 -92.881748) (xy 46.584617 -92.900945) (xy 46.492328 -92.910581)
			(xy 46.445932 -92.911168) (xy 46.399537 -92.910577) (xy 46.307248 -92.900935) (xy 46.216465 -92.881741)
			(xy 46.128171 -92.853205) (xy 46.085506 -92.834968) (xy 46.075564 -92.831162) (xy 46.0543 -92.831162)
			(xy 46.044358 -92.834968) (xy 46.00169 -92.8532) (xy 45.9134 -92.881748) (xy 45.822617 -92.900945)
			(xy 45.730328 -92.910581) (xy 45.683932 -92.911168) (xy 45.637537 -92.910577) (xy 45.545248 -92.900935)
			(xy 45.454465 -92.881741) (xy 45.366171 -92.853205) (xy 45.323506 -92.834968) (xy 45.313564 -92.831162)
			(xy 45.2923 -92.831162) (xy 45.282358 -92.834968) (xy 45.23969 -92.8532) (xy 45.1514 -92.881748)
			(xy 45.060617 -92.900945) (xy 44.968328 -92.910581) (xy 44.921932 -92.911168) (xy 44.880828 -92.910717)
			(xy 44.798971 -92.903135) (xy 44.718163 -92.888031) (xy 44.639093 -92.865536) (xy 44.562436 -92.83584)
			(xy 44.488846 -92.799198) (xy 44.418952 -92.755922) (xy 44.353349 -92.706381) (xy 44.292597 -92.650998)
			(xy 44.237214 -92.590245) (xy 44.187674 -92.524642) (xy 44.144398 -92.454747) (xy 44.107757 -92.381157)
			(xy 44.078062 -92.3045) (xy 44.055567 -92.225429) (xy 44.040464 -92.144621) (xy 44.032882 -92.062764)
			(xy 44.032424 -92.02166) (xy 38.803258 -92.02166) (xy 38.845373 -92.087194) (xy 38.884184 -92.162475)
			(xy 38.915663 -92.241105) (xy 38.939524 -92.322372) (xy 38.955553 -92.405538) (xy 38.963604 -92.489852)
			(xy 38.964108 -92.5322) (xy 38.963678 -92.572338) (xy 38.956464 -92.65229) (xy 38.942074 -92.731267)
			(xy 38.920628 -92.808626) (xy 38.892299 -92.883738) (xy 38.875208 -92.920058) (xy 38.870715 -92.93066)
			(xy 38.870697 -92.953661) (xy 38.875208 -92.964254) (xy 38.89232 -93.000565) (xy 38.920646 -93.075679)
			(xy 38.942088 -93.15304) (xy 38.956471 -93.232019) (xy 38.963678 -93.311973) (xy 38.964108 -93.352112)
			(xy 38.963625 -93.39478) (xy 38.95548 -93.479726) (xy 38.939246 -93.563503) (xy 38.915073 -93.645342)
			(xy 38.899592 -93.685106) (xy 38.896352 -93.694364) (xy 38.896337 -93.713956) (xy 38.899592 -93.723206)
			(xy 38.915085 -93.762966) (xy 38.939275 -93.844802) (xy 38.955507 -93.928582) (xy 38.963632 -94.013531)
			(xy 38.964108 -94.0562) (xy 38.963604 -94.098548) (xy 38.955553 -94.182862) (xy 38.939524 -94.266028)
			(xy 38.915663 -94.347295) (xy 38.884184 -94.425925) (xy 38.845373 -94.501206) (xy 38.799583 -94.572458)
			(xy 38.747227 -94.639034) (xy 38.688779 -94.700332) (xy 38.624769 -94.755797) (xy 38.555777 -94.804926)
			(xy 38.482427 -94.847275) (xy 38.405384 -94.882459) (xy 38.325345 -94.910161) (xy 38.243036 -94.930129)
			(xy 38.159201 -94.942182) (xy 38.0746 -94.946213) (xy 37.989999 -94.942182) (xy 37.906164 -94.930129)
			(xy 37.823855 -94.910161) (xy 37.743816 -94.882459) (xy 37.666773 -94.847275) (xy 37.593423 -94.804926)
			(xy 37.524431 -94.755797) (xy 37.460421 -94.700332) (xy 37.401973 -94.639034) (xy 37.349617 -94.572458)
			(xy 37.303827 -94.501206) (xy 37.265016 -94.425925) (xy 37.233537 -94.347295) (xy 37.209676 -94.266028)
			(xy 37.193647 -94.182862) (xy 37.185596 -94.098548) (xy 37.185092 -94.0562) (xy 14.347699 -94.0562)
			(xy 14.342953 -94.1059) (xy 14.326924 -94.189066) (xy 14.303063 -94.270333) (xy 14.271584 -94.348963)
			(xy 14.232773 -94.424244) (xy 14.186983 -94.495496) (xy 14.134627 -94.562072) (xy 14.076179 -94.62337)
			(xy 14.012169 -94.678835) (xy 13.943177 -94.727964) (xy 13.869827 -94.770313) (xy 13.792784 -94.805497)
			(xy 13.712745 -94.833199) (xy 13.630436 -94.853167) (xy 13.546601 -94.86522) (xy 13.462 -94.869251)
			(xy 13.377399 -94.86522) (xy 13.293564 -94.853167) (xy 13.211255 -94.833199) (xy 13.131216 -94.805497)
			(xy 13.054173 -94.770313) (xy 12.980823 -94.727964) (xy 12.911831 -94.678835) (xy 12.847821 -94.62337)
			(xy 12.789373 -94.562072) (xy 12.737017 -94.495496) (xy 12.691227 -94.424244) (xy 12.652416 -94.348963)
			(xy 12.620937 -94.270333) (xy 12.597076 -94.189066) (xy 12.581047 -94.1059) (xy 12.572996 -94.021586)
			(xy 12.572492 -93.979238) (xy 0.509016 -93.979238) (xy 0.509016 -98.975361) (xy 26.288742 -98.975361)
			(xy 26.288742 -98.890639) (xy 26.296795 -98.806302) (xy 26.312829 -98.723112) (xy 26.336697 -98.641822)
			(xy 26.368185 -98.56317) (xy 26.407007 -98.487867) (xy 26.45281 -98.416595) (xy 26.505181 -98.349999)
			(xy 26.563646 -98.288684) (xy 26.627674 -98.233203) (xy 26.696686 -98.18406) (xy 26.770056 -98.1417)
			(xy 26.847121 -98.106505) (xy 26.927183 -98.078796) (xy 27.009516 -98.058822) (xy 27.093375 -98.046765)
			(xy 27.178 -98.042734) (xy 27.262625 -98.046765) (xy 27.346484 -98.058822) (xy 27.428817 -98.078796)
			(xy 27.508879 -98.106505) (xy 27.585944 -98.1417) (xy 27.659314 -98.18406) (xy 27.728326 -98.233203)
			(xy 27.792354 -98.288684) (xy 27.850819 -98.349999) (xy 27.90319 -98.416595) (xy 27.948993 -98.487867)
			(xy 27.987815 -98.56317) (xy 28.019303 -98.641822) (xy 28.043171 -98.723112) (xy 28.059205 -98.806302)
			(xy 28.067258 -98.890639) (xy 28.067762 -98.933) (xy 28.067258 -98.975361) (xy 28.059205 -99.059698)
			(xy 28.043171 -99.142888) (xy 28.019303 -99.224178) (xy 27.987815 -99.30283) (xy 27.948993 -99.378133)
			(xy 27.90319 -99.449405) (xy 27.850819 -99.516001) (xy 27.792354 -99.577316) (xy 27.728326 -99.632797)
			(xy 27.659314 -99.68194) (xy 27.585944 -99.7243) (xy 27.508879 -99.759495) (xy 27.428817 -99.787204)
			(xy 27.346484 -99.807178) (xy 27.262625 -99.819235) (xy 27.178 -99.823267) (xy 27.093375 -99.819235)
			(xy 27.009516 -99.807178) (xy 26.927183 -99.787204) (xy 26.847121 -99.759495) (xy 26.770056 -99.7243)
			(xy 26.696686 -99.68194) (xy 26.627674 -99.632797) (xy 26.563646 -99.577316) (xy 26.505181 -99.516001)
			(xy 26.45281 -99.449405) (xy 26.407007 -99.378133) (xy 26.368185 -99.30283) (xy 26.336697 -99.224178)
			(xy 26.312829 -99.142888) (xy 26.296795 -99.059698) (xy 26.288742 -98.975361) (xy 0.509016 -98.975361)
			(xy 0.509016 -101.134361) (xy 20.065742 -101.134361) (xy 20.065742 -101.049639) (xy 20.073795 -100.965302)
			(xy 20.089829 -100.882112) (xy 20.113697 -100.800822) (xy 20.145185 -100.72217) (xy 20.184007 -100.646867)
			(xy 20.22981 -100.575595) (xy 20.282181 -100.508999) (xy 20.340646 -100.447684) (xy 20.404674 -100.392203)
			(xy 20.473686 -100.34306) (xy 20.547056 -100.3007) (xy 20.624121 -100.265505) (xy 20.704183 -100.237796)
			(xy 20.786516 -100.217822) (xy 20.870375 -100.205765) (xy 20.955 -100.201734) (xy 21.039625 -100.205765)
			(xy 21.123484 -100.217822) (xy 21.205817 -100.237796) (xy 21.285879 -100.265505) (xy 21.362944 -100.3007)
			(xy 21.436314 -100.34306) (xy 21.505326 -100.392203) (xy 21.569354 -100.447684) (xy 21.627819 -100.508999)
			(xy 21.68019 -100.575595) (xy 21.725993 -100.646867) (xy 21.764815 -100.72217) (xy 21.796303 -100.800822)
			(xy 21.807219 -100.838) (xy 28.702 -100.838) (xy 28.702474 -100.796921) (xy 28.710055 -100.715113)
			(xy 28.725151 -100.634354) (xy 28.747635 -100.555332) (xy 28.777314 -100.478722) (xy 28.813935 -100.405177)
			(xy 28.857185 -100.335325) (xy 28.906697 -100.269762) (xy 28.962046 -100.209046) (xy 29.022762 -100.153697)
			(xy 29.088325 -100.104185) (xy 29.158177 -100.060935) (xy 29.231722 -100.024314) (xy 29.308332 -99.994635)
			(xy 29.387354 -99.972151) (xy 29.468113 -99.957055) (xy 29.549921 -99.949474) (xy 29.591 -99.949)
			(xy 29.632983 -99.949463) (xy 29.716576 -99.957372) (xy 29.79905 -99.973128) (xy 29.879672 -99.996591)
			(xy 29.957721 -100.027553) (xy 30.032503 -100.065736) (xy 30.103351 -100.110801) (xy 30.169634 -100.162346)
			(xy 30.23076 -100.219912) (xy 30.286186 -100.282986) (xy 30.335417 -100.351005) (xy 30.378014 -100.423364)
			(xy 30.413598 -100.499417) (xy 30.428184 -100.538788) (xy 30.430456 -100.544618) (xy 30.437389 -100.555027)
			(xy 30.4419 -100.559362) (xy 30.472208 -100.587402) (xy 30.52802 -100.64826) (xy 30.577954 -100.714026)
			(xy 30.621581 -100.784135) (xy 30.658526 -100.857984) (xy 30.68847 -100.934938) (xy 30.711156 -101.014335)
			(xy 30.72639 -101.095493) (xy 30.73404 -101.177713) (xy 30.734508 -101.219) (xy 30.734033 -101.260102)
			(xy 30.726448 -101.341957) (xy 30.711343 -101.422762) (xy 30.688847 -101.501829) (xy 30.659151 -101.578483)
			(xy 30.622509 -101.65207) (xy 30.579234 -101.721962) (xy 30.529694 -101.787563) (xy 30.474313 -101.848313)
			(xy 30.413563 -101.903694) (xy 30.347962 -101.953234) (xy 30.27807 -101.996509) (xy 30.204483 -102.033151)
			(xy 30.127829 -102.062847) (xy 30.048762 -102.085343) (xy 29.967957 -102.100448) (xy 29.886102 -102.108033)
			(xy 29.845 -102.108508) (xy 29.802903 -102.108048) (xy 29.719084 -102.100101) (xy 29.636391 -102.084268)
			(xy 29.555565 -102.060692) (xy 29.477328 -102.029583) (xy 29.402381 -101.99122) (xy 29.331395 -101.945945)
			(xy 29.265005 -101.894166) (xy 29.203806 -101.836344) (xy 29.148344 -101.772997) (xy 29.099118 -101.704693)
			(xy 29.056566 -101.632042) (xy 29.02107 -101.555695) (xy 29.006546 -101.51618) (xy 29.004259 -101.51036)
			(xy 28.997316 -101.499963) (xy 28.99283 -101.495606) (xy 28.962727 -101.467571) (xy 28.907237 -101.406838)
			(xy 28.857597 -101.341238) (xy 28.814231 -101.271331) (xy 28.777511 -101.197716) (xy 28.74775 -101.121022)
			(xy 28.725204 -101.041907) (xy 28.710065 -100.961046) (xy 28.702463 -100.879133) (xy 28.702 -100.838)
			(xy 21.807219 -100.838) (xy 21.820171 -100.882112) (xy 21.836205 -100.965302) (xy 21.844258 -101.049639)
			(xy 21.844762 -101.092) (xy 21.844258 -101.134361) (xy 21.836205 -101.218698) (xy 21.820171 -101.301888)
			(xy 21.796303 -101.383178) (xy 21.764815 -101.46183) (xy 21.725993 -101.537133) (xy 21.68019 -101.608405)
			(xy 21.627819 -101.675001) (xy 21.569354 -101.736316) (xy 21.505326 -101.791797) (xy 21.436314 -101.84094)
			(xy 21.362944 -101.8833) (xy 21.285879 -101.918495) (xy 21.205817 -101.946204) (xy 21.123484 -101.966178)
			(xy 21.039625 -101.978235) (xy 20.955 -101.982267) (xy 20.870375 -101.978235) (xy 20.786516 -101.966178)
			(xy 20.704183 -101.946204) (xy 20.624121 -101.918495) (xy 20.547056 -101.8833) (xy 20.473686 -101.84094)
			(xy 20.404674 -101.791797) (xy 20.340646 -101.736316) (xy 20.282181 -101.675001) (xy 20.22981 -101.608405)
			(xy 20.184007 -101.537133) (xy 20.145185 -101.46183) (xy 20.113697 -101.383178) (xy 20.089829 -101.301888)
			(xy 20.073795 -101.218698) (xy 20.065742 -101.134361) (xy 0.509016 -101.134361) (xy 0.509016 -102.810056)
			(xy 6.441451 -102.810056) (xy 6.445429 -102.710063) (xy 6.457339 -102.610703) (xy 6.477106 -102.512602)
			(xy 6.504605 -102.416383) (xy 6.539661 -102.322652) (xy 6.582053 -102.232003) (xy 6.631514 -102.145009)
			(xy 6.68773 -102.062219) (xy 6.750346 -101.984157) (xy 6.818965 -101.911317) (xy 6.893156 -101.844159)
			(xy 6.972447 -101.783107) (xy 7.056338 -101.728549) (xy 7.144299 -101.680828) (xy 7.235773 -101.640246)
			(xy 7.330182 -101.60706) (xy 7.426929 -101.58148) (xy 7.525403 -101.563667) (xy 7.624981 -101.553735)
			(xy 7.725033 -101.551745) (xy 7.824927 -101.557711) (xy 7.924031 -101.571595) (xy 8.021719 -101.593308)
			(xy 8.117373 -101.622714) (xy 8.210388 -101.659627) (xy 8.300176 -101.703813) (xy 8.38617 -101.754994)
			(xy 8.467826 -101.812844) (xy 8.544627 -101.877) (xy 8.616089 -101.947054) (xy 8.681759 -102.022565)
			(xy 8.741221 -102.103055) (xy 8.794101 -102.188014) (xy 8.840064 -102.276906) (xy 8.878819 -102.369169)
			(xy 8.910121 -102.464219) (xy 8.933773 -102.561456) (xy 8.949624 -102.660265) (xy 8.957574 -102.76002)
			(xy 8.958072 -102.810056) (xy 8.957574 -102.860092) (xy 8.949624 -102.959847) (xy 8.933773 -103.058656)
			(xy 8.910121 -103.155893) (xy 8.878819 -103.250943) (xy 8.874033 -103.262336) (xy 18.801076 -103.262336)
			(xy 18.801076 -103.177688) (xy 18.809122 -103.093422) (xy 18.825142 -103.010303) (xy 18.84899 -102.929084)
			(xy 18.880451 -102.850499) (xy 18.919239 -102.77526) (xy 18.965003 -102.704049) (xy 19.01733 -102.637511)
			(xy 19.075744 -102.576248) (xy 19.139717 -102.520815) (xy 19.20867 -102.471714) (xy 19.281978 -102.429389)
			(xy 19.358977 -102.394225) (xy 19.43897 -102.366539) (xy 19.521232 -102.346582) (xy 19.605019 -102.334536)
			(xy 19.689572 -102.330508) (xy 19.774125 -102.334536) (xy 19.857912 -102.346582) (xy 19.940174 -102.366539)
			(xy 20.020167 -102.394225) (xy 20.097166 -102.429389) (xy 20.170474 -102.471714) (xy 20.239427 -102.520815)
			(xy 20.3034 -102.576248) (xy 20.361814 -102.637511) (xy 20.414141 -102.704049) (xy 20.459905 -102.77526)
			(xy 20.498693 -102.850499) (xy 20.530154 -102.929084) (xy 20.554002 -103.010303) (xy 20.570022 -103.093422)
			(xy 20.578068 -103.177688) (xy 20.578572 -103.220012) (xy 20.578068 -103.262336) (xy 20.570022 -103.346602)
			(xy 20.554002 -103.429721) (xy 20.530154 -103.51094) (xy 20.498693 -103.589525) (xy 20.459905 -103.664764)
			(xy 20.414141 -103.735975) (xy 20.361814 -103.802513) (xy 20.3034 -103.863776) (xy 20.239427 -103.919209)
			(xy 20.170474 -103.96831) (xy 20.097166 -104.010635) (xy 20.020167 -104.045799) (xy 19.940174 -104.073485)
			(xy 19.857912 -104.093442) (xy 19.774125 -104.105488) (xy 19.689572 -104.109516) (xy 19.605019 -104.105488)
			(xy 19.521232 -104.093442) (xy 19.43897 -104.073485) (xy 19.358977 -104.045799) (xy 19.281978 -104.010635)
			(xy 19.20867 -103.96831) (xy 19.139717 -103.919209) (xy 19.075744 -103.863776) (xy 19.01733 -103.802513)
			(xy 18.965003 -103.735975) (xy 18.919239 -103.664764) (xy 18.880451 -103.589525) (xy 18.84899 -103.51094)
			(xy 18.825142 -103.429721) (xy 18.809122 -103.346602) (xy 18.801076 -103.262336) (xy 8.874033 -103.262336)
			(xy 8.840064 -103.343206) (xy 8.794101 -103.432098) (xy 8.741221 -103.517057) (xy 8.681759 -103.597547)
			(xy 8.616089 -103.673058) (xy 8.544627 -103.743112) (xy 8.467826 -103.807268) (xy 8.38617 -103.865118)
			(xy 8.300176 -103.916299) (xy 8.210388 -103.960485) (xy 8.117373 -103.997398) (xy 8.021719 -104.026804)
			(xy 7.924031 -104.048517) (xy 7.824927 -104.062401) (xy 7.725033 -104.068367) (xy 7.624981 -104.066377)
			(xy 7.525403 -104.056445) (xy 7.426929 -104.038632) (xy 7.330182 -104.013052) (xy 7.235773 -103.979866)
			(xy 7.144299 -103.939284) (xy 7.056338 -103.891563) (xy 6.972447 -103.837005) (xy 6.893156 -103.775953)
			(xy 6.818965 -103.708795) (xy 6.750346 -103.635955) (xy 6.68773 -103.557893) (xy 6.631514 -103.475103)
			(xy 6.582053 -103.388109) (xy 6.539661 -103.29746) (xy 6.504605 -103.203729) (xy 6.477106 -103.10751)
			(xy 6.457339 -103.009409) (xy 6.445429 -102.910049) (xy 6.441451 -102.810056) (xy 0.509016 -102.810056)
			(xy 0.509016 -105.452361) (xy 19.938742 -105.452361) (xy 19.938742 -105.367639) (xy 19.946795 -105.283302)
			(xy 19.962829 -105.200112) (xy 19.986697 -105.118822) (xy 20.018185 -105.04017) (xy 20.057007 -104.964867)
			(xy 20.10281 -104.893595) (xy 20.155181 -104.826999) (xy 20.213646 -104.765684) (xy 20.277674 -104.710203)
			(xy 20.346686 -104.66106) (xy 20.420056 -104.6187) (xy 20.497121 -104.583505) (xy 20.577183 -104.555796)
			(xy 20.659516 -104.535822) (xy 20.743375 -104.523765) (xy 20.828 -104.519734) (xy 20.912625 -104.523765)
			(xy 20.996484 -104.535822) (xy 21.078817 -104.555796) (xy 21.158879 -104.583505) (xy 21.235944 -104.6187)
			(xy 21.309314 -104.66106) (xy 21.378326 -104.710203) (xy 21.442354 -104.765684) (xy 21.500819 -104.826999)
			(xy 21.55319 -104.893595) (xy 21.598993 -104.964867) (xy 21.637815 -105.04017) (xy 21.669303 -105.118822)
			(xy 21.693171 -105.200112) (xy 21.709205 -105.283302) (xy 21.717258 -105.367639) (xy 21.717762 -105.41)
			(xy 21.717258 -105.452361) (xy 21.709205 -105.536698) (xy 21.693171 -105.619888) (xy 21.669303 -105.701178)
			(xy 21.637815 -105.77983) (xy 21.598993 -105.855133) (xy 21.55319 -105.926405) (xy 21.500819 -105.993001)
			(xy 21.442354 -106.054316) (xy 21.378326 -106.109797) (xy 21.309314 -106.15894) (xy 21.235944 -106.2013)
			(xy 21.158879 -106.236495) (xy 21.078817 -106.264204) (xy 20.996484 -106.284178) (xy 20.912625 -106.296235)
			(xy 20.828 -106.300267) (xy 20.743375 -106.296235) (xy 20.659516 -106.284178) (xy 20.577183 -106.264204)
			(xy 20.497121 -106.236495) (xy 20.420056 -106.2013) (xy 20.346686 -106.15894) (xy 20.277674 -106.109797)
			(xy 20.213646 -106.054316) (xy 20.155181 -105.993001) (xy 20.10281 -105.926405) (xy 20.057007 -105.855133)
			(xy 20.018185 -105.77983) (xy 19.986697 -105.701178) (xy 19.962829 -105.619888) (xy 19.946795 -105.536698)
			(xy 19.938742 -105.452361) (xy 0.509016 -105.452361) (xy 0.509016 -108.500361) (xy 17.144742 -108.500361)
			(xy 17.144742 -108.415639) (xy 17.152795 -108.331302) (xy 17.168829 -108.248112) (xy 17.192697 -108.166822)
			(xy 17.224185 -108.08817) (xy 17.263007 -108.012867) (xy 17.30881 -107.941595) (xy 17.361181 -107.874999)
			(xy 17.419646 -107.813684) (xy 17.483674 -107.758203) (xy 17.552686 -107.70906) (xy 17.626056 -107.6667)
			(xy 17.703121 -107.631505) (xy 17.783183 -107.603796) (xy 17.865516 -107.583822) (xy 17.949375 -107.571765)
			(xy 18.034 -107.567734) (xy 18.118625 -107.571765) (xy 18.202484 -107.583822) (xy 18.284817 -107.603796)
			(xy 18.364879 -107.631505) (xy 18.441944 -107.6667) (xy 18.515314 -107.70906) (xy 18.584326 -107.758203)
			(xy 18.648354 -107.813684) (xy 18.706819 -107.874999) (xy 18.75919 -107.941595) (xy 18.804993 -108.012867)
			(xy 18.843815 -108.08817) (xy 18.875303 -108.166822) (xy 18.899171 -108.248112) (xy 18.915205 -108.331302)
			(xy 18.923258 -108.415639) (xy 18.923762 -108.458) (xy 18.923258 -108.500361) (xy 18.915205 -108.584698)
			(xy 18.899171 -108.667888) (xy 18.886816 -108.709968) (xy 43.677851 -108.709968) (xy 43.681826 -108.607518)
			(xy 43.693729 -108.505685) (xy 43.713487 -108.40508) (xy 43.740982 -108.306309) (xy 43.776048 -108.209965)
			(xy 43.818474 -108.116629) (xy 43.868006 -108.026861) (xy 43.924346 -107.941201) (xy 43.987154 -107.860165)
			(xy 44.056052 -107.784239) (xy 44.130628 -107.713881) (xy 44.210431 -107.649513) (xy 44.294982 -107.591524)
			(xy 44.383773 -107.54026) (xy 44.476269 -107.496032) (xy 44.571914 -107.459104) (xy 44.670134 -107.429699)
			(xy 44.770337 -107.407994) (xy 44.87192 -107.394118) (xy 44.974274 -107.388157) (xy 45.076781 -107.390145)
			(xy 45.178826 -107.400071) (xy 45.279795 -107.417874) (xy 45.379081 -107.443449) (xy 45.476086 -107.47664)
			(xy 45.570228 -107.517249) (xy 45.66094 -107.565031) (xy 45.747676 -107.619699) (xy 45.829915 -107.680923)
			(xy 45.907162 -107.748337) (xy 45.978953 -107.821534) (xy 46.044856 -107.900074) (xy 46.104475 -107.983484)
			(xy 46.15745 -108.071264) (xy 46.203464 -108.162886) (xy 46.24224 -108.257797) (xy 46.273544 -108.355428)
			(xy 46.297188 -108.455191) (xy 46.31303 -108.556486) (xy 46.320975 -108.658705) (xy 46.321472 -108.709968)
			(xy 46.320975 -108.761231) (xy 46.31303 -108.86345) (xy 46.297188 -108.964745) (xy 46.273544 -109.064508)
			(xy 46.24224 -109.162139) (xy 46.203464 -109.25705) (xy 46.15745 -109.348672) (xy 46.104475 -109.436452)
			(xy 46.044856 -109.519862) (xy 45.978953 -109.598402) (xy 45.907162 -109.671599) (xy 45.829915 -109.739013)
			(xy 45.747676 -109.800237) (xy 45.66094 -109.854905) (xy 45.570228 -109.902687) (xy 45.476086 -109.943296)
			(xy 45.379081 -109.976487) (xy 45.279795 -110.002062) (xy 45.178826 -110.019865) (xy 45.076781 -110.029791)
			(xy 44.974274 -110.031779) (xy 44.87192 -110.025818) (xy 44.770337 -110.011942) (xy 44.670134 -109.990237)
			(xy 44.571914 -109.960832) (xy 44.476269 -109.923904) (xy 44.383773 -109.879676) (xy 44.294982 -109.828412)
			(xy 44.210431 -109.770423) (xy 44.130628 -109.706055) (xy 44.056052 -109.635697) (xy 43.987154 -109.559771)
			(xy 43.924346 -109.478735) (xy 43.868006 -109.393075) (xy 43.818474 -109.303307) (xy 43.776048 -109.209971)
			(xy 43.740982 -109.113627) (xy 43.713487 -109.014856) (xy 43.693729 -108.914251) (xy 43.681826 -108.812418)
			(xy 43.677851 -108.709968) (xy 18.886816 -108.709968) (xy 18.875303 -108.749178) (xy 18.843815 -108.82783)
			(xy 18.804993 -108.903133) (xy 18.75919 -108.974405) (xy 18.706819 -109.041001) (xy 18.648354 -109.102316)
			(xy 18.584326 -109.157797) (xy 18.515314 -109.20694) (xy 18.441944 -109.2493) (xy 18.364879 -109.284495)
			(xy 18.284817 -109.312204) (xy 18.202484 -109.332178) (xy 18.118625 -109.344235) (xy 18.034 -109.348267)
			(xy 17.949375 -109.344235) (xy 17.865516 -109.332178) (xy 17.783183 -109.312204) (xy 17.703121 -109.284495)
			(xy 17.626056 -109.2493) (xy 17.552686 -109.20694) (xy 17.483674 -109.157797) (xy 17.419646 -109.102316)
			(xy 17.361181 -109.041001) (xy 17.30881 -108.974405) (xy 17.263007 -108.903133) (xy 17.224185 -108.82783)
			(xy 17.192697 -108.749178) (xy 17.168829 -108.667888) (xy 17.152795 -108.584698) (xy 17.144742 -108.500361)
			(xy 0.509016 -108.500361) (xy 0.509016 -110.709964) (xy 41.677855 -110.709964) (xy 41.68183 -110.607514)
			(xy 41.693733 -110.505681) (xy 41.713491 -110.405076) (xy 41.740986 -110.306305) (xy 41.776052 -110.209961)
			(xy 41.818478 -110.116625) (xy 41.86801 -110.026857) (xy 41.92435 -109.941197) (xy 41.987158 -109.860161)
			(xy 42.056056 -109.784235) (xy 42.130632 -109.713877) (xy 42.210435 -109.649509) (xy 42.294986 -109.59152)
			(xy 42.383777 -109.540256) (xy 42.476273 -109.496028) (xy 42.571918 -109.4591) (xy 42.670138 -109.429695)
			(xy 42.770341 -109.40799) (xy 42.871924 -109.394114) (xy 42.974278 -109.388153) (xy 43.076785 -109.390141)
			(xy 43.17883 -109.400067) (xy 43.279799 -109.41787) (xy 43.379085 -109.443445) (xy 43.47609 -109.476636)
			(xy 43.570232 -109.517245) (xy 43.660944 -109.565027) (xy 43.74768 -109.619695) (xy 43.829919 -109.680919)
			(xy 43.907166 -109.748333) (xy 43.978957 -109.82153) (xy 44.04486 -109.90007) (xy 44.104479 -109.98348)
			(xy 44.157454 -110.07126) (xy 44.203468 -110.162882) (xy 44.242244 -110.257793) (xy 44.273548 -110.355424)
			(xy 44.297192 -110.455187) (xy 44.313034 -110.556482) (xy 44.320979 -110.658701) (xy 44.321476 -110.709964)
			(xy 44.320979 -110.761227) (xy 44.313034 -110.863446) (xy 44.297192 -110.964741) (xy 44.273548 -111.064504)
			(xy 44.242244 -111.162135) (xy 44.203468 -111.257046) (xy 44.157454 -111.348668) (xy 44.104479 -111.436448)
			(xy 44.04486 -111.519858) (xy 43.978957 -111.598398) (xy 43.907166 -111.671595) (xy 43.829919 -111.739009)
			(xy 43.74768 -111.800233) (xy 43.660944 -111.854901) (xy 43.570232 -111.902683) (xy 43.47609 -111.943292)
			(xy 43.379085 -111.976483) (xy 43.279799 -112.002058) (xy 43.17883 -112.019861) (xy 43.076785 -112.029787)
			(xy 42.974278 -112.031775) (xy 42.871924 -112.025814) (xy 42.770341 -112.011938) (xy 42.670138 -111.990233)
			(xy 42.571918 -111.960828) (xy 42.476273 -111.9239) (xy 42.383777 -111.879672) (xy 42.294986 -111.828408)
			(xy 42.210435 -111.770419) (xy 42.130632 -111.706051) (xy 42.056056 -111.635693) (xy 41.987158 -111.559767)
			(xy 41.92435 -111.478731) (xy 41.86801 -111.393071) (xy 41.818478 -111.303303) (xy 41.776052 -111.209967)
			(xy 41.740986 -111.113623) (xy 41.713491 -111.014852) (xy 41.693733 -110.914247) (xy 41.68183 -110.812414)
			(xy 41.677855 -110.709964) (xy 0.509016 -110.709964) (xy 0.509016 -112.70996) (xy 7.377949 -112.70996)
			(xy 7.381924 -112.60751) (xy 7.393827 -112.505677) (xy 7.413585 -112.405072) (xy 7.44108 -112.306301)
			(xy 7.476146 -112.209957) (xy 7.518572 -112.116621) (xy 7.568104 -112.026853) (xy 7.624444 -111.941193)
			(xy 7.687252 -111.860157) (xy 7.75615 -111.784231) (xy 7.830726 -111.713873) (xy 7.910529 -111.649505)
			(xy 7.99508 -111.591516) (xy 8.083871 -111.540252) (xy 8.176367 -111.496024) (xy 8.272012 -111.459096)
			(xy 8.370232 -111.429691) (xy 8.470435 -111.407986) (xy 8.572018 -111.39411) (xy 8.674372 -111.388149)
			(xy 8.776879 -111.390137) (xy 8.878924 -111.400063) (xy 8.979893 -111.417866) (xy 9.079179 -111.443441)
			(xy 9.176184 -111.476632) (xy 9.270326 -111.517241) (xy 9.361038 -111.565023) (xy 9.447774 -111.619691)
			(xy 9.530013 -111.680915) (xy 9.60726 -111.748329) (xy 9.679051 -111.821526) (xy 9.744954 -111.900066)
			(xy 9.804573 -111.983476) (xy 9.857548 -112.071256) (xy 9.903562 -112.162878) (xy 9.942338 -112.257789)
			(xy 9.973642 -112.35542) (xy 9.997286 -112.455183) (xy 10.013128 -112.556478) (xy 10.021073 -112.658697)
			(xy 10.02139 -112.691361) (xy 17.017742 -112.691361) (xy 17.017742 -112.606639) (xy 17.025795 -112.522302)
			(xy 17.041829 -112.439112) (xy 17.065697 -112.357822) (xy 17.097185 -112.27917) (xy 17.136007 -112.203867)
			(xy 17.18181 -112.132595) (xy 17.234181 -112.065999) (xy 17.292646 -112.004684) (xy 17.356674 -111.949203)
			(xy 17.425686 -111.90006) (xy 17.499056 -111.8577) (xy 17.576121 -111.822505) (xy 17.656183 -111.794796)
			(xy 17.738516 -111.774822) (xy 17.822375 -111.762765) (xy 17.907 -111.758734) (xy 17.991625 -111.762765)
			(xy 18.075484 -111.774822) (xy 18.157817 -111.794796) (xy 18.237879 -111.822505) (xy 18.314944 -111.8577)
			(xy 18.388314 -111.90006) (xy 18.457326 -111.949203) (xy 18.521354 -112.004684) (xy 18.579819 -112.065999)
			(xy 18.63219 -112.132595) (xy 18.677993 -112.203867) (xy 18.716815 -112.27917) (xy 18.748303 -112.357822)
			(xy 18.772171 -112.439112) (xy 18.788205 -112.522302) (xy 18.796258 -112.606639) (xy 18.796762 -112.649)
			(xy 18.796258 -112.691361) (xy 18.788205 -112.775698) (xy 18.772171 -112.858888) (xy 18.748303 -112.940178)
			(xy 18.716815 -113.01883) (xy 18.677993 -113.094133) (xy 18.63219 -113.165405) (xy 18.579819 -113.232001)
			(xy 18.521354 -113.293316) (xy 18.457326 -113.348797) (xy 18.388314 -113.39794) (xy 18.314944 -113.4403)
			(xy 18.237879 -113.475495) (xy 18.157817 -113.503204) (xy 18.075484 -113.523178) (xy 17.991625 -113.535235)
			(xy 17.907 -113.539267) (xy 17.822375 -113.535235) (xy 17.738516 -113.523178) (xy 17.656183 -113.503204)
			(xy 17.576121 -113.475495) (xy 17.499056 -113.4403) (xy 17.425686 -113.39794) (xy 17.356674 -113.348797)
			(xy 17.292646 -113.293316) (xy 17.234181 -113.232001) (xy 17.18181 -113.165405) (xy 17.136007 -113.094133)
			(xy 17.097185 -113.01883) (xy 17.065697 -112.940178) (xy 17.041829 -112.858888) (xy 17.025795 -112.775698)
			(xy 17.017742 -112.691361) (xy 10.02139 -112.691361) (xy 10.02157 -112.70996) (xy 10.021073 -112.761223)
			(xy 10.013128 -112.863442) (xy 9.997286 -112.964737) (xy 9.973642 -113.0645) (xy 9.942338 -113.162131)
			(xy 9.903562 -113.257042) (xy 9.857548 -113.348664) (xy 9.804573 -113.436444) (xy 9.744954 -113.519854)
			(xy 9.679051 -113.598394) (xy 9.60726 -113.671591) (xy 9.530013 -113.739005) (xy 9.447774 -113.800229)
			(xy 9.361038 -113.854897) (xy 9.270326 -113.902679) (xy 9.176184 -113.943288) (xy 9.079179 -113.976479)
			(xy 8.979893 -114.002054) (xy 8.878924 -114.019857) (xy 8.776879 -114.029783) (xy 8.674372 -114.031771)
			(xy 8.572018 -114.02581) (xy 8.470435 -114.011934) (xy 8.370232 -113.990229) (xy 8.272012 -113.960824)
			(xy 8.176367 -113.923896) (xy 8.083871 -113.879668) (xy 7.99508 -113.828404) (xy 7.910529 -113.770415)
			(xy 7.830726 -113.706047) (xy 7.75615 -113.635689) (xy 7.687252 -113.559763) (xy 7.624444 -113.478727)
			(xy 7.568104 -113.393067) (xy 7.518572 -113.303299) (xy 7.476146 -113.209963) (xy 7.44108 -113.113619)
			(xy 7.413585 -113.014848) (xy 7.393827 -112.914243) (xy 7.381924 -112.81241) (xy 7.377949 -112.70996)
			(xy 0.509016 -112.70996) (xy 0.509016 -114.709956) (xy 5.377953 -114.709956) (xy 5.381928 -114.607506)
			(xy 5.393831 -114.505673) (xy 5.413589 -114.405068) (xy 5.441084 -114.306297) (xy 5.47615 -114.209953)
			(xy 5.518576 -114.116617) (xy 5.568108 -114.026849) (xy 5.624448 -113.941189) (xy 5.687256 -113.860153)
			(xy 5.756154 -113.784227) (xy 5.83073 -113.713869) (xy 5.910533 -113.649501) (xy 5.995084 -113.591512)
			(xy 6.083875 -113.540248) (xy 6.176371 -113.49602) (xy 6.272016 -113.459092) (xy 6.370236 -113.429687)
			(xy 6.470439 -113.407982) (xy 6.572022 -113.394106) (xy 6.674376 -113.388145) (xy 6.776883 -113.390133)
			(xy 6.878928 -113.400059) (xy 6.979897 -113.417862) (xy 7.079183 -113.443437) (xy 7.176188 -113.476628)
			(xy 7.27033 -113.517237) (xy 7.361042 -113.565019) (xy 7.447778 -113.619687) (xy 7.530017 -113.680911)
			(xy 7.607264 -113.748325) (xy 7.679055 -113.821522) (xy 7.744958 -113.900062) (xy 7.804577 -113.983472)
			(xy 7.857552 -114.071252) (xy 7.903566 -114.162874) (xy 7.942342 -114.257785) (xy 7.973646 -114.355416)
			(xy 7.99729 -114.455179) (xy 8.013132 -114.556474) (xy 8.021077 -114.658693) (xy 8.021574 -114.709956)
			(xy 8.021077 -114.761219) (xy 8.013132 -114.863438) (xy 7.99729 -114.964733) (xy 7.973646 -115.064496)
			(xy 7.942342 -115.162127) (xy 7.903566 -115.257038) (xy 7.857552 -115.34866) (xy 7.804577 -115.43644)
			(xy 7.744958 -115.51985) (xy 7.679055 -115.59839) (xy 7.607264 -115.671587) (xy 7.530017 -115.739001)
			(xy 7.447778 -115.800225) (xy 7.361042 -115.854893) (xy 7.27033 -115.902675) (xy 7.176188 -115.943284)
			(xy 7.079183 -115.976475) (xy 6.979897 -116.00205) (xy 6.878928 -116.019853) (xy 6.776883 -116.029779)
			(xy 6.674376 -116.031767) (xy 6.572022 -116.025806) (xy 6.470439 -116.01193) (xy 6.370236 -115.990225)
			(xy 6.272016 -115.96082) (xy 6.176371 -115.923892) (xy 6.083875 -115.879664) (xy 5.995084 -115.8284)
			(xy 5.910533 -115.770411) (xy 5.83073 -115.706043) (xy 5.756154 -115.635685) (xy 5.687256 -115.559759)
			(xy 5.624448 -115.478723) (xy 5.568108 -115.393063) (xy 5.518576 -115.303295) (xy 5.47615 -115.209959)
			(xy 5.441084 -115.113615) (xy 5.413589 -115.014844) (xy 5.393831 -114.914239) (xy 5.381928 -114.812406)
			(xy 5.377953 -114.709956) (xy 0.509016 -114.709956) (xy 0.509016 -116.84) (xy 17.220692 -116.84)
			(xy 17.221212 -116.796905) (xy 17.229531 -116.711118) (xy 17.246109 -116.626538) (xy 17.270792 -116.543958)
			(xy 17.303347 -116.464153) (xy 17.34347 -116.387872) (xy 17.390783 -116.31583) (xy 17.444844 -116.248703)
			(xy 17.505145 -116.18712) (xy 17.571121 -116.13166) (xy 17.642152 -116.082842) (xy 17.717573 -116.041124)
			(xy 17.796675 -116.006898) (xy 17.878718 -115.980484) (xy 17.920716 -115.970812) (xy 17.928895 -115.968685)
			(xy 17.943298 -115.959859) (xy 17.94891 -115.95354) (xy 17.976985 -115.920571) (xy 18.038611 -115.859729)
			(xy 18.105864 -115.80517) (xy 18.178105 -115.757411) (xy 18.254649 -115.716906) (xy 18.33477 -115.684039)
			(xy 18.417708 -115.659121) (xy 18.502676 -115.642389) (xy 18.58887 -115.634001) (xy 18.63217 -115.6335)
			(xy 18.673249 -115.633989) (xy 18.755057 -115.641567) (xy 18.835817 -115.656661) (xy 18.91484 -115.679142)
			(xy 18.991451 -115.708819) (xy 19.064997 -115.745439) (xy 19.13485 -115.788688) (xy 19.200415 -115.838198)
			(xy 19.261132 -115.893547) (xy 19.316483 -115.954262) (xy 19.365995 -116.019825) (xy 19.409247 -116.089677)
			(xy 19.445868 -116.163222) (xy 19.475548 -116.239832) (xy 19.498032 -116.318854) (xy 19.513129 -116.399613)
			(xy 19.52071 -116.481421) (xy 19.52117 -116.5225) (xy 19.52064 -116.565503) (xy 19.512324 -116.651107)
			(xy 19.495782 -116.735507) (xy 19.471166 -116.817916) (xy 19.438707 -116.897562) (xy 19.398708 -116.973701)
			(xy 19.351544 -117.045622) (xy 19.297654 -117.112652) (xy 19.237544 -117.174165) (xy 19.171774 -117.229586)
			(xy 19.10096 -117.278396) (xy 19.025763 -117.32014) (xy 18.946887 -117.354427) (xy 18.865068 -117.380937)
			(xy 18.823178 -117.390672) (xy 18.814999 -117.392801) (xy 18.800597 -117.401626) (xy 18.794984 -117.407944)
			(xy 18.766867 -117.441037) (xy 18.705173 -117.502157) (xy 18.637816 -117.556972) (xy 18.5699 -117.602)
			(xy 30.097988 -117.602) (xy 30.102018 -117.517399) (xy 30.114071 -117.433564) (xy 30.134039 -117.351255)
			(xy 30.161741 -117.271216) (xy 30.196925 -117.194173) (xy 30.239274 -117.120823) (xy 30.288403 -117.051831)
			(xy 30.343868 -116.987821) (xy 30.405166 -116.929373) (xy 30.471742 -116.877017) (xy 30.542994 -116.831227)
			(xy 30.618275 -116.792416) (xy 30.696905 -116.760937) (xy 30.778172 -116.737076) (xy 30.861338 -116.721047)
			(xy 30.945652 -116.712996) (xy 30.988 -116.712492) (xy 31.028194 -116.712951) (xy 31.108256 -116.720185)
			(xy 31.18734 -116.734611) (xy 31.264799 -116.756112) (xy 31.340003 -116.784513) (xy 31.376366 -116.801646)
			(xy 31.385389 -116.805561) (xy 31.404998 -116.806883) (xy 31.423678 -116.800774) (xy 31.431484 -116.794788)
			(xy 31.465894 -116.766349) (xy 31.53944 -116.715744) (xy 31.617688 -116.672766) (xy 31.69985 -116.637846)
			(xy 31.785097 -116.611337) (xy 31.872573 -116.593505) (xy 31.961395 -116.584531) (xy 32.006032 -116.583968)
			(xy 32.048356 -116.584476) (xy 32.132621 -116.592522) (xy 32.21574 -116.608542) (xy 32.296959 -116.63239)
			(xy 32.375544 -116.663851) (xy 32.450782 -116.702639) (xy 32.521993 -116.748404) (xy 32.588531 -116.80073)
			(xy 32.649794 -116.859144) (xy 32.705226 -116.923117) (xy 32.754327 -116.99207) (xy 32.796651 -117.065377)
			(xy 32.831815 -117.142376) (xy 32.859501 -117.222369) (xy 32.879458 -117.304631) (xy 32.891504 -117.388418)
			(xy 32.895532 -117.47297) (xy 32.891504 -117.557522) (xy 32.879458 -117.641309) (xy 32.859501 -117.723571)
			(xy 32.831815 -117.803564) (xy 32.796651 -117.880563) (xy 32.754327 -117.95387) (xy 32.705226 -118.022823)
			(xy 32.649794 -118.086796) (xy 32.588531 -118.14521) (xy 32.521993 -118.197536) (xy 32.450782 -118.243301)
			(xy 32.375544 -118.282089) (xy 32.296959 -118.31355) (xy 32.21574 -118.337398) (xy 32.132621 -118.353418)
			(xy 32.048356 -118.361464) (xy 32.006032 -118.361968) (xy 31.965943 -118.361526) (xy 31.886093 -118.354303)
			(xy 31.807218 -118.339911) (xy 31.729961 -118.318469) (xy 31.654952 -118.29015) (xy 31.618682 -118.273068)
			(xy 31.609682 -118.269171) (xy 31.590126 -118.267914) (xy 31.571544 -118.274137) (xy 31.563818 -118.28018)
			(xy 31.529361 -118.308724) (xy 31.455669 -118.359483) (xy 31.377253 -118.402587) (xy 31.294905 -118.437598)
			(xy 31.209457 -118.464163) (xy 31.121774 -118.482014) (xy 31.032741 -118.490969) (xy 30.988 -118.491508)
			(xy 30.945652 -118.491004) (xy 30.861338 -118.482953) (xy 30.778172 -118.466924) (xy 30.696905 -118.443063)
			(xy 30.618275 -118.411584) (xy 30.542994 -118.372773) (xy 30.471742 -118.326983) (xy 30.405166 -118.274627)
			(xy 30.343868 -118.216179) (xy 30.288403 -118.152169) (xy 30.239274 -118.083177) (xy 30.196925 -118.009827)
			(xy 30.161741 -117.932784) (xy 30.134039 -117.852745) (xy 30.114071 -117.770436) (xy 30.102018 -117.686601)
			(xy 30.097988 -117.602) (xy 18.5699 -117.602) (xy 18.565435 -117.60496) (xy 18.488722 -117.645664)
			(xy 18.408406 -117.678696) (xy 18.325253 -117.703742) (xy 18.240054 -117.720563) (xy 18.153622 -117.728999)
			(xy 18.1102 -117.729508) (xy 18.069098 -117.729033) (xy 17.987243 -117.721448) (xy 17.906438 -117.706343)
			(xy 17.827371 -117.683847) (xy 17.750717 -117.654151) (xy 17.67713 -117.617509) (xy 17.607238 -117.574234)
			(xy 17.541637 -117.524694) (xy 17.480887 -117.469313) (xy 17.425506 -117.408563) (xy 17.375966 -117.342962)
			(xy 17.332691 -117.27307) (xy 17.296049 -117.199483) (xy 17.266353 -117.122829) (xy 17.243857 -117.043762)
			(xy 17.228752 -116.962957) (xy 17.221167 -116.881102) (xy 17.220692 -116.84) (xy 0.509016 -116.84)
			(xy 0.509016 -120.609868) (xy 42.741353 -120.609868) (xy 42.745331 -120.509875) (xy 42.757241 -120.410515)
			(xy 42.777008 -120.312414) (xy 42.804507 -120.216195) (xy 42.839563 -120.122464) (xy 42.881955 -120.031815)
			(xy 42.931416 -119.944821) (xy 42.987632 -119.862031) (xy 43.050248 -119.783969) (xy 43.118867 -119.711129)
			(xy 43.193058 -119.643971) (xy 43.272349 -119.582919) (xy 43.35624 -119.528361) (xy 43.444201 -119.48064)
			(xy 43.535675 -119.440058) (xy 43.630084 -119.406872) (xy 43.726831 -119.381292) (xy 43.825305 -119.363479)
			(xy 43.924883 -119.353547) (xy 44.024935 -119.351557) (xy 44.124829 -119.357523) (xy 44.223933 -119.371407)
			(xy 44.321621 -119.39312) (xy 44.417275 -119.422526) (xy 44.51029 -119.459439) (xy 44.600078 -119.503625)
			(xy 44.686072 -119.554806) (xy 44.767728 -119.612656) (xy 44.844529 -119.676812) (xy 44.915991 -119.746866)
			(xy 44.981661 -119.822377) (xy 45.041123 -119.902867) (xy 45.094003 -119.987826) (xy 45.139966 -120.076718)
			(xy 45.178721 -120.168981) (xy 45.210023 -120.264031) (xy 45.233675 -120.361268) (xy 45.249526 -120.460077)
			(xy 45.257476 -120.559832) (xy 45.257974 -120.609868) (xy 45.257476 -120.659904) (xy 45.249526 -120.759659)
			(xy 45.233675 -120.858468) (xy 45.210023 -120.955705) (xy 45.178721 -121.050755) (xy 45.139966 -121.143018)
			(xy 45.094003 -121.23191) (xy 45.041123 -121.316869) (xy 44.981661 -121.397359) (xy 44.915991 -121.47287)
			(xy 44.844529 -121.542924) (xy 44.767728 -121.60708) (xy 44.686072 -121.66493) (xy 44.600078 -121.716111)
			(xy 44.51029 -121.760297) (xy 44.417275 -121.79721) (xy 44.321621 -121.826616) (xy 44.223933 -121.848329)
			(xy 44.124829 -121.862213) (xy 44.024935 -121.868179) (xy 43.924883 -121.866189) (xy 43.825305 -121.856257)
			(xy 43.726831 -121.838444) (xy 43.630084 -121.812864) (xy 43.535675 -121.779678) (xy 43.444201 -121.739096)
			(xy 43.35624 -121.691375) (xy 43.272349 -121.636817) (xy 43.193058 -121.575765) (xy 43.118867 -121.508607)
			(xy 43.050248 -121.435767) (xy 42.987632 -121.357705) (xy 42.931416 -121.274915) (xy 42.881955 -121.187921)
			(xy 42.839563 -121.097272) (xy 42.804507 -121.003541) (xy 42.777008 -120.907322) (xy 42.757241 -120.809221)
			(xy 42.745331 -120.709861) (xy 42.741353 -120.609868) (xy 0.509016 -120.609868) (xy 0.509016 -193.082361)
			(xy 4.952742 -193.082361) (xy 4.952742 -192.997639) (xy 4.960795 -192.913302) (xy 4.976829 -192.830112)
			(xy 5.000697 -192.748822) (xy 5.032185 -192.67017) (xy 5.071007 -192.594867) (xy 5.11681 -192.523595)
			(xy 5.169181 -192.456999) (xy 5.227646 -192.395684) (xy 5.291674 -192.340203) (xy 5.360686 -192.29106)
			(xy 5.434056 -192.2487) (xy 5.511121 -192.213505) (xy 5.591183 -192.185796) (xy 5.673516 -192.165822)
			(xy 5.757375 -192.153765) (xy 5.842 -192.149734) (xy 5.926625 -192.153765) (xy 6.010484 -192.165822)
			(xy 6.092817 -192.185796) (xy 6.172879 -192.213505) (xy 6.249944 -192.2487) (xy 6.323314 -192.29106)
			(xy 6.392326 -192.340203) (xy 6.456354 -192.395684) (xy 6.514819 -192.456999) (xy 6.56719 -192.523595)
			(xy 6.612993 -192.594867) (xy 6.651815 -192.67017) (xy 6.683303 -192.748822) (xy 6.707171 -192.830112)
			(xy 6.723205 -192.913302) (xy 6.731258 -192.997639) (xy 6.731762 -193.04) (xy 6.731258 -193.082361)
			(xy 6.723205 -193.166698) (xy 6.707171 -193.249888) (xy 6.683303 -193.331178) (xy 6.651815 -193.40983)
			(xy 6.612993 -193.485133) (xy 6.56719 -193.556405) (xy 6.514819 -193.623001) (xy 6.456354 -193.684316)
			(xy 6.392326 -193.739797) (xy 6.323314 -193.78894) (xy 6.249944 -193.8313) (xy 6.172879 -193.866495)
			(xy 6.092817 -193.894204) (xy 6.010484 -193.914178) (xy 5.926625 -193.926235) (xy 5.842 -193.930267)
			(xy 5.757375 -193.926235) (xy 5.673516 -193.914178) (xy 5.591183 -193.894204) (xy 5.511121 -193.866495)
			(xy 5.434056 -193.8313) (xy 5.360686 -193.78894) (xy 5.291674 -193.739797) (xy 5.227646 -193.684316)
			(xy 5.169181 -193.623001) (xy 5.11681 -193.556405) (xy 5.071007 -193.485133) (xy 5.032185 -193.40983)
			(xy 5.000697 -193.331178) (xy 4.976829 -193.249888) (xy 4.960795 -193.166698) (xy 4.952742 -193.082361)
			(xy 0.509016 -193.082361) (xy 0.509016 -195.1101) (xy 6.441451 -195.1101) (xy 6.445429 -195.010107)
			(xy 6.457339 -194.910747) (xy 6.477106 -194.812646) (xy 6.504605 -194.716427) (xy 6.539661 -194.622696)
			(xy 6.582053 -194.532047) (xy 6.631514 -194.445053) (xy 6.68773 -194.362263) (xy 6.750346 -194.284201)
			(xy 6.818965 -194.211361) (xy 6.893156 -194.144203) (xy 6.972447 -194.083151) (xy 7.056338 -194.028593)
			(xy 7.144299 -193.980872) (xy 7.235773 -193.94029) (xy 7.330182 -193.907104) (xy 7.426929 -193.881524)
			(xy 7.525403 -193.863711) (xy 7.624981 -193.853779) (xy 7.725033 -193.851789) (xy 7.824927 -193.857755)
			(xy 7.924031 -193.871639) (xy 8.021719 -193.893352) (xy 8.117373 -193.922758) (xy 8.210388 -193.959671)
			(xy 8.300176 -194.003857) (xy 8.38617 -194.055038) (xy 8.467826 -194.112888) (xy 8.544627 -194.177044)
			(xy 8.616089 -194.247098) (xy 8.681759 -194.322609) (xy 8.741221 -194.403099) (xy 8.794101 -194.488058)
			(xy 8.840064 -194.57695) (xy 8.878819 -194.669213) (xy 8.910121 -194.764263) (xy 8.933773 -194.8615)
			(xy 8.949624 -194.960309) (xy 8.957574 -195.060064) (xy 8.958072 -195.1101) (xy 8.957574 -195.160136)
			(xy 8.949624 -195.259891) (xy 8.933773 -195.3587) (xy 8.910121 -195.455937) (xy 8.878819 -195.550987)
			(xy 8.840064 -195.64325) (xy 8.794101 -195.732142) (xy 8.741221 -195.817101) (xy 8.681759 -195.897591)
			(xy 8.616089 -195.973102) (xy 8.544627 -196.043156) (xy 8.467826 -196.107312) (xy 8.38617 -196.165162)
			(xy 8.300176 -196.216343) (xy 8.210388 -196.260529) (xy 8.117373 -196.297442) (xy 8.021719 -196.326848)
			(xy 7.924031 -196.348561) (xy 7.824927 -196.362445) (xy 7.725033 -196.368411) (xy 7.624981 -196.366421)
			(xy 7.525403 -196.356489) (xy 7.426929 -196.338676) (xy 7.330182 -196.313096) (xy 7.235773 -196.27991)
			(xy 7.144299 -196.239328) (xy 7.056338 -196.191607) (xy 6.972447 -196.137049) (xy 6.893156 -196.075997)
			(xy 6.818965 -196.008839) (xy 6.750346 -195.935999) (xy 6.68773 -195.857937) (xy 6.631514 -195.775147)
			(xy 6.582053 -195.688153) (xy 6.539661 -195.597504) (xy 6.504605 -195.503773) (xy 6.477106 -195.407554)
			(xy 6.457339 -195.309453) (xy 6.445429 -195.210093) (xy 6.441451 -195.1101) (xy 0.509016 -195.1101)
			(xy 0.509016 -196.85) (xy 18.770092 -196.85) (xy 18.770517 -196.810159) (xy 18.777625 -196.730796)
			(xy 18.791803 -196.652386) (xy 18.812936 -196.575558) (xy 18.82648 -196.538088) (xy 18.82915 -196.530146)
			(xy 18.829679 -196.51341) (xy 18.827496 -196.505322) (xy 18.814897 -196.462741) (xy 18.797265 -196.375704)
			(xy 18.788408 -196.287342) (xy 18.787872 -196.24294) (xy 18.788376 -196.200616) (xy 18.796422 -196.11635)
			(xy 18.812442 -196.033231) (xy 18.83629 -195.952012) (xy 18.867751 -195.873427) (xy 18.906539 -195.798188)
			(xy 18.952303 -195.726977) (xy 19.00463 -195.660439) (xy 19.063044 -195.599176) (xy 19.127017 -195.543743)
			(xy 19.19597 -195.494642) (xy 19.269278 -195.452317) (xy 19.346277 -195.417153) (xy 19.42627 -195.389467)
			(xy 19.508532 -195.36951) (xy 19.592319 -195.357464) (xy 19.676872 -195.353436) (xy 19.761425 -195.357464)
			(xy 19.845212 -195.36951) (xy 19.927474 -195.389467) (xy 20.007467 -195.417153) (xy 20.084466 -195.452317)
			(xy 20.157774 -195.494642) (xy 20.226727 -195.543743) (xy 20.2907 -195.599176) (xy 20.349114 -195.660439)
			(xy 20.401441 -195.726977) (xy 20.447205 -195.798188) (xy 20.485993 -195.873427) (xy 20.517454 -195.952012)
			(xy 20.541302 -196.033231) (xy 20.557322 -196.11635) (xy 20.565368 -196.200616) (xy 20.565872 -196.24294)
			(xy 20.56543 -196.282547) (xy 20.558368 -196.361445) (xy 20.544321 -196.439403) (xy 20.5234 -196.515803)
			(xy 20.509992 -196.553074) (xy 20.507444 -196.561045) (xy 20.507049 -196.577762) (xy 20.50923 -196.58584)
			(xy 20.521931 -196.628706) (xy 20.539699 -196.716331) (xy 20.548593 -196.805295) (xy 20.549108 -196.85)
			(xy 20.548604 -196.892348) (xy 20.540553 -196.976662) (xy 20.524524 -197.059828) (xy 20.511555 -197.104)
			(xy 33.121092 -197.104) (xy 33.121603 -197.061427) (xy 33.129737 -196.976671) (xy 33.14593 -196.893079)
			(xy 33.170034 -196.811416) (xy 33.201829 -196.732429) (xy 33.241024 -196.656841) (xy 33.28726 -196.585342)
			(xy 33.340115 -196.518588) (xy 33.36925 -196.487542) (xy 33.37306 -196.48297) (xy 33.398215 -196.450706)
			(xy 33.453548 -196.390439) (xy 33.514184 -196.33551) (xy 33.57961 -196.286385) (xy 33.649272 -196.243477)
			(xy 33.722582 -196.207151) (xy 33.798919 -196.177713) (xy 33.877638 -196.155413) (xy 33.958072 -196.140439)
			(xy 34.039542 -196.132918) (xy 34.08045 -196.13245) (xy 34.12153 -196.132908) (xy 34.203341 -196.140485)
			(xy 34.284103 -196.155578) (xy 34.363128 -196.17806) (xy 34.439742 -196.207737) (xy 34.51329 -196.244358)
			(xy 34.583145 -196.287608) (xy 34.648711 -196.337121) (xy 34.709428 -196.392472) (xy 34.764779 -196.453189)
			(xy 34.814292 -196.518755) (xy 34.857542 -196.58861) (xy 34.894163 -196.662158) (xy 34.92384 -196.738772)
			(xy 34.946322 -196.817797) (xy 34.961415 -196.898559) (xy 34.968992 -196.98037) (xy 34.96945 -197.02145)
			(xy 34.968972 -197.063356) (xy 34.961085 -197.146796) (xy 34.945377 -197.229123) (xy 34.921987 -197.309606)
			(xy 34.891123 -197.387528) (xy 34.85306 -197.462198) (xy 34.808135 -197.532953) (xy 34.756748 -197.599164)
			(xy 34.728404 -197.630034) (xy 34.724848 -197.634352) (xy 34.699744 -197.667357) (xy 34.644308 -197.729035)
			(xy 34.583373 -197.785287) (xy 34.517468 -197.835625) (xy 34.447165 -197.879613) (xy 34.373075 -197.916868)
			(xy 34.295839 -197.947067) (xy 34.216129 -197.969949) (xy 34.134635 -197.985315) (xy 34.052065 -197.993031)
			(xy 34.0106 -197.993508) (xy 33.969498 -197.993033) (xy 33.887643 -197.985448) (xy 33.806838 -197.970343)
			(xy 33.727771 -197.947847) (xy 33.651117 -197.918151) (xy 33.57753 -197.881509) (xy 33.507638 -197.838234)
			(xy 33.442037 -197.788694) (xy 33.381287 -197.733313) (xy 33.325906 -197.672563) (xy 33.276366 -197.606962)
			(xy 33.233091 -197.53707) (xy 33.196449 -197.463483) (xy 33.166753 -197.386829) (xy 33.144257 -197.307762)
			(xy 33.129152 -197.226957) (xy 33.121567 -197.145102) (xy 33.121092 -197.104) (xy 20.511555 -197.104)
			(xy 20.500663 -197.141095) (xy 20.469184 -197.219725) (xy 20.430373 -197.295006) (xy 20.384583 -197.366258)
			(xy 20.332227 -197.432834) (xy 20.273779 -197.494132) (xy 20.209769 -197.549597) (xy 20.140777 -197.598726)
			(xy 20.067427 -197.641075) (xy 19.990384 -197.676259) (xy 19.910345 -197.703961) (xy 19.828036 -197.723929)
			(xy 19.744201 -197.735982) (xy 19.6596 -197.740013) (xy 19.574999 -197.735982) (xy 19.491164 -197.723929)
			(xy 19.408855 -197.703961) (xy 19.328816 -197.676259) (xy 19.251773 -197.641075) (xy 19.178423 -197.598726)
			(xy 19.109431 -197.549597) (xy 19.045421 -197.494132) (xy 18.986973 -197.432834) (xy 18.934617 -197.366258)
			(xy 18.888827 -197.295006) (xy 18.850016 -197.219725) (xy 18.818537 -197.141095) (xy 18.794676 -197.059828)
			(xy 18.778647 -196.976662) (xy 18.770596 -196.892348) (xy 18.770092 -196.85) (xy 0.509016 -196.85)
			(xy 0.509016 -201.010012) (xy 43.677851 -201.010012) (xy 43.681826 -200.907562) (xy 43.693729 -200.805729)
			(xy 43.713487 -200.705124) (xy 43.740982 -200.606353) (xy 43.776048 -200.510009) (xy 43.818474 -200.416673)
			(xy 43.868006 -200.326905) (xy 43.924346 -200.241245) (xy 43.987154 -200.160209) (xy 44.056052 -200.084283)
			(xy 44.130628 -200.013925) (xy 44.210431 -199.949557) (xy 44.294982 -199.891568) (xy 44.383773 -199.840304)
			(xy 44.476269 -199.796076) (xy 44.571914 -199.759148) (xy 44.670134 -199.729743) (xy 44.770337 -199.708038)
			(xy 44.87192 -199.694162) (xy 44.974274 -199.688201) (xy 45.076781 -199.690189) (xy 45.178826 -199.700115)
			(xy 45.279795 -199.717918) (xy 45.379081 -199.743493) (xy 45.476086 -199.776684) (xy 45.570228 -199.817293)
			(xy 45.66094 -199.865075) (xy 45.747676 -199.919743) (xy 45.829915 -199.980967) (xy 45.907162 -200.048381)
			(xy 45.978953 -200.121578) (xy 46.044856 -200.200118) (xy 46.104475 -200.283528) (xy 46.15745 -200.371308)
			(xy 46.203464 -200.46293) (xy 46.24224 -200.557841) (xy 46.273544 -200.655472) (xy 46.297188 -200.755235)
			(xy 46.31303 -200.85653) (xy 46.320975 -200.958749) (xy 46.321472 -201.010012) (xy 46.320975 -201.061275)
			(xy 46.31303 -201.163494) (xy 46.297188 -201.264789) (xy 46.273544 -201.364552) (xy 46.24224 -201.462183)
			(xy 46.203464 -201.557094) (xy 46.15745 -201.648716) (xy 46.104475 -201.736496) (xy 46.044856 -201.819906)
			(xy 45.978953 -201.898446) (xy 45.907162 -201.971643) (xy 45.829915 -202.039057) (xy 45.747676 -202.100281)
			(xy 45.66094 -202.154949) (xy 45.570228 -202.202731) (xy 45.476086 -202.24334) (xy 45.379081 -202.276531)
			(xy 45.279795 -202.302106) (xy 45.178826 -202.319909) (xy 45.076781 -202.329835) (xy 44.974274 -202.331823)
			(xy 44.87192 -202.325862) (xy 44.770337 -202.311986) (xy 44.670134 -202.290281) (xy 44.571914 -202.260876)
			(xy 44.476269 -202.223948) (xy 44.383773 -202.17972) (xy 44.294982 -202.128456) (xy 44.210431 -202.070467)
			(xy 44.130628 -202.006099) (xy 44.056052 -201.935741) (xy 43.987154 -201.859815) (xy 43.924346 -201.778779)
			(xy 43.868006 -201.693119) (xy 43.818474 -201.603351) (xy 43.776048 -201.510015) (xy 43.740982 -201.413671)
			(xy 43.713487 -201.3149) (xy 43.693729 -201.214295) (xy 43.681826 -201.112462) (xy 43.677851 -201.010012)
			(xy 0.509016 -201.010012) (xy 0.509016 -202.715311) (xy 14.350742 -202.715311) (xy 14.350742 -202.630589)
			(xy 14.358795 -202.546252) (xy 14.374829 -202.463062) (xy 14.398697 -202.381772) (xy 14.430185 -202.30312)
			(xy 14.469007 -202.227817) (xy 14.51481 -202.156545) (xy 14.567181 -202.089949) (xy 14.625646 -202.028634)
			(xy 14.689674 -201.973153) (xy 14.758686 -201.92401) (xy 14.832056 -201.88165) (xy 14.909121 -201.846455)
			(xy 14.989183 -201.818746) (xy 15.071516 -201.798772) (xy 15.155375 -201.786715) (xy 15.24 -201.782684)
			(xy 15.324625 -201.786715) (xy 15.408484 -201.798772) (xy 15.490817 -201.818746) (xy 15.570879 -201.846455)
			(xy 15.647944 -201.88165) (xy 15.721314 -201.92401) (xy 15.790326 -201.973153) (xy 15.854354 -202.028634)
			(xy 15.912819 -202.089949) (xy 15.96519 -202.156545) (xy 16.010993 -202.227817) (xy 16.049815 -202.30312)
			(xy 16.081303 -202.381772) (xy 16.105171 -202.463062) (xy 16.121205 -202.546252) (xy 16.129258 -202.630589)
			(xy 16.129762 -202.67295) (xy 16.129258 -202.715311) (xy 16.121205 -202.799648) (xy 16.105171 -202.882838)
			(xy 16.081303 -202.964128) (xy 16.062935 -203.010008) (xy 41.677855 -203.010008) (xy 41.68183 -202.907558)
			(xy 41.693733 -202.805725) (xy 41.713491 -202.70512) (xy 41.740986 -202.606349) (xy 41.776052 -202.510005)
			(xy 41.818478 -202.416669) (xy 41.86801 -202.326901) (xy 41.92435 -202.241241) (xy 41.987158 -202.160205)
			(xy 42.056056 -202.084279) (xy 42.130632 -202.013921) (xy 42.210435 -201.949553) (xy 42.294986 -201.891564)
			(xy 42.383777 -201.8403) (xy 42.476273 -201.796072) (xy 42.571918 -201.759144) (xy 42.670138 -201.729739)
			(xy 42.770341 -201.708034) (xy 42.871924 -201.694158) (xy 42.974278 -201.688197) (xy 43.076785 -201.690185)
			(xy 43.17883 -201.700111) (xy 43.279799 -201.717914) (xy 43.379085 -201.743489) (xy 43.47609 -201.77668)
			(xy 43.570232 -201.817289) (xy 43.660944 -201.865071) (xy 43.74768 -201.919739) (xy 43.829919 -201.980963)
			(xy 43.907166 -202.048377) (xy 43.978957 -202.121574) (xy 44.04486 -202.200114) (xy 44.104479 -202.283524)
			(xy 44.157454 -202.371304) (xy 44.203468 -202.462926) (xy 44.242244 -202.557837) (xy 44.273548 -202.655468)
			(xy 44.297192 -202.755231) (xy 44.313034 -202.856526) (xy 44.320979 -202.958745) (xy 44.321476 -203.010008)
			(xy 44.320979 -203.061271) (xy 44.313034 -203.16349) (xy 44.297192 -203.264785) (xy 44.273548 -203.364548)
			(xy 44.242244 -203.462179) (xy 44.203468 -203.55709) (xy 44.157454 -203.648712) (xy 44.104479 -203.736492)
			(xy 44.04486 -203.819902) (xy 43.978957 -203.898442) (xy 43.907166 -203.971639) (xy 43.829919 -204.039053)
			(xy 43.74768 -204.100277) (xy 43.660944 -204.154945) (xy 43.570232 -204.202727) (xy 43.47609 -204.243336)
			(xy 43.379085 -204.276527) (xy 43.279799 -204.302102) (xy 43.17883 -204.319905) (xy 43.076785 -204.329831)
			(xy 42.974278 -204.331819) (xy 42.871924 -204.325858) (xy 42.770341 -204.311982) (xy 42.670138 -204.290277)
			(xy 42.571918 -204.260872) (xy 42.476273 -204.223944) (xy 42.383777 -204.179716) (xy 42.294986 -204.128452)
			(xy 42.210435 -204.070463) (xy 42.130632 -204.006095) (xy 42.056056 -203.935737) (xy 41.987158 -203.859811)
			(xy 41.92435 -203.778775) (xy 41.86801 -203.693115) (xy 41.818478 -203.603347) (xy 41.776052 -203.510011)
			(xy 41.740986 -203.413667) (xy 41.713491 -203.314896) (xy 41.693733 -203.214291) (xy 41.68183 -203.112458)
			(xy 41.677855 -203.010008) (xy 16.062935 -203.010008) (xy 16.049815 -203.04278) (xy 16.010993 -203.118083)
			(xy 15.96519 -203.189355) (xy 15.912819 -203.255951) (xy 15.854354 -203.317266) (xy 15.790326 -203.372747)
			(xy 15.721314 -203.42189) (xy 15.647944 -203.46425) (xy 15.570879 -203.499445) (xy 15.490817 -203.527154)
			(xy 15.408484 -203.547128) (xy 15.324625 -203.559185) (xy 15.24 -203.563217) (xy 15.155375 -203.559185)
			(xy 15.071516 -203.547128) (xy 14.989183 -203.527154) (xy 14.909121 -203.499445) (xy 14.832056 -203.46425)
			(xy 14.758686 -203.42189) (xy 14.689674 -203.372747) (xy 14.625646 -203.317266) (xy 14.567181 -203.255951)
			(xy 14.51481 -203.189355) (xy 14.469007 -203.118083) (xy 14.430185 -203.04278) (xy 14.398697 -202.964128)
			(xy 14.374829 -202.882838) (xy 14.358795 -202.799648) (xy 14.350742 -202.715311) (xy 0.509016 -202.715311)
			(xy 0.509016 -205.010004) (xy 7.377949 -205.010004) (xy 7.381924 -204.907554) (xy 7.393827 -204.805721)
			(xy 7.413585 -204.705116) (xy 7.44108 -204.606345) (xy 7.476146 -204.510001) (xy 7.518572 -204.416665)
			(xy 7.568104 -204.326897) (xy 7.624444 -204.241237) (xy 7.687252 -204.160201) (xy 7.75615 -204.084275)
			(xy 7.830726 -204.013917) (xy 7.910529 -203.949549) (xy 7.99508 -203.89156) (xy 8.083871 -203.840296)
			(xy 8.176367 -203.796068) (xy 8.272012 -203.75914) (xy 8.370232 -203.729735) (xy 8.470435 -203.70803)
			(xy 8.572018 -203.694154) (xy 8.674372 -203.688193) (xy 8.776879 -203.690181) (xy 8.878924 -203.700107)
			(xy 8.979893 -203.71791) (xy 9.079179 -203.743485) (xy 9.176184 -203.776676) (xy 9.270326 -203.817285)
			(xy 9.361038 -203.865067) (xy 9.447774 -203.919735) (xy 9.530013 -203.980959) (xy 9.60726 -204.048373)
			(xy 9.679051 -204.12157) (xy 9.744954 -204.20011) (xy 9.804573 -204.28352) (xy 9.857548 -204.3713)
			(xy 9.878131 -204.412285) (xy 16.382742 -204.412285) (xy 16.382742 -204.327563) (xy 16.390795 -204.243226)
			(xy 16.406829 -204.160036) (xy 16.430697 -204.078746) (xy 16.462185 -204.000094) (xy 16.501007 -203.924791)
			(xy 16.54681 -203.853519) (xy 16.599181 -203.786923) (xy 16.657646 -203.725608) (xy 16.721674 -203.670127)
			(xy 16.790686 -203.620984) (xy 16.864056 -203.578624) (xy 16.941121 -203.543429) (xy 17.021183 -203.51572)
			(xy 17.103516 -203.495746) (xy 17.187375 -203.483689) (xy 17.272 -203.479658) (xy 17.356625 -203.483689)
			(xy 17.440484 -203.495746) (xy 17.522817 -203.51572) (xy 17.602879 -203.543429) (xy 17.679944 -203.578624)
			(xy 17.753314 -203.620984) (xy 17.822326 -203.670127) (xy 17.886354 -203.725608) (xy 17.944819 -203.786923)
			(xy 17.99719 -203.853519) (xy 18.042993 -203.924791) (xy 18.081815 -204.000094) (xy 18.113303 -204.078746)
			(xy 18.137171 -204.160036) (xy 18.153205 -204.243226) (xy 18.161258 -204.327563) (xy 18.161762 -204.369924)
			(xy 18.161258 -204.412285) (xy 18.153205 -204.496622) (xy 18.137171 -204.579812) (xy 18.113303 -204.661102)
			(xy 18.081815 -204.739754) (xy 18.042993 -204.815057) (xy 17.99719 -204.886329) (xy 17.944819 -204.952925)
			(xy 17.886354 -205.01424) (xy 17.822326 -205.069721) (xy 17.753314 -205.118864) (xy 17.679944 -205.161224)
			(xy 17.602879 -205.196419) (xy 17.522817 -205.224128) (xy 17.440484 -205.244102) (xy 17.356625 -205.256159)
			(xy 17.272 -205.260191) (xy 17.187375 -205.256159) (xy 17.103516 -205.244102) (xy 17.021183 -205.224128)
			(xy 16.941121 -205.196419) (xy 16.864056 -205.161224) (xy 16.790686 -205.118864) (xy 16.721674 -205.069721)
			(xy 16.657646 -205.01424) (xy 16.599181 -204.952925) (xy 16.54681 -204.886329) (xy 16.501007 -204.815057)
			(xy 16.462185 -204.739754) (xy 16.430697 -204.661102) (xy 16.406829 -204.579812) (xy 16.390795 -204.496622)
			(xy 16.382742 -204.412285) (xy 9.878131 -204.412285) (xy 9.903562 -204.462922) (xy 9.942338 -204.557833)
			(xy 9.973642 -204.655464) (xy 9.997286 -204.755227) (xy 10.013128 -204.856522) (xy 10.021073 -204.958741)
			(xy 10.02157 -205.010004) (xy 10.021073 -205.061267) (xy 10.013128 -205.163486) (xy 9.997286 -205.264781)
			(xy 9.973642 -205.364544) (xy 9.942338 -205.462175) (xy 9.903562 -205.557086) (xy 9.857548 -205.648708)
			(xy 9.804573 -205.736488) (xy 9.744954 -205.819898) (xy 9.679051 -205.898438) (xy 9.60726 -205.971635)
			(xy 9.530013 -206.039049) (xy 9.447774 -206.100273) (xy 9.361038 -206.154941) (xy 9.270326 -206.202723)
			(xy 9.176184 -206.243332) (xy 9.079179 -206.276523) (xy 8.979893 -206.302098) (xy 8.878924 -206.319901)
			(xy 8.776879 -206.329827) (xy 8.674372 -206.331815) (xy 8.572018 -206.325854) (xy 8.470435 -206.311978)
			(xy 8.370232 -206.290273) (xy 8.272012 -206.260868) (xy 8.176367 -206.22394) (xy 8.083871 -206.179712)
			(xy 7.99508 -206.128448) (xy 7.910529 -206.070459) (xy 7.830726 -206.006091) (xy 7.75615 -205.935733)
			(xy 7.687252 -205.859807) (xy 7.624444 -205.778771) (xy 7.568104 -205.693111) (xy 7.518572 -205.603343)
			(xy 7.476146 -205.510007) (xy 7.44108 -205.413663) (xy 7.413585 -205.314892) (xy 7.393827 -205.214287)
			(xy 7.381924 -205.112454) (xy 7.377949 -205.010004) (xy 0.509016 -205.010004) (xy 0.509016 -207.01)
			(xy 5.377953 -207.01) (xy 5.381928 -206.90755) (xy 5.393831 -206.805717) (xy 5.413589 -206.705112)
			(xy 5.441084 -206.606341) (xy 5.47615 -206.509997) (xy 5.518576 -206.416661) (xy 5.568108 -206.326893)
			(xy 5.624448 -206.241233) (xy 5.687256 -206.160197) (xy 5.756154 -206.084271) (xy 5.83073 -206.013913)
			(xy 5.910533 -205.949545) (xy 5.995084 -205.891556) (xy 6.083875 -205.840292) (xy 6.176371 -205.796064)
			(xy 6.272016 -205.759136) (xy 6.370236 -205.729731) (xy 6.470439 -205.708026) (xy 6.572022 -205.69415)
			(xy 6.674376 -205.688189) (xy 6.776883 -205.690177) (xy 6.878928 -205.700103) (xy 6.979897 -205.717906)
			(xy 7.079183 -205.743481) (xy 7.176188 -205.776672) (xy 7.27033 -205.817281) (xy 7.361042 -205.865063)
			(xy 7.447778 -205.919731) (xy 7.530017 -205.980955) (xy 7.607264 -206.048369) (xy 7.679055 -206.121566)
			(xy 7.744958 -206.200106) (xy 7.804577 -206.283516) (xy 7.857552 -206.371296) (xy 7.903566 -206.462918)
			(xy 7.942342 -206.557829) (xy 7.973646 -206.65546) (xy 7.99729 -206.755223) (xy 8.013132 -206.856518)
			(xy 8.021077 -206.958737) (xy 8.021574 -207.01) (xy 8.021077 -207.061263) (xy 8.013132 -207.163482)
			(xy 7.99729 -207.264777) (xy 7.973646 -207.36454) (xy 7.942342 -207.462171) (xy 7.903566 -207.557082)
			(xy 7.857552 -207.648704) (xy 7.804577 -207.736484) (xy 7.744958 -207.819894) (xy 7.679055 -207.898434)
			(xy 7.607264 -207.971631) (xy 7.530017 -208.039045) (xy 7.447778 -208.100269) (xy 7.361042 -208.154937)
			(xy 7.27033 -208.202719) (xy 7.176188 -208.243328) (xy 7.079183 -208.276519) (xy 6.979897 -208.302094)
			(xy 6.878928 -208.319897) (xy 6.776883 -208.329823) (xy 6.674376 -208.331811) (xy 6.572022 -208.32585)
			(xy 6.470439 -208.311974) (xy 6.370236 -208.290269) (xy 6.272016 -208.260864) (xy 6.176371 -208.223936)
			(xy 6.083875 -208.179708) (xy 5.995084 -208.128444) (xy 5.910533 -208.070455) (xy 5.83073 -208.006087)
			(xy 5.756154 -207.935729) (xy 5.687256 -207.859803) (xy 5.624448 -207.778767) (xy 5.568108 -207.693107)
			(xy 5.518576 -207.603339) (xy 5.47615 -207.510003) (xy 5.441084 -207.413659) (xy 5.413589 -207.314888)
			(xy 5.393831 -207.214283) (xy 5.381928 -207.11245) (xy 5.377953 -207.01) (xy 0.509016 -207.01) (xy 0.509016 -209.169)
			(xy 18.668492 -209.169) (xy 18.668996 -209.126652) (xy 18.677047 -209.042338) (xy 18.693076 -208.959172)
			(xy 18.716937 -208.877905) (xy 18.748416 -208.799275) (xy 18.787227 -208.723994) (xy 18.833017 -208.652742)
			(xy 18.885373 -208.586166) (xy 18.943821 -208.524868) (xy 19.007831 -208.469403) (xy 19.076823 -208.420274)
			(xy 19.150173 -208.377925) (xy 19.227216 -208.342741) (xy 19.307255 -208.315039) (xy 19.389564 -208.295071)
			(xy 19.473399 -208.283018) (xy 19.558 -208.278988) (xy 19.642601 -208.283018) (xy 19.726436 -208.295071)
			(xy 19.808745 -208.315039) (xy 19.888784 -208.342741) (xy 19.965827 -208.377925) (xy 20.039177 -208.420274)
			(xy 20.108169 -208.469403) (xy 20.172179 -208.524868) (xy 20.230627 -208.586166) (xy 20.282983 -208.652742)
			(xy 20.328773 -208.723994) (xy 20.367584 -208.799275) (xy 20.399063 -208.877905) (xy 20.422924 -208.959172)
			(xy 20.438953 -209.042338) (xy 20.447004 -209.126652) (xy 20.447508 -209.169) (xy 20.446968 -209.213971)
			(xy 20.437959 -209.30346) (xy 20.419974 -209.391585) (xy 20.407122 -209.434684) (xy 20.40382 -209.445352)
			(xy 20.40636 -209.466434) (xy 20.456652 -209.550508) (xy 20.474178 -209.5627) (xy 20.4851 -209.564732)
			(xy 20.525354 -209.572796) (xy 20.604278 -209.595425) (xy 20.680781 -209.625228) (xy 20.754213 -209.661953)
			(xy 20.82395 -209.705287) (xy 20.889398 -209.75486) (xy 20.950001 -209.810252) (xy 21.005244 -209.870992)
			(xy 21.054656 -209.936562) (xy 21.097817 -210.006405) (xy 21.13436 -210.079928) (xy 21.163975 -210.156505)
			(xy 21.186409 -210.235484) (xy 21.201472 -210.316194) (xy 21.209036 -210.397948) (xy 21.209508 -210.439)
			(xy 21.209033 -210.480102) (xy 21.201448 -210.561957) (xy 21.187361 -210.637317) (xy 30.352742 -210.637317)
			(xy 30.352742 -210.552595) (xy 30.360795 -210.468258) (xy 30.376829 -210.385068) (xy 30.400697 -210.303778)
			(xy 30.432185 -210.225126) (xy 30.471007 -210.149823) (xy 30.51681 -210.078551) (xy 30.569181 -210.011955)
			(xy 30.627646 -209.95064) (xy 30.691674 -209.895159) (xy 30.760686 -209.846016) (xy 30.834056 -209.803656)
			(xy 30.911121 -209.768461) (xy 30.991183 -209.740752) (xy 31.073516 -209.720778) (xy 31.157375 -209.708721)
			(xy 31.242 -209.70469) (xy 31.326625 -209.708721) (xy 31.410484 -209.720778) (xy 31.492817 -209.740752)
			(xy 31.572879 -209.768461) (xy 31.649944 -209.803656) (xy 31.723314 -209.846016) (xy 31.792326 -209.895159)
			(xy 31.856354 -209.95064) (xy 31.914819 -210.011955) (xy 31.96719 -210.078551) (xy 32.012993 -210.149823)
			(xy 32.051815 -210.225126) (xy 32.083303 -210.303778) (xy 32.107171 -210.385068) (xy 32.123205 -210.468258)
			(xy 32.131258 -210.552595) (xy 32.131762 -210.594956) (xy 32.131258 -210.637317) (xy 32.123205 -210.721654)
			(xy 32.107171 -210.804844) (xy 32.083303 -210.886134) (xy 32.051815 -210.964786) (xy 32.012993 -211.040089)
			(xy 31.96719 -211.111361) (xy 31.914819 -211.177957) (xy 31.856354 -211.239272) (xy 31.792326 -211.294753)
			(xy 31.723314 -211.343896) (xy 31.649944 -211.386256) (xy 31.572879 -211.421451) (xy 31.492817 -211.44916)
			(xy 31.410484 -211.469134) (xy 31.326625 -211.481191) (xy 31.242 -211.485223) (xy 31.157375 -211.481191)
			(xy 31.073516 -211.469134) (xy 30.991183 -211.44916) (xy 30.911121 -211.421451) (xy 30.834056 -211.386256)
			(xy 30.760686 -211.343896) (xy 30.691674 -211.294753) (xy 30.627646 -211.239272) (xy 30.569181 -211.177957)
			(xy 30.51681 -211.111361) (xy 30.471007 -211.040089) (xy 30.432185 -210.964786) (xy 30.400697 -210.886134)
			(xy 30.376829 -210.804844) (xy 30.360795 -210.721654) (xy 30.352742 -210.637317) (xy 21.187361 -210.637317)
			(xy 21.186343 -210.642762) (xy 21.163847 -210.721829) (xy 21.134151 -210.798483) (xy 21.097509 -210.87207)
			(xy 21.054234 -210.941962) (xy 21.004694 -211.007563) (xy 20.949313 -211.068313) (xy 20.888563 -211.123694)
			(xy 20.822962 -211.173234) (xy 20.75307 -211.216509) (xy 20.679483 -211.253151) (xy 20.602829 -211.282847)
			(xy 20.523762 -211.305343) (xy 20.442957 -211.320448) (xy 20.361102 -211.328033) (xy 20.32 -211.328508)
			(xy 20.277374 -211.328032) (xy 20.19251 -211.319904) (xy 20.108813 -211.303692) (xy 20.027052 -211.279546)
			(xy 19.947976 -211.247687) (xy 19.872311 -211.208408) (xy 19.800752 -211.16207) (xy 19.767042 -211.135976)
			(xy 19.758192 -211.129547) (xy 19.736981 -211.124292) (xy 19.726148 -211.125816) (xy 19.685631 -211.132951)
			(xy 19.60371 -211.140583) (xy 19.562572 -211.141056) (xy 19.521492 -211.140598) (xy 19.439683 -211.133017)
			(xy 19.358923 -211.117921) (xy 19.279899 -211.095437) (xy 19.203288 -211.065757) (xy 19.129742 -211.029136)
			(xy 19.059888 -210.985884) (xy 18.994324 -210.936372) (xy 18.933607 -210.881022) (xy 18.878257 -210.820305)
			(xy 18.828745 -210.75474) (xy 18.785493 -210.684887) (xy 18.748872 -210.61134) (xy 18.719193 -210.534729)
			(xy 18.696709 -210.455706) (xy 18.681612 -210.374945) (xy 18.674032 -210.293136) (xy 18.673572 -210.252056)
			(xy 18.674149 -210.206906) (xy 18.6833 -210.117071) (xy 18.701515 -210.028627) (xy 18.728605 -209.942487)
			(xy 18.764291 -209.859537) (xy 18.808204 -209.780634) (xy 18.833592 -209.743294) (xy 18.839012 -209.734401)
			(xy 18.843033 -209.713991) (xy 18.83869 -209.693648) (xy 18.833084 -209.684874) (xy 18.810683 -209.652572)
			(xy 18.770969 -209.584728) (xy 18.737391 -209.513647) (xy 18.710212 -209.439881) (xy 18.689642 -209.364007)
			(xy 18.675842 -209.286614) (xy 18.668919 -209.208307) (xy 18.668492 -209.169) (xy 0.509016 -209.169)
			(xy 0.509016 -212.909912) (xy 42.741353 -212.909912) (xy 42.745331 -212.809919) (xy 42.757241 -212.710559)
			(xy 42.777008 -212.612458) (xy 42.804507 -212.516239) (xy 42.839563 -212.422508) (xy 42.881955 -212.331859)
			(xy 42.931416 -212.244865) (xy 42.987632 -212.162075) (xy 43.050248 -212.084013) (xy 43.118867 -212.011173)
			(xy 43.193058 -211.944015) (xy 43.272349 -211.882963) (xy 43.35624 -211.828405) (xy 43.444201 -211.780684)
			(xy 43.535675 -211.740102) (xy 43.630084 -211.706916) (xy 43.726831 -211.681336) (xy 43.825305 -211.663523)
			(xy 43.924883 -211.653591) (xy 44.024935 -211.651601) (xy 44.124829 -211.657567) (xy 44.223933 -211.671451)
			(xy 44.321621 -211.693164) (xy 44.417275 -211.72257) (xy 44.51029 -211.759483) (xy 44.600078 -211.803669)
			(xy 44.686072 -211.85485) (xy 44.767728 -211.9127) (xy 44.844529 -211.976856) (xy 44.915991 -212.04691)
			(xy 44.981661 -212.122421) (xy 45.041123 -212.202911) (xy 45.094003 -212.28787) (xy 45.139966 -212.376762)
			(xy 45.178721 -212.469025) (xy 45.210023 -212.564075) (xy 45.233675 -212.661312) (xy 45.249526 -212.760121)
			(xy 45.257476 -212.859876) (xy 45.257974 -212.909912) (xy 45.257476 -212.959948) (xy 45.249526 -213.059703)
			(xy 45.233675 -213.158512) (xy 45.210023 -213.255749) (xy 45.178721 -213.350799) (xy 45.139966 -213.443062)
			(xy 45.094003 -213.531954) (xy 45.041123 -213.616913) (xy 44.981661 -213.697403) (xy 44.915991 -213.772914)
			(xy 44.844529 -213.842968) (xy 44.767728 -213.907124) (xy 44.686072 -213.964974) (xy 44.600078 -214.016155)
			(xy 44.51029 -214.060341) (xy 44.417275 -214.097254) (xy 44.321621 -214.12666) (xy 44.223933 -214.148373)
			(xy 44.124829 -214.162257) (xy 44.024935 -214.168223) (xy 43.924883 -214.166233) (xy 43.825305 -214.156301)
			(xy 43.726831 -214.138488) (xy 43.630084 -214.112908) (xy 43.535675 -214.079722) (xy 43.444201 -214.03914)
			(xy 43.35624 -213.991419) (xy 43.272349 -213.936861) (xy 43.193058 -213.875809) (xy 43.118867 -213.808651)
			(xy 43.050248 -213.735811) (xy 42.987632 -213.657749) (xy 42.931416 -213.574959) (xy 42.881955 -213.487965)
			(xy 42.839563 -213.397316) (xy 42.804507 -213.303585) (xy 42.777008 -213.207366) (xy 42.757241 -213.109265)
			(xy 42.745331 -213.009905) (xy 42.741353 -212.909912) (xy 0.509016 -212.909912) (xy 0.509016 -214.659661)
			(xy 20.446742 -214.659661) (xy 20.446742 -214.574939) (xy 20.454795 -214.490602) (xy 20.470829 -214.407412)
			(xy 20.494697 -214.326122) (xy 20.526185 -214.24747) (xy 20.565007 -214.172167) (xy 20.61081 -214.100895)
			(xy 20.663181 -214.034299) (xy 20.721646 -213.972984) (xy 20.785674 -213.917503) (xy 20.854686 -213.86836)
			(xy 20.928056 -213.826) (xy 21.005121 -213.790805) (xy 21.085183 -213.763096) (xy 21.167516 -213.743122)
			(xy 21.251375 -213.731065) (xy 21.336 -213.727034) (xy 21.420625 -213.731065) (xy 21.504484 -213.743122)
			(xy 21.586817 -213.763096) (xy 21.666879 -213.790805) (xy 21.743944 -213.826) (xy 21.817314 -213.86836)
			(xy 21.886326 -213.917503) (xy 21.950354 -213.972984) (xy 22.008819 -214.034299) (xy 22.06119 -214.100895)
			(xy 22.106993 -214.172167) (xy 22.145815 -214.24747) (xy 22.177303 -214.326122) (xy 22.201171 -214.407412)
			(xy 22.217205 -214.490602) (xy 22.225258 -214.574939) (xy 22.225762 -214.6173) (xy 22.225258 -214.659661)
			(xy 22.217205 -214.743998) (xy 22.201171 -214.827188) (xy 22.177303 -214.908478) (xy 22.145815 -214.98713)
			(xy 22.106993 -215.062433) (xy 22.06119 -215.133705) (xy 22.008819 -215.200301) (xy 21.950354 -215.261616)
			(xy 21.886326 -215.317097) (xy 21.817314 -215.36624) (xy 21.743944 -215.4086) (xy 21.666879 -215.443795)
			(xy 21.586817 -215.471504) (xy 21.504484 -215.491478) (xy 21.420625 -215.503535) (xy 21.336 -215.507567)
			(xy 21.251375 -215.503535) (xy 21.167516 -215.491478) (xy 21.085183 -215.471504) (xy 21.005121 -215.443795)
			(xy 20.928056 -215.4086) (xy 20.854686 -215.36624) (xy 20.785674 -215.317097) (xy 20.721646 -215.261616)
			(xy 20.663181 -215.200301) (xy 20.61081 -215.133705) (xy 20.565007 -215.062433) (xy 20.526185 -214.98713)
			(xy 20.494697 -214.908478) (xy 20.470829 -214.827188) (xy 20.454795 -214.743998) (xy 20.446742 -214.659661)
			(xy 0.509016 -214.659661) (xy 0.509016 -216.577361) (xy 18.287742 -216.577361) (xy 18.287742 -216.492639)
			(xy 18.295795 -216.408302) (xy 18.311829 -216.325112) (xy 18.335697 -216.243822) (xy 18.367185 -216.16517)
			(xy 18.406007 -216.089867) (xy 18.45181 -216.018595) (xy 18.504181 -215.951999) (xy 18.562646 -215.890684)
			(xy 18.626674 -215.835203) (xy 18.695686 -215.78606) (xy 18.769056 -215.7437) (xy 18.846121 -215.708505)
			(xy 18.926183 -215.680796) (xy 19.008516 -215.660822) (xy 19.092375 -215.648765) (xy 19.177 -215.644734)
			(xy 19.261625 -215.648765) (xy 19.345484 -215.660822) (xy 19.427817 -215.680796) (xy 19.507879 -215.708505)
			(xy 19.584944 -215.7437) (xy 19.658314 -215.78606) (xy 19.727326 -215.835203) (xy 19.791354 -215.890684)
			(xy 19.849819 -215.951999) (xy 19.90219 -216.018595) (xy 19.947993 -216.089867) (xy 19.986815 -216.16517)
			(xy 20.018303 -216.243822) (xy 20.042171 -216.325112) (xy 20.058205 -216.408302) (xy 20.066258 -216.492639)
			(xy 20.066762 -216.535) (xy 20.066258 -216.577361) (xy 20.058205 -216.661698) (xy 20.042171 -216.744888)
			(xy 20.018303 -216.826178) (xy 19.986815 -216.90483) (xy 19.947993 -216.980133) (xy 19.90219 -217.051405)
			(xy 19.849819 -217.118001) (xy 19.791354 -217.179316) (xy 19.727326 -217.234797) (xy 19.658314 -217.28394)
			(xy 19.584944 -217.3263) (xy 19.507879 -217.361495) (xy 19.427817 -217.389204) (xy 19.345484 -217.409178)
			(xy 19.261625 -217.421235) (xy 19.177 -217.425267) (xy 19.092375 -217.421235) (xy 19.008516 -217.409178)
			(xy 18.926183 -217.389204) (xy 18.846121 -217.361495) (xy 18.769056 -217.3263) (xy 18.695686 -217.28394)
			(xy 18.626674 -217.234797) (xy 18.562646 -217.179316) (xy 18.504181 -217.118001) (xy 18.45181 -217.051405)
			(xy 18.406007 -216.980133) (xy 18.367185 -216.90483) (xy 18.335697 -216.826178) (xy 18.311829 -216.744888)
			(xy 18.295795 -216.661698) (xy 18.287742 -216.577361) (xy 0.509016 -216.577361) (xy 0.509016 -219.117361)
			(xy 2.539742 -219.117361) (xy 2.539742 -219.032639) (xy 2.547795 -218.948302) (xy 2.563829 -218.865112)
			(xy 2.587697 -218.783822) (xy 2.619185 -218.70517) (xy 2.658007 -218.629867) (xy 2.70381 -218.558595)
			(xy 2.756181 -218.491999) (xy 2.814646 -218.430684) (xy 2.878674 -218.375203) (xy 2.947686 -218.32606)
			(xy 3.021056 -218.2837) (xy 3.098121 -218.248505) (xy 3.178183 -218.220796) (xy 3.260516 -218.200822)
			(xy 3.344375 -218.188765) (xy 3.429 -218.184734) (xy 3.513625 -218.188765) (xy 3.597484 -218.200822)
			(xy 3.679817 -218.220796) (xy 3.759879 -218.248505) (xy 3.836944 -218.2837) (xy 3.910314 -218.32606)
			(xy 3.979326 -218.375203) (xy 4.043354 -218.430684) (xy 4.101819 -218.491999) (xy 4.15419 -218.558595)
			(xy 4.199993 -218.629867) (xy 4.238815 -218.70517) (xy 4.270303 -218.783822) (xy 4.294171 -218.865112)
			(xy 4.310205 -218.948302) (xy 4.318258 -219.032639) (xy 4.318762 -219.075) (xy 4.318258 -219.117361)
			(xy 4.310205 -219.201698) (xy 4.294171 -219.284888) (xy 4.270303 -219.366178) (xy 4.238815 -219.44483)
			(xy 4.199993 -219.520133) (xy 4.15419 -219.591405) (xy 4.101819 -219.658001) (xy 4.043354 -219.719316)
			(xy 3.979326 -219.774797) (xy 3.910314 -219.82394) (xy 3.836944 -219.8663) (xy 3.759879 -219.901495)
			(xy 3.679817 -219.929204) (xy 3.597484 -219.949178) (xy 3.513625 -219.961235) (xy 3.429 -219.965267)
			(xy 3.344375 -219.961235) (xy 3.260516 -219.949178) (xy 3.178183 -219.929204) (xy 3.098121 -219.901495)
			(xy 3.021056 -219.8663) (xy 2.947686 -219.82394) (xy 2.878674 -219.774797) (xy 2.814646 -219.719316)
			(xy 2.756181 -219.658001) (xy 2.70381 -219.591405) (xy 2.658007 -219.520133) (xy 2.619185 -219.44483)
			(xy 2.587697 -219.366178) (xy 2.563829 -219.284888) (xy 2.547795 -219.201698) (xy 2.539742 -219.117361)
			(xy 0.509016 -219.117361) (xy 0.509016 -224.38741) (xy 11.380724 -224.38741) (xy 11.381308 -224.341014)
			(xy 11.390952 -224.248726) (xy 11.410148 -224.157942) (xy 11.438686 -224.069649) (xy 11.456924 -224.026984)
			(xy 11.460722 -224.01704) (xy 11.460725 -223.995778) (xy 11.456924 -223.985836) (xy 11.438684 -223.943172)
			(xy 11.410139 -223.85488) (xy 11.390944 -223.764096) (xy 11.381309 -223.671806) (xy 11.380724 -223.62541)
			(xy 11.381308 -223.579014) (xy 11.390952 -223.486726) (xy 11.410148 -223.395942) (xy 11.438686 -223.307649)
			(xy 11.456924 -223.264984) (xy 11.460722 -223.25504) (xy 11.460725 -223.233778) (xy 11.456924 -223.223836)
			(xy 11.438684 -223.181172) (xy 11.410139 -223.09288) (xy 11.390944 -223.002096) (xy 11.381309 -222.909806)
			(xy 11.380724 -222.86341) (xy 11.381222 -222.822304) (xy 11.388805 -222.740442) (xy 11.403908 -222.659629)
			(xy 11.426402 -222.580553) (xy 11.456094 -222.50389) (xy 11.492732 -222.430293) (xy 11.536004 -222.36039)
			(xy 11.585539 -222.294777) (xy 11.640916 -222.234013) (xy 11.701663 -222.178617) (xy 11.767261 -222.129061)
			(xy 11.83715 -222.085768) (xy 11.910736 -222.049106) (xy 11.98739 -222.01939) (xy 12.066458 -221.996872)
			(xy 12.147266 -221.981744) (xy 12.229126 -221.974135) (xy 12.270232 -221.973648) (xy 12.308522 -221.974043)
			(xy 12.384816 -221.980654) (xy 12.460259 -221.993806) (xy 12.53429 -222.013402) (xy 12.57046 -222.025972)
			(xy 12.578897 -222.028623) (xy 12.596567 -222.028623) (xy 12.605004 -222.025972) (xy 12.641177 -222.013416)
			(xy 12.715212 -221.993846) (xy 12.790653 -221.980703) (xy 12.866944 -221.974082) (xy 12.905232 -221.973648)
			(xy 12.946343 -221.974111) (xy 13.028213 -221.981698) (xy 13.109033 -221.996809) (xy 13.188115 -222.019314)
			(xy 13.264781 -222.049021) (xy 13.33838 -222.085677) (xy 13.408281 -222.128967) (xy 13.473889 -222.178524)
			(xy 13.534644 -222.233924) (xy 13.590027 -222.294695) (xy 13.639565 -222.360317) (xy 13.682836 -222.430231)
			(xy 13.719471 -222.503839) (xy 13.749156 -222.580515) (xy 13.771638 -222.659602) (xy 13.786726 -222.740427)
			(xy 13.794291 -222.822299) (xy 13.79474 -222.86341) (xy 13.794166 -222.909806) (xy 13.78452 -223.002095)
			(xy 13.765321 -223.092879) (xy 13.73678 -223.181172) (xy 13.71854 -223.223836) (xy 13.714727 -223.233776)
			(xy 13.714731 -223.255042) (xy 13.71854 -223.264984) (xy 13.73679 -223.307644) (xy 13.765332 -223.395937)
			(xy 13.784524 -223.486723) (xy 13.794156 -223.579014) (xy 13.79474 -223.62541) (xy 13.794166 -223.671806)
			(xy 13.78452 -223.764095) (xy 13.765321 -223.854879) (xy 13.73678 -223.943172) (xy 13.71854 -223.985836)
			(xy 13.714727 -223.995776) (xy 13.714731 -224.017042) (xy 13.71854 -224.026984) (xy 13.73679 -224.069644)
			(xy 13.765332 -224.157937) (xy 13.784524 -224.248723) (xy 13.794156 -224.341014) (xy 13.79474 -224.38741)
			(xy 13.794297 -224.428518) (xy 13.786712 -224.510382) (xy 13.771606 -224.591198) (xy 13.74911 -224.670275)
			(xy 13.719414 -224.74694) (xy 13.682773 -224.820538) (xy 13.639498 -224.890443) (xy 13.589959 -224.956057)
			(xy 13.534578 -225.016821) (xy 13.473828 -225.072217) (xy 13.408226 -225.121773) (xy 13.338333 -225.165065)
			(xy 13.264743 -225.201725) (xy 13.188086 -225.231439) (xy 13.109014 -225.253955) (xy 13.028202 -225.269081)
			(xy 12.946339 -225.276687) (xy 12.905232 -225.277172) (xy 12.866942 -225.276757) (xy 12.790648 -225.270152)
			(xy 12.715206 -225.257005) (xy 12.641175 -225.237415) (xy 12.605004 -225.224848) (xy 12.596567 -225.222197)
			(xy 12.578897 -225.222197) (xy 12.57046 -225.224848) (xy 12.534281 -225.237387) (xy 12.460248 -225.256961)
			(xy 12.384809 -225.270109) (xy 12.30852 -225.276735) (xy 12.270232 -225.277172) (xy 12.229122 -225.276706)
			(xy 12.147251 -225.269118) (xy 12.066431 -225.254007) (xy 11.98735 -225.231503) (xy 11.910683 -225.201796)
			(xy 11.837085 -225.165141) (xy 11.767183 -225.121851) (xy 11.701575 -225.072294) (xy 11.64082 -225.016894)
			(xy 11.585437 -224.956124) (xy 11.535899 -224.890502) (xy 11.492628 -224.820589) (xy 11.455993 -224.74698)
			(xy 11.426308 -224.670305) (xy 11.403826 -224.591218) (xy 11.388738 -224.510393) (xy 11.381173 -224.428521)
			(xy 11.380724 -224.38741) (xy 0.509016 -224.38741) (xy 0.509016 -227.61321) (xy 37.175948 -227.61321)
			(xy 37.17653 -227.566814) (xy 37.186174 -227.474526) (xy 37.20537 -227.383742) (xy 37.23391 -227.295449)
			(xy 37.252148 -227.252784) (xy 37.25595 -227.24284) (xy 37.255954 -227.221578) (xy 37.252148 -227.211636)
			(xy 37.23391 -227.168971) (xy 37.205363 -227.08068) (xy 37.186168 -226.989896) (xy 37.176533 -226.897606)
			(xy 37.175948 -226.85121) (xy 37.17653 -226.804814) (xy 37.186174 -226.712526) (xy 37.20537 -226.621742)
			(xy 37.23391 -226.533449) (xy 37.252148 -226.490784) (xy 37.25595 -226.48084) (xy 37.255954 -226.459578)
			(xy 37.252148 -226.449636) (xy 37.23391 -226.406971) (xy 37.205363 -226.31868) (xy 37.186168 -226.227896)
			(xy 37.176533 -226.135606) (xy 37.175948 -226.08921) (xy 37.176422 -226.048103) (xy 37.184006 -225.96624)
			(xy 37.199109 -225.885425) (xy 37.221603 -225.806349) (xy 37.251297 -225.729684) (xy 37.287936 -225.656086)
			(xy 37.331209 -225.586182) (xy 37.380746 -225.520568) (xy 37.436125 -225.459804) (xy 37.496873 -225.404408)
			(xy 37.562473 -225.354852) (xy 37.632364 -225.31156) (xy 37.705952 -225.274899) (xy 37.782608 -225.245184)
			(xy 37.861678 -225.222667) (xy 37.942488 -225.207541) (xy 38.024349 -225.199934) (xy 38.065456 -225.199448)
			(xy 38.103746 -225.199866) (xy 38.180039 -225.20647) (xy 38.255482 -225.219616) (xy 38.329513 -225.239206)
			(xy 38.365684 -225.251772) (xy 38.374121 -225.254423) (xy 38.391791 -225.254423) (xy 38.400228 -225.251772)
			(xy 38.436409 -225.239237) (xy 38.51044 -225.219662) (xy 38.585879 -225.206512) (xy 38.662168 -225.199885)
			(xy 38.700456 -225.199448) (xy 38.741565 -225.199994) (xy 38.823431 -225.207578) (xy 38.904249 -225.222684)
			(xy 38.983327 -225.245184) (xy 39.059992 -225.274885) (xy 39.133589 -225.311535) (xy 39.203489 -225.354821)
			(xy 39.269096 -225.404372) (xy 39.329851 -225.459767) (xy 39.385234 -225.520531) (xy 39.434773 -225.586148)
			(xy 39.478046 -225.656056) (xy 39.514682 -225.72966) (xy 39.544369 -225.80633) (xy 39.566854 -225.885413)
			(xy 39.581945 -225.966233) (xy 39.589513 -226.048101) (xy 39.589964 -226.08921) (xy 39.589388 -226.135606)
			(xy 39.579742 -226.227895) (xy 39.560544 -226.318678) (xy 39.532003 -226.406972) (xy 39.513764 -226.449636)
			(xy 39.50995 -226.459576) (xy 39.509953 -226.480842) (xy 39.513764 -226.490784) (xy 39.532009 -226.533446)
			(xy 39.560554 -226.621738) (xy 39.579747 -226.712523) (xy 39.58938 -226.804814) (xy 39.589964 -226.85121)
			(xy 39.589388 -226.897606) (xy 39.579742 -226.989895) (xy 39.560544 -227.080678) (xy 39.532003 -227.168972)
			(xy 39.513764 -227.211636) (xy 39.50995 -227.221576) (xy 39.509953 -227.242842) (xy 39.513764 -227.252784)
			(xy 39.532009 -227.295446) (xy 39.560554 -227.383738) (xy 39.579747 -227.474523) (xy 39.58938 -227.566814)
			(xy 39.589964 -227.61321) (xy 39.589497 -227.654317) (xy 39.581912 -227.73618) (xy 39.566807 -227.816994)
			(xy 39.544311 -227.89607) (xy 39.514617 -227.972734) (xy 39.477977 -228.046332) (xy 39.434703 -228.116235)
			(xy 39.385166 -228.181849) (xy 39.329787 -228.242613) (xy 39.269038 -228.298009) (xy 39.203438 -228.347564)
			(xy 39.133547 -228.390857) (xy 39.059959 -228.427518) (xy 38.983304 -228.457233) (xy 38.904234 -228.479751)
			(xy 38.823424 -228.494878) (xy 38.741563 -228.502486) (xy 38.700456 -228.502972) (xy 38.662167 -228.50255)
			(xy 38.585873 -228.495947) (xy 38.51043 -228.482802) (xy 38.436399 -228.463214) (xy 38.400228 -228.450648)
			(xy 38.391791 -228.447997) (xy 38.374121 -228.447997) (xy 38.365684 -228.450648) (xy 38.329503 -228.46318)
			(xy 38.255471 -228.482756) (xy 38.180032 -228.495906) (xy 38.103744 -228.502534) (xy 38.065456 -228.502972)
			(xy 38.024344 -228.502589) (xy 37.94247 -228.494997) (xy 37.861646 -228.479882) (xy 37.782563 -228.457372)
			(xy 37.705894 -228.42766) (xy 37.632294 -228.391) (xy 37.562391 -228.347704) (xy 37.496782 -228.298142)
			(xy 37.436027 -228.242736) (xy 37.380645 -228.18196) (xy 37.331107 -228.116333) (xy 37.287837 -228.046414)
			(xy 37.251205 -227.972801) (xy 37.221522 -227.89612) (xy 37.199042 -227.817028) (xy 37.183957 -227.736199)
			(xy 37.176395 -227.654323) (xy 37.175948 -227.61321) (xy 0.509016 -227.61321) (xy 0.509016 -230.439214)
			(xy 7.371588 -230.439214) (xy 7.372184 -230.392811) (xy 7.381883 -230.300513) (xy 7.401145 -230.209727)
			(xy 7.429762 -230.121443) (xy 7.448042 -230.078788) (xy 7.451842 -230.068844) (xy 7.451847 -230.047582)
			(xy 7.448042 -230.03764) (xy 7.429785 -229.994977) (xy 7.40119 -229.90669) (xy 7.381932 -229.815908)
			(xy 7.372218 -229.723615) (xy 7.371588 -229.677214) (xy 7.372092 -229.634853) (xy 7.380145 -229.550516)
			(xy 7.396179 -229.467326) (xy 7.420047 -229.386036) (xy 7.451535 -229.307384) (xy 7.490357 -229.232081)
			(xy 7.53616 -229.160809) (xy 7.588531 -229.094213) (xy 7.646996 -229.032898) (xy 7.711024 -228.977417)
			(xy 7.780036 -228.928274) (xy 7.853406 -228.885914) (xy 7.930471 -228.850719) (xy 8.010533 -228.82301)
			(xy 8.092866 -228.803036) (xy 8.176725 -228.790979) (xy 8.26135 -228.786948) (xy 8.345975 -228.790979)
			(xy 8.429834 -228.803036) (xy 8.512167 -228.82301) (xy 8.592229 -228.850719) (xy 8.669294 -228.885914)
			(xy 8.742664 -228.928274) (xy 8.811676 -228.977417) (xy 8.875704 -229.032898) (xy 8.934169 -229.094213)
			(xy 8.98654 -229.160809) (xy 9.032343 -229.232081) (xy 9.071165 -229.307384) (xy 9.102653 -229.386036)
			(xy 9.126521 -229.467326) (xy 9.142555 -229.550516) (xy 9.150608 -229.634853) (xy 9.151112 -229.677214)
			(xy 9.150491 -229.723616) (xy 9.140799 -229.815914) (xy 9.121544 -229.906699) (xy 9.092935 -229.994984)
			(xy 9.074658 -230.03764) (xy 9.070842 -230.047579) (xy 9.070847 -230.068846) (xy 9.074658 -230.078788)
			(xy 9.092924 -230.121447) (xy 9.121516 -230.209736) (xy 9.140772 -230.300519) (xy 9.150484 -230.392813)
			(xy 9.151112 -230.439214) (xy 9.150608 -230.481575) (xy 9.142555 -230.565912) (xy 9.126521 -230.649102)
			(xy 9.102653 -230.730392) (xy 9.071165 -230.809044) (xy 9.032343 -230.884347) (xy 8.98654 -230.955619)
			(xy 8.934169 -231.022215) (xy 8.875704 -231.08353) (xy 8.811676 -231.139011) (xy 8.742664 -231.188154)
			(xy 8.669294 -231.230514) (xy 8.592229 -231.265709) (xy 8.512167 -231.293418) (xy 8.429834 -231.313392)
			(xy 8.345975 -231.325449) (xy 8.26135 -231.329481) (xy 8.176725 -231.325449) (xy 8.092866 -231.313392)
			(xy 8.010533 -231.293418) (xy 7.930471 -231.265709) (xy 7.853406 -231.230514) (xy 7.780036 -231.188154)
			(xy 7.711024 -231.139011) (xy 7.646996 -231.08353) (xy 7.588531 -231.022215) (xy 7.53616 -230.955619)
			(xy 7.490357 -230.884347) (xy 7.451535 -230.809044) (xy 7.420047 -230.730392) (xy 7.396179 -230.649102)
			(xy 7.380145 -230.565912) (xy 7.372092 -230.481575) (xy 7.371588 -230.439214) (xy 0.509016 -230.439214)
			(xy 0.509016 -235.773214) (xy 7.396988 -235.773214) (xy 7.397584 -235.726811) (xy 7.407283 -235.634513)
			(xy 7.426545 -235.543727) (xy 7.455162 -235.455443) (xy 7.473442 -235.412788) (xy 7.477242 -235.402844)
			(xy 7.477247 -235.381582) (xy 7.473442 -235.37164) (xy 7.455185 -235.328977) (xy 7.42659 -235.24069)
			(xy 7.407332 -235.149908) (xy 7.397618 -235.057615) (xy 7.396988 -235.011214) (xy 7.397531 -234.967564)
			(xy 7.406089 -234.880683) (xy 7.423114 -234.795059) (xy 7.448444 -234.711514) (xy 7.481834 -234.63085)
			(xy 7.522962 -234.553845) (xy 7.571435 -234.481238) (xy 7.626786 -234.413727) (xy 7.688482 -234.351961)
			(xy 7.75593 -234.296534) (xy 7.828483 -234.247979) (xy 7.905442 -234.206764) (xy 7.986067 -234.173283)
			(xy 8.02767 -234.16006) (xy 8.043418 -234.155234) (xy 8.06323 -234.129326) (xy 8.066786 -234.00004)
			(xy 8.048498 -233.973116) (xy 8.033004 -233.967528) (xy 7.993889 -233.952766) (xy 7.918359 -233.916908)
			(xy 7.846527 -233.874123) (xy 7.779025 -233.824787) (xy 7.716449 -233.769336) (xy 7.659352 -233.708258)
			(xy 7.608237 -233.642093) (xy 7.563555 -233.571424) (xy 7.5257 -233.496875) (xy 7.495006 -233.419104)
			(xy 7.471744 -233.338795) (xy 7.456119 -233.256659) (xy 7.448269 -233.173419) (xy 7.447788 -233.131614)
			(xy 7.448384 -233.085211) (xy 7.458083 -232.992913) (xy 7.477345 -232.902127) (xy 7.505962 -232.813843)
			(xy 7.524242 -232.771188) (xy 7.528042 -232.761244) (xy 7.528047 -232.739982) (xy 7.524242 -232.73004)
			(xy 7.505985 -232.687377) (xy 7.47739 -232.59909) (xy 7.458132 -232.508308) (xy 7.448418 -232.416015)
			(xy 7.447788 -232.369614) (xy 7.448292 -232.327253) (xy 7.456345 -232.242916) (xy 7.472379 -232.159726)
			(xy 7.496247 -232.078436) (xy 7.527735 -231.999784) (xy 7.566557 -231.924481) (xy 7.61236 -231.853209)
			(xy 7.664731 -231.786613) (xy 7.723196 -231.725298) (xy 7.787224 -231.669817) (xy 7.856236 -231.620674)
			(xy 7.929606 -231.578314) (xy 8.006671 -231.543119) (xy 8.086733 -231.51541) (xy 8.169066 -231.495436)
			(xy 8.252925 -231.483379) (xy 8.33755 -231.479348) (xy 8.422175 -231.483379) (xy 8.506034 -231.495436)
			(xy 8.588367 -231.51541) (xy 8.668429 -231.543119) (xy 8.745494 -231.578314) (xy 8.818864 -231.620674)
			(xy 8.887876 -231.669817) (xy 8.951904 -231.725298) (xy 9.010369 -231.786613) (xy 9.06274 -231.853209)
			(xy 9.108543 -231.924481) (xy 9.147365 -231.999784) (xy 9.159062 -232.029) (xy 40.480996 -232.029)
			(xy 40.481621 -231.982598) (xy 40.491311 -231.8903) (xy 40.510566 -231.799515) (xy 40.539174 -231.71123)
			(xy 40.55745 -231.668574) (xy 40.561258 -231.658632) (xy 40.561258 -231.637368) (xy 40.55745 -231.627426)
			(xy 40.539189 -231.584765) (xy 40.510595 -231.496477) (xy 40.491338 -231.405694) (xy 40.481625 -231.313401)
			(xy 40.480996 -231.267) (xy 40.4815 -231.224639) (xy 40.489553 -231.140302) (xy 40.505587 -231.057112)
			(xy 40.529455 -230.975822) (xy 40.560943 -230.89717) (xy 40.599765 -230.821867) (xy 40.645568 -230.750595)
			(xy 40.697939 -230.683999) (xy 40.756404 -230.622684) (xy 40.820432 -230.567203) (xy 40.889444 -230.51806)
			(xy 40.962814 -230.4757) (xy 41.039879 -230.440505) (xy 41.119941 -230.412796) (xy 41.202274 -230.392822)
			(xy 41.286133 -230.380765) (xy 41.370758 -230.376734) (xy 41.455383 -230.380765) (xy 41.539242 -230.392822)
			(xy 41.621575 -230.412796) (xy 41.701637 -230.440505) (xy 41.778702 -230.4757) (xy 41.852072 -230.51806)
			(xy 41.921084 -230.567203) (xy 41.985112 -230.622684) (xy 42.043577 -230.683999) (xy 42.095948 -230.750595)
			(xy 42.141751 -230.821867) (xy 42.180573 -230.89717) (xy 42.212061 -230.975822) (xy 42.235929 -231.057112)
			(xy 42.251963 -231.140302) (xy 42.260016 -231.224639) (xy 42.26052 -231.267) (xy 42.259893 -231.313402)
			(xy 42.250203 -231.405699) (xy 42.23095 -231.496485) (xy 42.202342 -231.58477) (xy 42.184066 -231.627426)
			(xy 42.180257 -231.637368) (xy 42.180257 -231.658632) (xy 42.184066 -231.668574) (xy 42.202328 -231.711235)
			(xy 42.230921 -231.799523) (xy 42.250178 -231.890306) (xy 42.259891 -231.982599) (xy 42.26052 -232.029)
			(xy 42.260016 -232.071361) (xy 42.251963 -232.155698) (xy 42.235929 -232.238888) (xy 42.212061 -232.320178)
			(xy 42.180573 -232.39883) (xy 42.141751 -232.474133) (xy 42.095948 -232.545405) (xy 42.043577 -232.612001)
			(xy 41.985112 -232.673316) (xy 41.921084 -232.728797) (xy 41.852072 -232.77794) (xy 41.778702 -232.8203)
			(xy 41.701637 -232.855495) (xy 41.621575 -232.883204) (xy 41.539242 -232.903178) (xy 41.455383 -232.915235)
			(xy 41.370758 -232.919267) (xy 41.286133 -232.915235) (xy 41.202274 -232.903178) (xy 41.119941 -232.883204)
			(xy 41.039879 -232.855495) (xy 40.962814 -232.8203) (xy 40.889444 -232.77794) (xy 40.820432 -232.728797)
			(xy 40.756404 -232.673316) (xy 40.697939 -232.612001) (xy 40.645568 -232.545405) (xy 40.599765 -232.474133)
			(xy 40.560943 -232.39883) (xy 40.529455 -232.320178) (xy 40.505587 -232.238888) (xy 40.489553 -232.155698)
			(xy 40.4815 -232.071361) (xy 40.480996 -232.029) (xy 9.159062 -232.029) (xy 9.178853 -232.078436)
			(xy 9.202721 -232.159726) (xy 9.218755 -232.242916) (xy 9.226808 -232.327253) (xy 9.227312 -232.369614)
			(xy 9.226691 -232.416016) (xy 9.216999 -232.508314) (xy 9.197744 -232.599099) (xy 9.169135 -232.687384)
			(xy 9.150858 -232.73004) (xy 9.147042 -232.739979) (xy 9.147047 -232.761246) (xy 9.150858 -232.771188)
			(xy 9.169124 -232.813847) (xy 9.197716 -232.902136) (xy 9.216972 -232.992919) (xy 9.226684 -233.085213)
			(xy 9.227312 -233.131614) (xy 9.226795 -233.175265) (xy 9.218234 -233.262146) (xy 9.201206 -233.347771)
			(xy 9.175874 -233.431317) (xy 9.142482 -233.51198) (xy 9.10135 -233.588986) (xy 9.052876 -233.661593)
			(xy 8.997523 -233.729104) (xy 8.935825 -233.790869) (xy 8.868375 -233.846295) (xy 8.795821 -233.89485)
			(xy 8.71886 -233.936065) (xy 8.638233 -233.969545) (xy 8.59663 -233.982768) (xy 8.580882 -233.987594)
			(xy 8.56107 -234.013502) (xy 8.557514 -234.142788) (xy 8.575802 -234.169712) (xy 8.591296 -234.1753)
			(xy 8.630413 -234.190055) (xy 8.705944 -234.225913) (xy 8.777777 -234.268699) (xy 8.845279 -234.318036)
			(xy 8.907854 -234.373488) (xy 8.964951 -234.434566) (xy 9.016066 -234.500731) (xy 9.060748 -234.571401)
			(xy 9.098603 -234.64595) (xy 9.129296 -234.723723) (xy 9.152558 -234.804031) (xy 9.168182 -234.886168)
			(xy 9.176032 -234.969409) (xy 9.176512 -235.011214) (xy 9.175891 -235.057616) (xy 9.166199 -235.149914)
			(xy 9.146944 -235.240699) (xy 9.118335 -235.328984) (xy 9.100058 -235.37164) (xy 9.096242 -235.381579)
			(xy 9.096247 -235.402846) (xy 9.100058 -235.412788) (xy 9.118324 -235.455447) (xy 9.146916 -235.543736)
			(xy 9.166172 -235.634519) (xy 9.175884 -235.726813) (xy 9.176512 -235.773214) (xy 9.176008 -235.815575)
			(xy 9.167955 -235.899912) (xy 9.151921 -235.983102) (xy 9.128053 -236.064392) (xy 9.096565 -236.143044)
			(xy 9.057743 -236.218347) (xy 9.01194 -236.289619) (xy 8.959569 -236.356215) (xy 8.901104 -236.41753)
			(xy 8.837076 -236.473011) (xy 8.768064 -236.522154) (xy 8.694694 -236.564514) (xy 8.617629 -236.599709)
			(xy 8.537567 -236.627418) (xy 8.455234 -236.647392) (xy 8.371375 -236.659449) (xy 8.28675 -236.663481)
			(xy 8.202125 -236.659449) (xy 8.118266 -236.647392) (xy 8.035933 -236.627418) (xy 7.955871 -236.599709)
			(xy 7.878806 -236.564514) (xy 7.805436 -236.522154) (xy 7.736424 -236.473011) (xy 7.672396 -236.41753)
			(xy 7.613931 -236.356215) (xy 7.56156 -236.289619) (xy 7.515757 -236.218347) (xy 7.476935 -236.143044)
			(xy 7.445447 -236.064392) (xy 7.421579 -235.983102) (xy 7.405545 -235.899912) (xy 7.397492 -235.815575)
			(xy 7.396988 -235.773214) (xy 0.509016 -235.773214) (xy 0.509016 -238.20501) (xy 6.117336 -238.20501)
			(xy 6.11797 -238.158608) (xy 6.127658 -238.066311) (xy 6.14691 -237.975526) (xy 6.175516 -237.88724)
			(xy 6.19379 -237.844584) (xy 6.19759 -237.83464) (xy 6.197594 -237.813378) (xy 6.19379 -237.803436)
			(xy 6.175528 -237.760775) (xy 6.146936 -237.672487) (xy 6.127679 -237.581704) (xy 6.117965 -237.489411)
			(xy 6.117336 -237.44301) (xy 6.11784 -237.400649) (xy 6.125893 -237.316312) (xy 6.141927 -237.233122)
			(xy 6.165795 -237.151832) (xy 6.197283 -237.07318) (xy 6.236105 -236.997877) (xy 6.281908 -236.926605)
			(xy 6.334279 -236.860009) (xy 6.392744 -236.798694) (xy 6.456772 -236.743213) (xy 6.525784 -236.69407)
			(xy 6.599154 -236.65171) (xy 6.676219 -236.616515) (xy 6.756281 -236.588806) (xy 6.838614 -236.568832)
			(xy 6.922473 -236.556775) (xy 7.007098 -236.552744) (xy 7.091723 -236.556775) (xy 7.175582 -236.568832)
			(xy 7.257915 -236.588806) (xy 7.337977 -236.616515) (xy 7.415042 -236.65171) (xy 7.488412 -236.69407)
			(xy 7.557424 -236.743213) (xy 7.621452 -236.798694) (xy 7.679917 -236.860009) (xy 7.732288 -236.926605)
			(xy 7.778091 -236.997877) (xy 7.816913 -237.07318) (xy 7.848401 -237.151832) (xy 7.872269 -237.233122)
			(xy 7.888303 -237.316312) (xy 7.892761 -237.363) (xy 40.480996 -237.363) (xy 40.481621 -237.316598)
			(xy 40.491311 -237.2243) (xy 40.510566 -237.133515) (xy 40.539174 -237.04523) (xy 40.55745 -237.002574)
			(xy 40.561258 -236.992632) (xy 40.561258 -236.971368) (xy 40.55745 -236.961426) (xy 40.539189 -236.918765)
			(xy 40.510595 -236.830477) (xy 40.491338 -236.739694) (xy 40.481625 -236.647401) (xy 40.480996 -236.601)
			(xy 40.481468 -236.559748) (xy 40.489125 -236.477599) (xy 40.504354 -236.396513) (xy 40.527026 -236.317184)
			(xy 40.556944 -236.240295) (xy 40.593852 -236.166506) (xy 40.637433 -236.096451) (xy 40.687313 -236.030732)
			(xy 40.743063 -235.969913) (xy 40.804204 -235.914517) (xy 40.870211 -235.865019) (xy 40.940518 -235.821845)
			(xy 40.977312 -235.803186) (xy 40.985606 -235.798599) (xy 40.998363 -235.784607) (xy 41.005163 -235.766935)
			(xy 41.005506 -235.757466) (xy 41.005506 -235.666534) (xy 41.005102 -235.657069) (xy 40.998326 -235.639398)
			(xy 40.985608 -235.625383) (xy 40.977312 -235.620814) (xy 40.940537 -235.60212) (xy 40.870235 -235.558945)
			(xy 40.804231 -235.509448) (xy 40.743093 -235.454053) (xy 40.687345 -235.393236) (xy 40.637466 -235.327521)
			(xy 40.593884 -235.25747) (xy 40.556974 -235.183685) (xy 40.527053 -235.106801) (xy 40.504377 -235.027477)
			(xy 40.489141 -234.946395) (xy 40.481477 -234.864251) (xy 40.480996 -234.823) (xy 40.481621 -234.776598)
			(xy 40.491311 -234.6843) (xy 40.510566 -234.593515) (xy 40.539174 -234.50523) (xy 40.55745 -234.462574)
			(xy 40.561258 -234.452632) (xy 40.561258 -234.431368) (xy 40.55745 -234.421426) (xy 40.539189 -234.378765)
			(xy 40.510595 -234.290477) (xy 40.491338 -234.199694) (xy 40.481625 -234.107401) (xy 40.480996 -234.061)
			(xy 40.4815 -234.018639) (xy 40.489553 -233.934302) (xy 40.505587 -233.851112) (xy 40.529455 -233.769822)
			(xy 40.560943 -233.69117) (xy 40.599765 -233.615867) (xy 40.645568 -233.544595) (xy 40.697939 -233.477999)
			(xy 40.756404 -233.416684) (xy 40.820432 -233.361203) (xy 40.889444 -233.31206) (xy 40.962814 -233.2697)
			(xy 41.039879 -233.234505) (xy 41.119941 -233.206796) (xy 41.202274 -233.186822) (xy 41.286133 -233.174765)
			(xy 41.370758 -233.170734) (xy 41.455383 -233.174765) (xy 41.539242 -233.186822) (xy 41.621575 -233.206796)
			(xy 41.701637 -233.234505) (xy 41.778702 -233.2697) (xy 41.852072 -233.31206) (xy 41.921084 -233.361203)
			(xy 41.985112 -233.416684) (xy 42.043577 -233.477999) (xy 42.095948 -233.544595) (xy 42.141751 -233.615867)
			(xy 42.180573 -233.69117) (xy 42.212061 -233.769822) (xy 42.235929 -233.851112) (xy 42.251963 -233.934302)
			(xy 42.260016 -234.018639) (xy 42.26052 -234.061) (xy 42.259893 -234.107402) (xy 42.250203 -234.199699)
			(xy 42.23095 -234.290485) (xy 42.202342 -234.37877) (xy 42.184066 -234.421426) (xy 42.180257 -234.431368)
			(xy 42.180257 -234.452632) (xy 42.184066 -234.462574) (xy 42.202328 -234.505235) (xy 42.230921 -234.593523)
			(xy 42.250178 -234.684306) (xy 42.259891 -234.776599) (xy 42.26052 -234.823) (xy 42.260039 -234.864252)
			(xy 42.252382 -234.9464) (xy 42.237153 -235.027486) (xy 42.214483 -235.106814) (xy 42.184565 -235.183703)
			(xy 42.147658 -235.257492) (xy 42.104077 -235.327546) (xy 42.054198 -235.393266) (xy 41.998449 -235.454085)
			(xy 41.937309 -235.509482) (xy 41.871303 -235.55898) (xy 41.800998 -235.602155) (xy 41.764204 -235.620814)
			(xy 41.755914 -235.625406) (xy 41.743154 -235.639395) (xy 41.736353 -235.657065) (xy 41.73601 -235.666534)
			(xy 41.73601 -235.757466) (xy 41.736405 -235.766932) (xy 41.743184 -235.784604) (xy 41.755906 -235.798619)
			(xy 41.764204 -235.803186) (xy 41.800983 -235.821872) (xy 41.871285 -235.865049) (xy 41.937288 -235.914547)
			(xy 41.998426 -235.969943) (xy 42.054173 -236.03076) (xy 42.104052 -236.096477) (xy 42.147633 -236.166528)
			(xy 42.184542 -236.240313) (xy 42.214464 -236.317198) (xy 42.237139 -236.396522) (xy 42.252375 -236.477604)
			(xy 42.260039 -236.559749) (xy 42.26052 -236.601) (xy 42.259893 -236.647402) (xy 42.250203 -236.739699)
			(xy 42.23095 -236.830485) (xy 42.202342 -236.91877) (xy 42.184066 -236.961426) (xy 42.180257 -236.971368)
			(xy 42.180257 -236.992632) (xy 42.184066 -237.002574) (xy 42.202328 -237.045235) (xy 42.230921 -237.133523)
			(xy 42.250178 -237.224306) (xy 42.259891 -237.316599) (xy 42.26052 -237.363) (xy 42.260016 -237.405361)
			(xy 42.251963 -237.489698) (xy 42.235929 -237.572888) (xy 42.212061 -237.654178) (xy 42.180573 -237.73283)
			(xy 42.141751 -237.808133) (xy 42.095948 -237.879405) (xy 42.043577 -237.946001) (xy 41.985112 -238.007316)
			(xy 41.921084 -238.062797) (xy 41.852072 -238.11194) (xy 41.778702 -238.1543) (xy 41.701637 -238.189495)
			(xy 41.621575 -238.217204) (xy 41.539242 -238.237178) (xy 41.455383 -238.249235) (xy 41.370758 -238.253267)
			(xy 41.286133 -238.249235) (xy 41.202274 -238.237178) (xy 41.119941 -238.217204) (xy 41.039879 -238.189495)
			(xy 40.962814 -238.1543) (xy 40.889444 -238.11194) (xy 40.820432 -238.062797) (xy 40.756404 -238.007316)
			(xy 40.697939 -237.946001) (xy 40.645568 -237.879405) (xy 40.599765 -237.808133) (xy 40.560943 -237.73283)
			(xy 40.529455 -237.654178) (xy 40.505587 -237.572888) (xy 40.489553 -237.489698) (xy 40.4815 -237.405361)
			(xy 40.480996 -237.363) (xy 7.892761 -237.363) (xy 7.896356 -237.400649) (xy 7.89686 -237.44301)
			(xy 7.896234 -237.489412) (xy 7.886543 -237.581709) (xy 7.867289 -237.672495) (xy 7.838682 -237.76078)
			(xy 7.820406 -237.803436) (xy 7.816595 -237.813376) (xy 7.816599 -237.834642) (xy 7.820406 -237.844584)
			(xy 7.838674 -237.887242) (xy 7.867265 -237.975532) (xy 7.88652 -238.066315) (xy 7.896232 -238.158609)
			(xy 7.89686 -238.20501) (xy 7.896356 -238.247371) (xy 7.888303 -238.331708) (xy 7.872269 -238.414898)
			(xy 7.848401 -238.496188) (xy 7.816913 -238.57484) (xy 7.778091 -238.650143) (xy 7.732288 -238.721415)
			(xy 7.679917 -238.788011) (xy 7.621452 -238.849326) (xy 7.557424 -238.904807) (xy 7.488412 -238.95395)
			(xy 7.415042 -238.99631) (xy 7.337977 -239.031505) (xy 7.257915 -239.059214) (xy 7.175582 -239.079188)
			(xy 7.091723 -239.091245) (xy 7.007098 -239.095277) (xy 6.922473 -239.091245) (xy 6.838614 -239.079188)
			(xy 6.756281 -239.059214) (xy 6.676219 -239.031505) (xy 6.599154 -238.99631) (xy 6.525784 -238.95395)
			(xy 6.456772 -238.904807) (xy 6.392744 -238.849326) (xy 6.334279 -238.788011) (xy 6.281908 -238.721415)
			(xy 6.236105 -238.650143) (xy 6.197283 -238.57484) (xy 6.165795 -238.496188) (xy 6.141927 -238.414898)
			(xy 6.125893 -238.331708) (xy 6.11784 -238.247371) (xy 6.117336 -238.20501) (xy 0.509016 -238.20501)
			(xy 0.509016 -239.5474) (xy 41.827196 -239.5474) (xy 41.827821 -239.500998) (xy 41.837511 -239.4087)
			(xy 41.856766 -239.317915) (xy 41.885374 -239.22963) (xy 41.90365 -239.186974) (xy 41.907458 -239.177032)
			(xy 41.907458 -239.155768) (xy 41.90365 -239.145826) (xy 41.885389 -239.103165) (xy 41.856795 -239.014877)
			(xy 41.837538 -238.924094) (xy 41.827825 -238.831801) (xy 41.827196 -238.7854) (xy 41.8277 -238.743039)
			(xy 41.835753 -238.658702) (xy 41.851787 -238.575512) (xy 41.875655 -238.494222) (xy 41.907143 -238.41557)
			(xy 41.945965 -238.340267) (xy 41.991768 -238.268995) (xy 42.044139 -238.202399) (xy 42.102604 -238.141084)
			(xy 42.166632 -238.085603) (xy 42.235644 -238.03646) (xy 42.309014 -237.9941) (xy 42.386079 -237.958905)
			(xy 42.466141 -237.931196) (xy 42.548474 -237.911222) (xy 42.632333 -237.899165) (xy 42.716958 -237.895134)
			(xy 42.801583 -237.899165) (xy 42.885442 -237.911222) (xy 42.967775 -237.931196) (xy 43.047837 -237.958905)
			(xy 43.124902 -237.9941) (xy 43.198272 -238.03646) (xy 43.267284 -238.085603) (xy 43.331312 -238.141084)
			(xy 43.389777 -238.202399) (xy 43.442148 -238.268995) (xy 43.487951 -238.340267) (xy 43.526773 -238.41557)
			(xy 43.558261 -238.494222) (xy 43.582129 -238.575512) (xy 43.598163 -238.658702) (xy 43.606216 -238.743039)
			(xy 43.60672 -238.7854) (xy 43.606093 -238.831802) (xy 43.596403 -238.924099) (xy 43.57715 -239.014885)
			(xy 43.548542 -239.10317) (xy 43.530266 -239.145826) (xy 43.526457 -239.155768) (xy 43.526457 -239.177032)
			(xy 43.530266 -239.186974) (xy 43.548528 -239.229635) (xy 43.577121 -239.317923) (xy 43.596378 -239.408706)
			(xy 43.606091 -239.500999) (xy 43.60672 -239.5474) (xy 43.606216 -239.589761) (xy 43.598163 -239.674098)
			(xy 43.582129 -239.757288) (xy 43.558261 -239.838578) (xy 43.526773 -239.91723) (xy 43.487951 -239.992533)
			(xy 43.442148 -240.063805) (xy 43.389777 -240.130401) (xy 43.331312 -240.191716) (xy 43.267284 -240.247197)
			(xy 43.198272 -240.29634) (xy 43.124902 -240.3387) (xy 43.047837 -240.373895) (xy 42.967775 -240.401604)
			(xy 42.885442 -240.421578) (xy 42.801583 -240.433635) (xy 42.716958 -240.437667) (xy 42.632333 -240.433635)
			(xy 42.548474 -240.421578) (xy 42.466141 -240.401604) (xy 42.386079 -240.373895) (xy 42.309014 -240.3387)
			(xy 42.235644 -240.29634) (xy 42.166632 -240.247197) (xy 42.102604 -240.191716) (xy 42.044139 -240.130401)
			(xy 41.991768 -240.063805) (xy 41.945965 -239.992533) (xy 41.907143 -239.91723) (xy 41.875655 -239.838578)
			(xy 41.851787 -239.757288) (xy 41.835753 -239.674098) (xy 41.8277 -239.589761) (xy 41.827196 -239.5474)
			(xy 0.509016 -239.5474) (xy 0.509016 -243.513864) (xy 2.815336 -243.513864) (xy 2.81576 -243.475575)
			(xy 2.822363 -243.399281) (xy 2.835507 -243.323838) (xy 2.855095 -243.249807) (xy 2.86766 -243.213636)
			(xy 2.870329 -243.205204) (xy 2.870317 -243.187529) (xy 2.86766 -243.179092) (xy 2.855117 -243.142914)
			(xy 2.835544 -243.068881) (xy 2.822396 -242.993442) (xy 2.815772 -242.917152) (xy 2.815336 -242.878864)
			(xy 2.815796 -242.837753) (xy 2.823384 -242.755883) (xy 2.838494 -242.675062) (xy 2.860999 -242.59598)
			(xy 2.890706 -242.519313) (xy 2.927361 -242.445715) (xy 2.970652 -242.375813) (xy 3.020209 -242.310205)
			(xy 3.075609 -242.24945) (xy 3.13638 -242.194067) (xy 3.202003 -242.144528) (xy 3.271917 -242.101257)
			(xy 3.345526 -242.064623) (xy 3.422201 -242.034938) (xy 3.501289 -242.012456) (xy 3.582114 -241.997369)
			(xy 3.663987 -241.989805) (xy 3.705098 -241.989356) (xy 3.744024 -241.989768) (xy 3.821581 -241.996546)
			(xy 3.898248 -242.010077) (xy 3.97344 -242.030258) (xy 4.010152 -242.043204) (xy 4.018701 -242.045968)
			(xy 4.036655 -242.045968) (xy 4.045204 -242.043204) (xy 4.081915 -242.030252) (xy 4.157107 -242.010073)
			(xy 4.233775 -241.996541) (xy 4.311331 -241.98976) (xy 4.350258 -241.989356) (xy 4.389185 -241.98975)
			(xy 4.466742 -241.996534) (xy 4.543409 -242.01007) (xy 4.6186 -242.030255) (xy 4.655312 -242.043204)
			(xy 4.663861 -242.045968) (xy 4.681815 -242.045968) (xy 4.690364 -242.043204) (xy 4.727079 -242.030264)
			(xy 4.802269 -242.010081) (xy 4.878936 -241.996546) (xy 4.956492 -241.989762) (xy 4.995418 -241.989356)
			(xy 5.036525 -241.989834) (xy 5.118387 -241.997419) (xy 5.199201 -242.012522) (xy 5.278278 -242.035017)
			(xy 5.354941 -242.06471) (xy 5.428539 -242.10135) (xy 5.498442 -242.144622) (xy 5.564056 -242.194159)
			(xy 5.62482 -242.249538) (xy 5.680216 -242.310285) (xy 5.729772 -242.375885) (xy 5.773065 -242.445776)
			(xy 5.809725 -242.519363) (xy 5.839441 -242.596018) (xy 5.861959 -242.675087) (xy 5.877086 -242.755897)
			(xy 5.884694 -242.837757) (xy 5.88518 -242.878864) (xy 5.884763 -242.917154) (xy 5.878158 -242.993447)
			(xy 5.865012 -243.06889) (xy 5.845422 -243.142921) (xy 5.832856 -243.179092) (xy 5.830223 -243.187533)
			(xy 5.830211 -243.2052) (xy 5.832856 -243.213636) (xy 5.839714 -243.233448) (xy 5.84454 -243.247926)
			(xy 5.868162 -243.266722) (xy 5.991098 -243.277898) (xy 6.017768 -243.263674) (xy 6.025134 -243.250466)
			(xy 6.046357 -243.212807) (xy 6.095112 -243.141417) (xy 6.150562 -243.075093) (xy 6.212185 -243.014462)
			(xy 6.279399 -242.960095) (xy 6.35157 -242.912504) (xy 6.428018 -242.872139) (xy 6.508021 -242.839381)
			(xy 6.590824 -242.814539) (xy 6.675647 -242.797846) (xy 6.761689 -242.789461) (xy 6.804914 -242.788948)
			(xy 6.843846 -242.789385) (xy 6.921408 -242.796228) (xy 6.998076 -242.809824) (xy 7.073261 -242.830071)
			(xy 7.109968 -242.84305) (xy 7.118517 -242.845814) (xy 7.136471 -242.845814) (xy 7.14502 -242.84305)
			(xy 7.181726 -242.830069) (xy 7.256913 -242.809829) (xy 7.333581 -242.796233) (xy 7.411142 -242.789386)
			(xy 7.450074 -242.788948) (xy 7.489005 -242.789397) (xy 7.566568 -242.796236) (xy 7.643235 -242.809829)
			(xy 7.718421 -242.830072) (xy 7.755128 -242.84305) (xy 7.763677 -242.845814) (xy 7.781631 -242.845814)
			(xy 7.79018 -242.84305) (xy 7.82689 -242.83008) (xy 7.902075 -242.809837) (xy 7.978742 -242.796238)
			(xy 8.056303 -242.789388) (xy 8.095234 -242.788948) (xy 8.136013 -242.789411) (xy 8.217227 -242.796893)
			(xy 8.297415 -242.811775) (xy 8.375904 -242.833935) (xy 8.452036 -242.863185) (xy 8.525172 -242.899281)
			(xy 8.594697 -242.941918) (xy 8.660027 -242.99074) (xy 8.720615 -243.045336) (xy 8.775952 -243.105249)
			(xy 8.825574 -243.169974) (xy 8.869063 -243.238969) (xy 8.887968 -243.275104) (xy 8.895334 -243.289582)
			(xy 8.923782 -243.304568) (xy 9.051036 -243.28755) (xy 9.074658 -243.26596) (xy 9.07796 -243.249958)
			(xy 9.087414 -243.207692) (xy 9.113452 -243.125083) (xy 9.147396 -243.045396) (xy 9.188925 -242.969386)
			(xy 9.237644 -242.897772) (xy 9.293094 -242.831232) (xy 9.354748 -242.770397) (xy 9.422023 -242.715842)
			(xy 9.494283 -242.668084) (xy 9.570842 -242.627576) (xy 9.650975 -242.5947) (xy 9.733925 -242.569769)
			(xy 9.818905 -242.553018) (xy 9.90511 -242.544606) (xy 9.948418 -242.544092) (xy 9.994814 -242.544669)
			(xy 10.087102 -242.554315) (xy 10.177886 -242.573513) (xy 10.266179 -242.602053) (xy 10.308844 -242.620292)
			(xy 10.318786 -242.624098) (xy 10.34005 -242.624098) (xy 10.349992 -242.620292) (xy 10.392652 -242.602041)
			(xy 10.480945 -242.573499) (xy 10.571731 -242.554307) (xy 10.664022 -242.544676) (xy 10.710418 -242.544092)
			(xy 10.751224 -242.544561) (xy 10.832494 -242.552036) (xy 10.912738 -242.566922) (xy 10.991281 -242.589094)
			(xy 11.067464 -242.618366) (xy 11.140647 -242.654491) (xy 11.210213 -242.697166) (xy 11.27558 -242.746032)
			(xy 11.336197 -242.800678) (xy 11.364214 -242.83035) (xy 11.373612 -242.84051) (xy 11.398758 -242.848384)
			(xy 11.511026 -242.824508) (xy 11.530838 -242.806982) (xy 11.535156 -242.794028) (xy 11.549272 -242.753862)
			(xy 11.584191 -242.676207) (xy 11.626369 -242.602243) (xy 11.67542 -242.532648) (xy 11.730896 -242.468056)
			(xy 11.792289 -242.409061) (xy 11.859037 -242.3562) (xy 11.93053 -242.309958) (xy 12.006114 -242.270758)
			(xy 12.085097 -242.238958) (xy 12.166757 -242.21485) (xy 12.250347 -242.198653) (xy 12.335102 -242.190516)
			(xy 12.377674 -242.190016) (xy 12.418788 -242.190489) (xy 12.500666 -242.198077) (xy 12.581494 -242.213186)
			(xy 12.660584 -242.235689) (xy 12.737259 -242.265394) (xy 12.810867 -242.302047) (xy 12.880779 -242.345334)
			(xy 12.946399 -242.394888) (xy 13.007166 -242.450285) (xy 13.062563 -242.511053) (xy 13.112117 -242.576673)
			(xy 13.155404 -242.646585) (xy 13.192057 -242.720193) (xy 13.221761 -242.796868) (xy 13.244264 -242.875958)
			(xy 13.259374 -242.956786) (xy 13.266961 -243.038664) (xy 13.267436 -243.079778) (xy 13.267025 -243.118068)
			(xy 13.260419 -243.194362) (xy 13.247271 -243.269804) (xy 13.227679 -243.343835) (xy 13.215112 -243.380006)
			(xy 13.212473 -243.388446) (xy 13.212466 -243.406113) (xy 13.215112 -243.41455) (xy 13.227652 -243.450729)
			(xy 13.247226 -243.524761) (xy 13.260374 -243.600201) (xy 13.267 -243.67649) (xy 13.267436 -243.714778)
			(xy 13.266846 -243.759) (xy 13.258017 -243.847003) (xy 13.240503 -243.933696) (xy 13.214478 -244.018225)
			(xy 13.19784 -244.059202) (xy 13.194714 -244.067772) (xy 13.194063 -244.085991) (xy 13.19657 -244.094762)
			(xy 13.211007 -244.140085) (xy 13.231231 -244.233036) (xy 13.239913 -244.31371) (xy 34.233104 -244.31371)
			(xy 34.233494 -244.275426) (xy 34.240032 -244.199137) (xy 34.253113 -244.123695) (xy 34.272639 -244.049658)
			(xy 34.285174 -244.013482) (xy 34.287819 -244.005044) (xy 34.287822 -243.987375) (xy 34.285174 -243.978938)
			(xy 34.272652 -243.942758) (xy 34.253143 -243.868719) (xy 34.240062 -243.793278) (xy 34.233506 -243.716993)
			(xy 34.233104 -243.67871) (xy 34.233622 -243.637604) (xy 34.241205 -243.555744) (xy 34.256307 -243.474932)
			(xy 34.2788 -243.395857) (xy 34.308492 -243.319195) (xy 34.345129 -243.245599) (xy 34.388399 -243.175696)
			(xy 34.437933 -243.110083) (xy 34.493309 -243.04932) (xy 34.554054 -242.993924) (xy 34.61965 -242.944368)
			(xy 34.689538 -242.901074) (xy 34.763122 -242.864412) (xy 34.839775 -242.834695) (xy 34.918841 -242.812176)
			(xy 34.999648 -242.797046) (xy 35.081507 -242.789436) (xy 35.122612 -242.788948) (xy 35.161544 -242.789386)
			(xy 35.239106 -242.796228) (xy 35.315774 -242.809825) (xy 35.390959 -242.830071) (xy 35.427666 -242.84305)
			(xy 35.436215 -242.845814) (xy 35.454169 -242.845814) (xy 35.462718 -242.84305) (xy 35.499424 -242.830069)
			(xy 35.574611 -242.809829) (xy 35.651279 -242.796234) (xy 35.72884 -242.789386) (xy 35.767772 -242.788948)
			(xy 35.806703 -242.789398) (xy 35.884266 -242.796237) (xy 35.960933 -242.80983) (xy 36.036119 -242.830072)
			(xy 36.072826 -242.84305) (xy 36.081375 -242.845814) (xy 36.099329 -242.845814) (xy 36.107878 -242.84305)
			(xy 36.144588 -242.830081) (xy 36.219774 -242.809837) (xy 36.29644 -242.796239) (xy 36.374001 -242.789388)
			(xy 36.412932 -242.788948) (xy 36.454042 -242.789422) (xy 36.535911 -242.797012) (xy 36.616729 -242.812125)
			(xy 36.695809 -242.834631) (xy 36.733923 -242.8494) (xy 44.997624 -242.8494) (xy 44.998043 -242.809633)
			(xy 45.005083 -242.730411) (xy 45.01917 -242.652134) (xy 45.040191 -242.575428) (xy 45.067978 -242.500906)
			(xy 45.084746 -242.464844) (xy 45.089077 -242.454343) (xy 45.089077 -242.431657) (xy 45.084746 -242.421156)
			(xy 45.068005 -242.385083) (xy 45.040224 -242.31056) (xy 45.019201 -242.233857) (xy 45.005104 -242.155584)
			(xy 44.998046 -242.076366) (xy 44.997624 -242.0366) (xy 44.998052 -241.995496) (xy 45.005638 -241.913638)
			(xy 45.020744 -241.83283) (xy 45.043241 -241.75376) (xy 45.072939 -241.677104) (xy 45.109583 -241.603514)
			(xy 45.152861 -241.53362) (xy 45.202404 -241.468017) (xy 45.257788 -241.407265) (xy 45.318542 -241.351883)
			(xy 45.384146 -241.302343) (xy 45.454042 -241.259068) (xy 45.527633 -241.222426) (xy 45.604291 -241.192731)
			(xy 45.683361 -241.170236) (xy 45.76417 -241.155133) (xy 45.846028 -241.147551) (xy 45.887132 -241.147092)
			(xy 45.928456 -241.147551) (xy 46.010751 -241.155163) (xy 46.091986 -241.170375) (xy 46.17146 -241.193055)
			(xy 46.248489 -241.223009) (xy 46.285658 -241.241072) (xy 46.295718 -241.245566) (xy 46.317716 -241.24635)
			(xy 46.328076 -241.242596) (xy 46.369278 -241.225801) (xy 46.454293 -241.199539) (xy 46.541505 -241.181888)
			(xy 46.630042 -241.173025) (xy 46.674532 -241.172492) (xy 46.715492 -241.17292) (xy 46.797069 -241.180391)
			(xy 46.877612 -241.195338) (xy 46.956438 -241.217636) (xy 46.994826 -241.231928) (xy 47.004522 -241.235225)
			(xy 47.024976 -241.234552) (xy 47.03445 -241.230658) (xy 47.069871 -241.214574) (xy 47.142968 -241.187937)
			(xy 47.218112 -241.167784) (xy 47.294728 -241.154269) (xy 47.372232 -241.147496) (xy 47.411132 -241.147092)
			(xy 47.452235 -241.147536) (xy 47.53409 -241.155124) (xy 47.614896 -241.170232) (xy 47.693963 -241.192731)
			(xy 47.770617 -241.222429) (xy 47.844204 -241.259074) (xy 47.914096 -241.302351) (xy 47.979697 -241.351893)
			(xy 48.040447 -241.407276) (xy 48.095828 -241.468028) (xy 48.145367 -241.53363) (xy 48.188642 -241.603524)
			(xy 48.225284 -241.677112) (xy 48.254979 -241.753767) (xy 48.277476 -241.832835) (xy 48.292581 -241.913642)
			(xy 48.300165 -241.995497) (xy 48.30064 -242.0366) (xy 48.300225 -242.076368) (xy 48.293184 -242.15559)
			(xy 48.279097 -242.233866) (xy 48.258075 -242.310572) (xy 48.230286 -242.385094) (xy 48.213518 -242.421156)
			(xy 48.209183 -242.431657) (xy 48.209183 -242.454343) (xy 48.213518 -242.464844) (xy 48.230264 -242.500915)
			(xy 48.258043 -242.575438) (xy 48.279064 -242.652142) (xy 48.29316 -242.730415) (xy 48.300218 -242.809634)
			(xy 48.30064 -242.8494) (xy 48.300133 -242.890502) (xy 48.292549 -242.972354) (xy 48.277444 -243.053158)
			(xy 48.254949 -243.132223) (xy 48.225254 -243.208875) (xy 48.188614 -243.282461) (xy 48.145341 -243.352352)
			(xy 48.095803 -243.417952) (xy 48.040424 -243.478702) (xy 47.979677 -243.534083) (xy 47.914078 -243.583623)
			(xy 47.844189 -243.626899) (xy 47.770604 -243.663541) (xy 47.693953 -243.693239) (xy 47.614889 -243.715737)
			(xy 47.534086 -243.730844) (xy 47.452234 -243.738432) (xy 47.411132 -243.738908) (xy 47.370172 -243.738491)
			(xy 47.288594 -243.731017) (xy 47.208051 -243.716067) (xy 47.129226 -243.693765) (xy 47.090838 -243.679472)
			(xy 47.081132 -243.676212) (xy 47.060688 -243.676861) (xy 47.051214 -243.680742) (xy 47.015798 -243.696839)
			(xy 46.9427 -243.723473) (xy 46.867555 -243.743624) (xy 46.790937 -243.757135) (xy 46.713432 -243.763905)
			(xy 46.674532 -243.764308) (xy 46.633208 -243.763863) (xy 46.550912 -243.756248) (xy 46.469677 -243.741033)
			(xy 46.390203 -243.718349) (xy 46.313175 -243.688393) (xy 46.276006 -243.670328) (xy 46.265932 -243.665873)
			(xy 46.243947 -243.665065) (xy 46.233588 -243.668804) (xy 46.192391 -243.685611) (xy 46.107373 -243.71187)
			(xy 46.020161 -243.729517) (xy 45.931622 -243.738377) (xy 45.887132 -243.738908) (xy 45.846029 -243.738417)
			(xy 45.764175 -243.730835) (xy 45.683368 -243.715733) (xy 45.604301 -243.693238) (xy 45.527646 -243.663544)
			(xy 45.454058 -243.626904) (xy 45.384164 -243.58363) (xy 45.318562 -243.534092) (xy 45.257811 -243.478712)
			(xy 45.202428 -243.417962) (xy 45.152888 -243.352362) (xy 45.109611 -243.28247) (xy 45.072968 -243.208884)
			(xy 45.043272 -243.13223) (xy 45.020775 -243.053163) (xy 45.005669 -242.972357) (xy 44.998084 -242.890503)
			(xy 44.997624 -242.8494) (xy 36.733923 -242.8494) (xy 36.772474 -242.864338) (xy 36.846071 -242.900994)
			(xy 36.915971 -242.944284) (xy 36.981578 -242.993841) (xy 37.042332 -243.04924) (xy 37.097714 -243.110009)
			(xy 37.147252 -243.175629) (xy 37.190524 -243.245541) (xy 37.227159 -243.319147) (xy 37.256846 -243.395821)
			(xy 37.279331 -243.474906) (xy 37.294421 -243.555729) (xy 37.301989 -243.6376) (xy 37.30244 -243.67871)
			(xy 37.302053 -243.716994) (xy 37.295514 -243.793283) (xy 37.282432 -243.868725) (xy 37.262905 -243.942762)
			(xy 37.25037 -243.978938) (xy 37.247713 -243.987373) (xy 37.247717 -244.005045) (xy 37.25037 -244.013482)
			(xy 37.262871 -244.049668) (xy 37.282385 -244.123705) (xy 37.295472 -244.199144) (xy 37.302035 -244.275427)
			(xy 37.30244 -244.31371) (xy 37.301997 -244.354818) (xy 37.294412 -244.436682) (xy 37.279306 -244.517498)
			(xy 37.25681 -244.596575) (xy 37.227114 -244.67324) (xy 37.190473 -244.746838) (xy 37.147198 -244.816743)
			(xy 37.097659 -244.882357) (xy 37.042278 -244.943121) (xy 36.981528 -244.998517) (xy 36.915926 -245.048073)
			(xy 36.846033 -245.091365) (xy 36.801488 -245.113556) (xy 37.48532 -245.113556) (xy 37.485699 -245.075271)
			(xy 37.492241 -244.998983) (xy 37.505325 -244.92354) (xy 37.524854 -244.849504) (xy 37.53739 -244.813328)
			(xy 37.540061 -244.804897) (xy 37.540047 -244.787221) (xy 37.53739 -244.778784) (xy 37.524882 -244.7426)
			(xy 37.505369 -244.668562) (xy 37.492284 -244.593123) (xy 37.485724 -244.516839) (xy 37.48532 -244.478556)
			(xy 37.485725 -244.437452) (xy 37.493314 -244.355595) (xy 37.508423 -244.274787) (xy 37.530924 -244.195718)
			(xy 37.560625 -244.119063) (xy 37.597271 -244.045475) (xy 37.640551 -243.975582) (xy 37.690096 -243.909981)
			(xy 37.745481 -243.84923) (xy 37.806236 -243.79385) (xy 37.871841 -243.744311) (xy 37.941738 -243.701036)
			(xy 38.015329 -243.664396) (xy 38.091987 -243.634701) (xy 38.171057 -243.612207) (xy 38.251866 -243.597104)
			(xy 38.333724 -243.589521) (xy 38.374828 -243.589048) (xy 38.413754 -243.589452) (xy 38.491311 -243.596232)
			(xy 38.567979 -243.609766) (xy 38.64317 -243.629948) (xy 38.679882 -243.642896) (xy 38.688431 -243.64566)
			(xy 38.706385 -243.64566) (xy 38.714934 -243.642896) (xy 38.751642 -243.629935) (xy 38.826835 -243.609758)
			(xy 38.903504 -243.596229) (xy 38.981061 -243.589451) (xy 39.019988 -243.589048) (xy 39.058914 -243.589464)
			(xy 39.136471 -243.596241) (xy 39.213138 -243.609771) (xy 39.288329 -243.62995) (xy 39.325042 -243.642896)
			(xy 39.333591 -243.64566) (xy 39.351545 -243.64566) (xy 39.360094 -243.642896) (xy 39.396806 -243.629947)
			(xy 39.471997 -243.609767) (xy 39.548665 -243.596234) (xy 39.626222 -243.589453) (xy 39.665148 -243.589048)
			(xy 39.70625 -243.589521) (xy 39.788103 -243.59711) (xy 39.868907 -243.612218) (xy 39.947972 -243.634717)
			(xy 40.024624 -243.664415) (xy 40.098209 -243.701058) (xy 40.1681 -243.744334) (xy 40.233699 -243.793874)
			(xy 40.294448 -243.849254) (xy 40.349829 -243.910004) (xy 40.399368 -243.975604) (xy 40.442644 -244.045494)
			(xy 40.479287 -244.11908) (xy 40.508984 -244.195732) (xy 40.531483 -244.274797) (xy 40.535672 -244.2972)
			(xy 40.983872 -244.2972) (xy 40.987902 -244.212596) (xy 40.999957 -244.128757) (xy 41.019926 -244.046445)
			(xy 41.047629 -243.966403) (xy 41.082816 -243.889357) (xy 41.125167 -243.816005) (xy 41.174299 -243.747011)
			(xy 41.229767 -243.682999) (xy 41.291069 -243.62455) (xy 41.357649 -243.572193) (xy 41.428904 -243.526402)
			(xy 41.50419 -243.487592) (xy 41.582824 -243.456115) (xy 41.664094 -243.432254) (xy 41.747265 -243.416227)
			(xy 41.831582 -243.408179) (xy 41.873932 -243.407692) (xy 41.920327 -243.408299) (xy 42.012615 -243.417937)
			(xy 42.103398 -243.437126) (xy 42.191693 -243.465657) (xy 42.234358 -243.483892) (xy 42.2443 -243.487698)
			(xy 42.265564 -243.487698) (xy 42.275506 -243.483892) (xy 42.318164 -243.465637) (xy 42.406458 -243.437095)
			(xy 42.497244 -243.417905) (xy 42.589536 -243.408275) (xy 42.635932 -243.407692) (xy 42.67828 -243.408197)
			(xy 42.762591 -243.416251) (xy 42.845755 -243.432282) (xy 42.927018 -243.456146) (xy 43.005646 -243.487626)
			(xy 43.080925 -243.526437) (xy 43.152174 -243.572228) (xy 43.218747 -243.624585) (xy 43.280043 -243.683032)
			(xy 43.335505 -243.747041) (xy 43.384632 -243.816033) (xy 43.426979 -243.889381) (xy 43.462162 -243.966423)
			(xy 43.489862 -244.04646) (xy 43.50983 -244.128768) (xy 43.521883 -244.212601) (xy 43.525913 -244.2972)
			(xy 43.521883 -244.381799) (xy 43.50983 -244.465632) (xy 43.489862 -244.54794) (xy 43.462162 -244.627977)
			(xy 43.426979 -244.705019) (xy 43.384632 -244.778367) (xy 43.335505 -244.847359) (xy 43.280043 -244.911368)
			(xy 43.218747 -244.969815) (xy 43.152174 -245.022172) (xy 43.080925 -245.067963) (xy 43.005646 -245.106774)
			(xy 42.927018 -245.138254) (xy 42.845755 -245.162118) (xy 42.762591 -245.178149) (xy 42.67828 -245.186203)
			(xy 42.635932 -245.186708) (xy 42.589537 -245.186114) (xy 42.497249 -245.176472) (xy 42.406465 -245.157279)
			(xy 42.318171 -245.128744) (xy 42.275506 -245.110508) (xy 42.265564 -245.106702) (xy 42.2443 -245.106702)
			(xy 42.234358 -245.110508) (xy 42.191691 -245.128742) (xy 42.103401 -245.157289) (xy 42.012617 -245.176485)
			(xy 41.920328 -245.186121) (xy 41.873932 -245.186708) (xy 41.831582 -245.186221) (xy 41.747265 -245.178173)
			(xy 41.664094 -245.162146) (xy 41.582824 -245.138285) (xy 41.50419 -245.106808) (xy 41.428904 -245.067998)
			(xy 41.357649 -245.022207) (xy 41.291069 -244.96985) (xy 41.229767 -244.911401) (xy 41.174299 -244.847389)
			(xy 41.125167 -244.778395) (xy 41.082816 -244.705043) (xy 41.047629 -244.627997) (xy 41.019926 -244.547955)
			(xy 40.999957 -244.465643) (xy 40.987902 -244.381804) (xy 40.983872 -244.2972) (xy 40.535672 -244.2972)
			(xy 40.546591 -244.355601) (xy 40.554179 -244.437454) (xy 40.554656 -244.478556) (xy 40.554282 -244.516841)
			(xy 40.547738 -244.593129) (xy 40.534653 -244.668572) (xy 40.515123 -244.742608) (xy 40.502586 -244.778784)
			(xy 40.499956 -244.787226) (xy 40.499941 -244.804892) (xy 40.502586 -244.813328) (xy 40.515097 -244.849511)
			(xy 40.534609 -244.923549) (xy 40.547693 -244.998989) (xy 40.554252 -245.075273) (xy 40.554656 -245.113556)
			(xy 40.554091 -245.154656) (xy 40.546511 -245.236507) (xy 40.531411 -245.317309) (xy 40.508919 -245.396372)
			(xy 40.479229 -245.473024) (xy 40.442593 -245.546609) (xy 40.399323 -245.616499) (xy 40.34979 -245.682099)
			(xy 40.294414 -245.742849) (xy 40.23367 -245.798231) (xy 40.168075 -245.847771) (xy 40.098189 -245.891048)
			(xy 40.024608 -245.927692) (xy 39.94796 -245.95739) (xy 39.868898 -245.97989) (xy 39.788098 -245.994998)
			(xy 39.706248 -246.002587) (xy 39.665148 -246.003064) (xy 39.625578 -246.00265) (xy 39.54675 -245.995641)
			(xy 39.468856 -245.981657) (xy 39.392513 -245.960808) (xy 39.355268 -245.947438) (xy 39.346599 -245.944608)
			(xy 39.328377 -245.944608) (xy 39.319708 -245.947438) (xy 39.282465 -245.960813) (xy 39.206121 -245.981658)
			(xy 39.128226 -245.995639) (xy 39.049398 -246.002645) (xy 39.009828 -246.003064) (xy 38.971543 -246.002694)
			(xy 38.895254 -245.996149) (xy 38.819812 -245.983063) (xy 38.745776 -245.963531) (xy 38.7096 -245.950994)
			(xy 38.701163 -245.948343) (xy 38.683493 -245.948343) (xy 38.675056 -245.950994) (xy 38.638874 -245.96351)
			(xy 38.564836 -245.98302) (xy 38.489396 -245.996103) (xy 38.413111 -246.002661) (xy 38.374828 -246.003064)
			(xy 38.333724 -246.002621) (xy 38.251867 -245.995038) (xy 38.171058 -245.979934) (xy 38.091988 -245.957438)
			(xy 38.015331 -245.927742) (xy 37.941741 -245.8911) (xy 37.871846 -245.847823) (xy 37.806243 -245.798281)
			(xy 37.745491 -245.742898) (xy 37.690108 -245.682145) (xy 37.640568 -245.616541) (xy 37.597293 -245.546645)
			(xy 37.560651 -245.473055) (xy 37.530957 -245.396397) (xy 37.508462 -245.317326) (xy 37.49336 -245.236518)
			(xy 37.485778 -245.15466) (xy 37.48532 -245.113556) (xy 36.801488 -245.113556) (xy 36.772443 -245.128025)
			(xy 36.695786 -245.157739) (xy 36.616714 -245.180255) (xy 36.535902 -245.195381) (xy 36.454039 -245.202987)
			(xy 36.412932 -245.203472) (xy 36.373357 -245.203012) (xy 36.294524 -245.195946) (xy 36.21663 -245.181902)
			(xy 36.140292 -245.160992) (xy 36.103052 -245.147592) (xy 36.094383 -245.144762) (xy 36.076161 -245.144762)
			(xy 36.067492 -245.147592) (xy 36.030254 -245.160998) (xy 35.953915 -245.181902) (xy 35.87602 -245.195946)
			(xy 35.797187 -245.203018) (xy 35.757612 -245.203472) (xy 35.719322 -245.203063) (xy 35.643028 -245.196456)
			(xy 35.567586 -245.183308) (xy 35.493555 -245.163716) (xy 35.457384 -245.151148) (xy 35.448947 -245.148497)
			(xy 35.431277 -245.148497) (xy 35.42284 -245.151148) (xy 35.386663 -245.163693) (xy 35.31263 -245.183265)
			(xy 35.23719 -245.196412) (xy 35.1609 -245.203036) (xy 35.122612 -245.203472) (xy 35.081501 -245.203036)
			(xy 34.999628 -245.195449) (xy 34.918806 -245.180338) (xy 34.839723 -245.157833) (xy 34.763054 -245.128126)
			(xy 34.689454 -245.09147) (xy 34.619551 -245.048177) (xy 34.553942 -244.998619) (xy 34.493187 -244.943216)
			(xy 34.437804 -244.882444) (xy 34.388265 -244.816819) (xy 34.344995 -244.746903) (xy 34.308362 -244.673292)
			(xy 34.278678 -244.596614) (xy 34.256198 -244.517523) (xy 34.241113 -244.436696) (xy 34.233551 -244.354822)
			(xy 34.233104 -244.31371) (xy 13.239913 -244.31371) (xy 13.241409 -244.327615) (xy 13.242036 -244.375178)
			(xy 13.241625 -244.413468) (xy 13.235019 -244.489762) (xy 13.221871 -244.565204) (xy 13.202279 -244.639235)
			(xy 13.189712 -244.675406) (xy 13.187073 -244.683846) (xy 13.187066 -244.701513) (xy 13.189712 -244.70995)
			(xy 13.202252 -244.746129) (xy 13.221826 -244.820161) (xy 13.234974 -244.895601) (xy 13.2416 -244.97189)
			(xy 13.242036 -245.010178) (xy 13.2416 -245.050088) (xy 13.234447 -245.129586) (xy 13.220204 -245.208124)
			(xy 13.198987 -245.285072) (xy 13.185394 -245.322598) (xy 13.182566 -245.331268) (xy 13.182559 -245.349491)
			(xy 13.185394 -245.358158) (xy 13.198976 -245.395688) (xy 13.220195 -245.472634) (xy 13.234438 -245.551171)
			(xy 13.241589 -245.630669) (xy 13.242036 -245.670578) (xy 13.241625 -245.708868) (xy 13.235019 -245.785162)
			(xy 13.221871 -245.860604) (xy 13.202279 -245.934635) (xy 13.189712 -245.970806) (xy 13.187073 -245.979246)
			(xy 13.187066 -245.996913) (xy 13.189712 -246.00535) (xy 13.202252 -246.041529) (xy 13.221826 -246.115561)
			(xy 13.223645 -246.126) (xy 44.997072 -246.126) (xy 45.001102 -246.041396) (xy 45.013157 -245.957557)
			(xy 45.033126 -245.875245) (xy 45.060829 -245.795203) (xy 45.096016 -245.718157) (xy 45.138367 -245.644805)
			(xy 45.187499 -245.575811) (xy 45.242967 -245.511799) (xy 45.304269 -245.45335) (xy 45.370849 -245.400993)
			(xy 45.442104 -245.355202) (xy 45.51739 -245.316392) (xy 45.596024 -245.284915) (xy 45.677294 -245.261054)
			(xy 45.760465 -245.245027) (xy 45.844782 -245.236979) (xy 45.887132 -245.236492) (xy 45.928456 -245.236951)
			(xy 46.010751 -245.244563) (xy 46.091986 -245.259775) (xy 46.17146 -245.282455) (xy 46.248489 -245.312409)
			(xy 46.285658 -245.330472) (xy 46.295718 -245.334966) (xy 46.317716 -245.33575) (xy 46.328076 -245.331996)
			(xy 46.369278 -245.315201) (xy 46.454293 -245.288939) (xy 46.541505 -245.271288) (xy 46.630042 -245.262425)
			(xy 46.674532 -245.261892) (xy 46.715492 -245.26232) (xy 46.797069 -245.269791) (xy 46.877612 -245.284738)
			(xy 46.956438 -245.307036) (xy 46.994826 -245.321328) (xy 47.004522 -245.324625) (xy 47.024976 -245.323952)
			(xy 47.03445 -245.320058) (xy 47.069871 -245.303974) (xy 47.142968 -245.277337) (xy 47.218112 -245.257184)
			(xy 47.294728 -245.243669) (xy 47.372232 -245.236896) (xy 47.411132 -245.236492) (xy 47.45348 -245.236997)
			(xy 47.537791 -245.245051) (xy 47.620955 -245.261082) (xy 47.702218 -245.284946) (xy 47.780846 -245.316426)
			(xy 47.856125 -245.355237) (xy 47.927374 -245.401028) (xy 47.993947 -245.453385) (xy 48.055243 -245.511832)
			(xy 48.110705 -245.575841) (xy 48.159832 -245.644833) (xy 48.202179 -245.718181) (xy 48.237362 -245.795223)
			(xy 48.265062 -245.87526) (xy 48.28503 -245.957568) (xy 48.297083 -246.041401) (xy 48.301113 -246.126)
			(xy 48.297083 -246.210599) (xy 48.28503 -246.294432) (xy 48.265062 -246.37674) (xy 48.237362 -246.456777)
			(xy 48.202179 -246.533819) (xy 48.159832 -246.607167) (xy 48.110705 -246.676159) (xy 48.055243 -246.740168)
			(xy 47.993947 -246.798615) (xy 47.927374 -246.850972) (xy 47.856125 -246.896763) (xy 47.780846 -246.935574)
			(xy 47.702218 -246.967054) (xy 47.620955 -246.990918) (xy 47.537791 -247.006949) (xy 47.45348 -247.015003)
			(xy 47.411132 -247.015508) (xy 47.370172 -247.015091) (xy 47.288594 -247.007617) (xy 47.208051 -246.992667)
			(xy 47.129226 -246.970365) (xy 47.090838 -246.956072) (xy 47.081132 -246.952812) (xy 47.060688 -246.953461)
			(xy 47.051214 -246.957342) (xy 47.015798 -246.973439) (xy 46.9427 -247.000073) (xy 46.867555 -247.020224)
			(xy 46.790937 -247.033735) (xy 46.713432 -247.040505) (xy 46.674532 -247.040908) (xy 46.633208 -247.040463)
			(xy 46.550912 -247.032848) (xy 46.469677 -247.017633) (xy 46.390203 -246.994949) (xy 46.313175 -246.964993)
			(xy 46.276006 -246.946928) (xy 46.265932 -246.942473) (xy 46.243947 -246.941665) (xy 46.233588 -246.945404)
			(xy 46.192391 -246.962211) (xy 46.107373 -246.98847) (xy 46.020161 -247.006117) (xy 45.931622 -247.014977)
			(xy 45.887132 -247.015508) (xy 45.844782 -247.015021) (xy 45.760465 -247.006973) (xy 45.677294 -246.990946)
			(xy 45.596024 -246.967085) (xy 45.51739 -246.935608) (xy 45.442104 -246.896798) (xy 45.370849 -246.851007)
			(xy 45.304269 -246.79865) (xy 45.242967 -246.740201) (xy 45.187499 -246.676189) (xy 45.138367 -246.607195)
			(xy 45.096016 -246.533843) (xy 45.060829 -246.456797) (xy 45.033126 -246.376755) (xy 45.013157 -246.294443)
			(xy 45.001102 -246.210604) (xy 44.997072 -246.126) (xy 13.223645 -246.126) (xy 13.234974 -246.191001)
			(xy 13.2416 -246.26729) (xy 13.242036 -246.305578) (xy 13.241386 -246.353139) (xy 13.231193 -246.447714)
			(xy 13.210984 -246.540665) (xy 13.19657 -246.585994) (xy 13.194034 -246.594763) (xy 13.194681 -246.61299)
			(xy 13.19784 -246.621554) (xy 13.214499 -246.662524) (xy 13.240533 -246.747053) (xy 13.258047 -246.833748)
			(xy 13.266869 -246.921755) (xy 13.267436 -246.965978) (xy 13.267025 -247.004268) (xy 13.260419 -247.080562)
			(xy 13.247271 -247.156004) (xy 13.227679 -247.230035) (xy 13.215112 -247.266206) (xy 13.212473 -247.274646)
			(xy 13.212466 -247.292313) (xy 13.215112 -247.30075) (xy 13.227652 -247.336929) (xy 13.247226 -247.410961)
			(xy 13.260374 -247.486401) (xy 13.267 -247.56269) (xy 13.267436 -247.600978) (xy 13.266932 -247.643339)
			(xy 13.258879 -247.727676) (xy 13.242845 -247.810866) (xy 13.218977 -247.892156) (xy 13.187489 -247.970808)
			(xy 13.148667 -248.046111) (xy 13.102864 -248.117383) (xy 13.050493 -248.183979) (xy 12.992028 -248.245294)
			(xy 12.928 -248.300775) (xy 12.858988 -248.349918) (xy 12.785618 -248.392278) (xy 12.708553 -248.427473)
			(xy 12.628491 -248.455182) (xy 12.546158 -248.475156) (xy 12.462299 -248.487213) (xy 12.377674 -248.491245)
			(xy 12.293049 -248.487213) (xy 12.20919 -248.475156) (xy 12.126857 -248.455182) (xy 12.046795 -248.427473)
			(xy 11.96973 -248.392278) (xy 11.89636 -248.349918) (xy 11.827348 -248.300775) (xy 11.76332 -248.245294)
			(xy 11.704855 -248.183979) (xy 11.652484 -248.117383) (xy 11.606681 -248.046111) (xy 11.567859 -247.970808)
			(xy 11.536371 -247.892156) (xy 11.512503 -247.810866) (xy 11.496469 -247.727676) (xy 11.488416 -247.643339)
			(xy 11.487912 -247.600978) (xy 11.488312 -247.562688) (xy 11.494922 -247.486394) (xy 11.508073 -247.410951)
			(xy 11.527667 -247.336921) (xy 11.540236 -247.30075) (xy 11.542898 -247.292316) (xy 11.542891 -247.274643)
			(xy 11.540236 -247.266206) (xy 11.527681 -247.230032) (xy 11.508111 -247.155998) (xy 11.494968 -247.080557)
			(xy 11.488346 -247.004266) (xy 11.487912 -246.965978) (xy 11.488553 -246.918417) (xy 11.498751 -246.823842)
			(xy 11.518963 -246.730891) (xy 11.533378 -246.685562) (xy 11.535934 -246.676798) (xy 11.535273 -246.658566)
			(xy 11.532108 -246.650002) (xy 11.515464 -246.609027) (xy 11.489427 -246.5245) (xy 11.471908 -246.437806)
			(xy 11.463082 -246.349801) (xy 11.462512 -246.305578) (xy 11.462912 -246.267288) (xy 11.469522 -246.190994)
			(xy 11.482673 -246.115551) (xy 11.502267 -246.041521) (xy 11.514836 -246.00535) (xy 11.517498 -245.996916)
			(xy 11.517491 -245.979243) (xy 11.514836 -245.970806) (xy 11.502281 -245.934632) (xy 11.482711 -245.860598)
			(xy 11.469568 -245.785157) (xy 11.462946 -245.708866) (xy 11.462512 -245.670578) (xy 11.462968 -245.630669)
			(xy 11.470116 -245.551171) (xy 11.484353 -245.472633) (xy 11.505564 -245.395685) (xy 11.519154 -245.358158)
			(xy 11.522007 -245.349494) (xy 11.522 -245.331265) (xy 11.519154 -245.322598) (xy 11.505557 -245.285074)
			(xy 11.484342 -245.208125) (xy 11.470104 -245.129586) (xy 11.462957 -245.050088) (xy 11.462512 -245.010178)
			(xy 11.462912 -244.971888) (xy 11.469522 -244.895594) (xy 11.482673 -244.820151) (xy 11.502267 -244.746121)
			(xy 11.514836 -244.70995) (xy 11.517498 -244.701516) (xy 11.517491 -244.683843) (xy 11.514836 -244.675406)
			(xy 11.502281 -244.639232) (xy 11.482711 -244.565198) (xy 11.469568 -244.489757) (xy 11.462946 -244.413466)
			(xy 11.462512 -244.375178) (xy 11.463091 -244.330956) (xy 11.471924 -244.242953) (xy 11.489441 -244.156259)
			(xy 11.515469 -244.07173) (xy 11.532108 -244.030754) (xy 11.535258 -244.022191) (xy 11.535895 -244.003966)
			(xy 11.533378 -243.995194) (xy 11.533378 -243.99494) (xy 11.530034 -243.986358) (xy 11.518403 -243.972098)
			(xy 11.502505 -243.962831) (xy 11.4935 -243.960904) (xy 11.465052 -243.956078) (xy 11.455924 -243.954901)
			(xy 11.437871 -243.958431) (xy 11.422217 -243.968089) (xy 11.416284 -243.975128) (xy 11.391096 -244.007189)
			(xy 11.335751 -244.067065) (xy 11.275157 -244.121624) (xy 11.209823 -244.170407) (xy 11.140298 -244.213004)
			(xy 11.067165 -244.249058) (xy 10.991039 -244.278267) (xy 10.912559 -244.300383) (xy 10.832384 -244.315223)
			(xy 10.751187 -244.322661) (xy 10.710418 -244.323108) (xy 10.664023 -244.322519) (xy 10.571734 -244.312876)
			(xy 10.480951 -244.293681) (xy 10.392657 -244.265145) (xy 10.349992 -244.246908) (xy 10.34005 -244.243102)
			(xy 10.318786 -244.243102) (xy 10.308844 -244.246908) (xy 10.266179 -244.265147) (xy 10.177888 -244.293692)
			(xy 10.087104 -244.312887) (xy 9.994814 -244.322522) (xy 9.948418 -244.323108) (xy 9.907644 -244.32266)
			(xy 9.826438 -244.315206) (xy 9.746255 -244.300349) (xy 9.667768 -244.278214) (xy 9.591638 -244.248988)
			(xy 9.518502 -244.212915) (xy 9.448976 -244.170299) (xy 9.383643 -244.121497) (xy 9.323052 -244.066919)
			(xy 9.267711 -244.007024) (xy 9.218085 -243.942315) (xy 9.174592 -243.873334) (xy 9.155684 -243.837206)
			(xy 9.148318 -243.822728) (xy 9.11987 -243.807742) (xy 8.992616 -243.82476) (xy 8.968994 -243.84635)
			(xy 8.965692 -243.862352) (xy 8.959187 -243.891967) (xy 8.942666 -243.950312) (xy 8.932672 -243.978938)
			(xy 8.930015 -243.987373) (xy 8.930019 -244.005045) (xy 8.932672 -244.013482) (xy 8.94522 -244.049658)
			(xy 8.964792 -244.123692) (xy 8.977938 -244.199132) (xy 8.984561 -244.275422) (xy 8.984996 -244.31371)
			(xy 8.984517 -244.354824) (xy 8.97693 -244.436702) (xy 8.961821 -244.51753) (xy 8.939318 -244.596619)
			(xy 8.909614 -244.673294) (xy 8.872962 -244.746902) (xy 8.829674 -244.816814) (xy 8.780121 -244.882434)
			(xy 8.724724 -244.943201) (xy 8.663957 -244.998598) (xy 8.598337 -245.048152) (xy 8.528426 -245.09144)
			(xy 8.454818 -245.128092) (xy 8.378143 -245.157797) (xy 8.299054 -245.1803) (xy 8.218226 -245.19541)
			(xy 8.136348 -245.202997) (xy 8.095234 -245.203472) (xy 8.055659 -245.203011) (xy 7.976826 -245.195945)
			(xy 7.898932 -245.181902) (xy 7.822594 -245.160992) (xy 7.785354 -245.147592) (xy 7.776685 -245.144762)
			(xy 7.758463 -245.144762) (xy 7.749794 -245.147592) (xy 7.712556 -245.160997) (xy 7.636216 -245.181901)
			(xy 7.558322 -245.195945) (xy 7.479489 -245.203018) (xy 7.439914 -245.203472) (xy 7.401624 -245.203062)
			(xy 7.32533 -245.196455) (xy 7.249888 -245.183307) (xy 7.175857 -245.163715) (xy 7.139686 -245.151148)
			(xy 7.131249 -245.148497) (xy 7.113579 -245.148497) (xy 7.105142 -245.151148) (xy 7.068965 -245.163692)
			(xy 6.994931 -245.183265) (xy 6.919492 -245.196412) (xy 6.843202 -245.203036) (xy 6.804914 -245.203472)
			(xy 6.763799 -245.203008) (xy 6.68192 -245.195421) (xy 6.601091 -245.180312) (xy 6.522 -245.157809)
			(xy 6.445323 -245.128104) (xy 6.371714 -245.091451) (xy 6.301801 -245.048163) (xy 6.23618 -244.998609)
			(xy 6.175411 -244.943211) (xy 6.120013 -244.882443) (xy 6.070459 -244.816823) (xy 6.02717 -244.74691)
			(xy 5.990517 -244.673301) (xy 5.960813 -244.596624) (xy 5.938309 -244.517533) (xy 5.9232 -244.436704)
			(xy 5.915612 -244.354825) (xy 5.915152 -244.31371) (xy 5.915559 -244.27542) (xy 5.922167 -244.199126)
			(xy 5.935315 -244.123684) (xy 5.954908 -244.049653) (xy 5.967476 -244.013482) (xy 5.970121 -244.005044)
			(xy 5.970124 -243.987375) (xy 5.967476 -243.978938) (xy 5.960618 -243.959126) (xy 5.955792 -243.944648)
			(xy 5.93217 -243.925852) (xy 5.809234 -243.914676) (xy 5.782564 -243.9289) (xy 5.775198 -243.942108)
			(xy 5.753931 -243.979733) (xy 5.705158 -244.051088) (xy 5.649695 -244.117378) (xy 5.588065 -244.177977)
			(xy 5.52085 -244.232315) (xy 5.448683 -244.279879) (xy 5.372244 -244.320221) (xy 5.292253 -244.352961)
			(xy 5.209464 -244.377791) (xy 5.124658 -244.394475) (xy 5.038634 -244.402858) (xy 4.995418 -244.403372)
			(xy 4.955849 -244.402936) (xy 4.877021 -244.395934) (xy 4.799127 -244.381956) (xy 4.722783 -244.361113)
			(xy 4.685538 -244.347746) (xy 4.676869 -244.344916) (xy 4.658647 -244.344916) (xy 4.649978 -244.347746)
			(xy 4.612728 -244.361101) (xy 4.536386 -244.381951) (xy 4.458494 -244.395938) (xy 4.379667 -244.402949)
			(xy 4.340098 -244.403372) (xy 4.301814 -244.402981) (xy 4.225525 -244.396442) (xy 4.150083 -244.383362)
			(xy 4.076046 -244.363836) (xy 4.03987 -244.351302) (xy 4.031433 -244.348651) (xy 4.013763 -244.348651)
			(xy 4.005326 -244.351302) (xy 3.969138 -244.363798) (xy 3.895102 -244.383314) (xy 3.819664 -244.396402)
			(xy 3.743381 -244.402966) (xy 3.705098 -244.403372) (xy 3.663991 -244.402899) (xy 3.582128 -244.395315)
			(xy 3.501314 -244.380211) (xy 3.422238 -244.357716) (xy 3.345574 -244.328022) (xy 3.271976 -244.291382)
			(xy 3.202073 -244.248109) (xy 3.136459 -244.198572) (xy 3.075695 -244.143193) (xy 3.020299 -244.082445)
			(xy 2.970743 -244.016845) (xy 2.927451 -243.946954) (xy 2.89079 -243.873367) (xy 2.861074 -243.796711)
			(xy 2.838557 -243.717641) (xy 2.82343 -243.636831) (xy 2.815822 -243.554971) (xy 2.815336 -243.513864)
			(xy 0.509016 -243.513864) (xy 0.509016 -248.835361) (xy 25.145742 -248.835361) (xy 25.145742 -248.750639)
			(xy 25.153795 -248.666302) (xy 25.169829 -248.583112) (xy 25.193697 -248.501822) (xy 25.225185 -248.42317)
			(xy 25.264007 -248.347867) (xy 25.30981 -248.276595) (xy 25.362181 -248.209999) (xy 25.420646 -248.148684)
			(xy 25.484674 -248.093203) (xy 25.553686 -248.04406) (xy 25.627056 -248.0017) (xy 25.704121 -247.966505)
			(xy 25.784183 -247.938796) (xy 25.866516 -247.918822) (xy 25.950375 -247.906765) (xy 26.035 -247.902734)
			(xy 26.119625 -247.906765) (xy 26.203484 -247.918822) (xy 26.285817 -247.938796) (xy 26.365879 -247.966505)
			(xy 26.442944 -248.0017) (xy 26.516314 -248.04406) (xy 26.585326 -248.093203) (xy 26.649354 -248.148684)
			(xy 26.707819 -248.209999) (xy 26.76019 -248.276595) (xy 26.805993 -248.347867) (xy 26.844815 -248.42317)
			(xy 26.876303 -248.501822) (xy 26.900171 -248.583112) (xy 26.916205 -248.666302) (xy 26.924258 -248.750639)
			(xy 26.924762 -248.793) (xy 26.924258 -248.835361) (xy 26.916205 -248.919698) (xy 26.900171 -249.002888)
			(xy 26.876303 -249.084178) (xy 26.844815 -249.16283) (xy 26.805993 -249.238133) (xy 26.76019 -249.309405)
			(xy 26.707819 -249.376001) (xy 26.649354 -249.437316) (xy 26.585326 -249.492797) (xy 26.516314 -249.54194)
			(xy 26.442944 -249.5843) (xy 26.365879 -249.619495) (xy 26.285817 -249.647204) (xy 26.203484 -249.667178)
			(xy 26.119625 -249.679235) (xy 26.035 -249.683267) (xy 25.950375 -249.679235) (xy 25.866516 -249.667178)
			(xy 25.784183 -249.647204) (xy 25.704121 -249.619495) (xy 25.627056 -249.5843) (xy 25.553686 -249.54194)
			(xy 25.484674 -249.492797) (xy 25.420646 -249.437316) (xy 25.362181 -249.376001) (xy 25.30981 -249.309405)
			(xy 25.264007 -249.238133) (xy 25.225185 -249.16283) (xy 25.193697 -249.084178) (xy 25.169829 -249.002888)
			(xy 25.153795 -248.919698) (xy 25.145742 -248.835361) (xy 0.509016 -248.835361) (xy 0.509016 -263.977374)
			(xy 0.508 -263.977374) (xy 0.508 -264.249916) (xy 0.509016 -264.249916) (xy 0.509016 -267.146024)
			(xy 2.53746 -267.146024) (xy 2.537827 -267.107739) (xy 2.544373 -267.03145) (xy 2.55746 -266.956008)
			(xy 2.576992 -266.881972) (xy 2.58953 -266.845796) (xy 2.59217 -266.837356) (xy 2.592178 -266.819688)
			(xy 2.58953 -266.811252) (xy 2.57702 -266.775068) (xy 2.557508 -266.701031) (xy 2.544424 -266.625591)
			(xy 2.537864 -266.549307) (xy 2.53746 -266.511024) (xy 2.537865 -266.471454) (xy 2.544876 -266.392626)
			(xy 2.558863 -266.314732) (xy 2.579715 -266.238389) (xy 2.593086 -266.201144) (xy 2.595933 -266.19248)
			(xy 2.595921 -266.174253) (xy 2.593086 -266.165584) (xy 2.579718 -266.128339) (xy 2.558871 -266.051995)
			(xy 2.544889 -265.974101) (xy 2.537881 -265.895273) (xy 2.53746 -265.855704) (xy 2.537926 -265.814601)
			(xy 2.545511 -265.732746) (xy 2.560616 -265.651939) (xy 2.583112 -265.572871) (xy 2.612808 -265.496216)
			(xy 2.64945 -265.422628) (xy 2.692726 -265.352735) (xy 2.742266 -265.287133) (xy 2.797647 -265.226382)
			(xy 2.858398 -265.171) (xy 2.924 -265.121459) (xy 2.993893 -265.078183) (xy 3.067481 -265.04154)
			(xy 3.144135 -265.011844) (xy 3.223203 -264.989347) (xy 3.30401 -264.974241) (xy 3.385865 -264.966656)
			(xy 3.426968 -264.966196) (xy 3.462095 -264.966499) (xy 3.532135 -264.971964) (xy 3.601524 -264.98295)
			(xy 3.635756 -264.990834) (xy 3.648964 -264.994136) (xy 3.674618 -264.98677) (xy 3.754628 -264.905236)
			(xy 3.761486 -264.879836) (xy 3.75793 -264.866628) (xy 3.748818 -264.829992) (xy 3.736061 -264.755577)
			(xy 3.729642 -264.68035) (xy 3.729228 -264.6426) (xy 3.729859 -264.596198) (xy 3.739548 -264.503901)
			(xy 3.758801 -264.413116) (xy 3.787407 -264.32483) (xy 3.805682 -264.282174) (xy 3.809488 -264.272232)
			(xy 3.809488 -264.250968) (xy 3.805682 -264.241026) (xy 3.787417 -264.198367) (xy 3.758825 -264.110078)
			(xy 3.739569 -264.019294) (xy 3.729857 -263.927001) (xy 3.729228 -263.8806) (xy 3.729692 -263.839489)
			(xy 3.73728 -263.757619) (xy 3.752391 -263.676799) (xy 3.774896 -263.597718) (xy 3.804602 -263.521051)
			(xy 3.841258 -263.447453) (xy 3.884548 -263.377551) (xy 3.934105 -263.311943) (xy 3.989505 -263.251188)
			(xy 4.050275 -263.195805) (xy 4.115897 -263.146267) (xy 4.185811 -263.102996) (xy 4.25942 -263.066361)
			(xy 4.336095 -263.036676) (xy 4.415182 -263.014194) (xy 4.496007 -262.999106) (xy 4.577879 -262.991541)
			(xy 4.61899 -262.991092) (xy 4.658757 -262.991518) (xy 4.737979 -262.998557) (xy 4.816255 -263.012642)
			(xy 4.892961 -263.033662) (xy 4.967484 -263.061447) (xy 5.003546 -263.078214) (xy 5.014047 -263.082546)
			(xy 5.036733 -263.082546) (xy 5.047234 -263.078214) (xy 5.083292 -263.061438) (xy 5.157819 -263.033665)
			(xy 5.234526 -263.01265) (xy 5.312802 -262.99856) (xy 5.392023 -262.99151) (xy 5.43179 -262.991092)
			(xy 5.470213 -262.991484) (xy 5.546776 -262.998075) (xy 5.622485 -263.011252) (xy 5.696772 -263.030916)
			(xy 5.769085 -263.05692) (xy 5.804154 -263.072626) (xy 5.815113 -263.077005) (xy 5.838675 -263.076351)
			(xy 5.849366 -263.071356) (xy 5.888227 -263.051102) (xy 5.969164 -263.017487) (xy 6.05301 -262.991984)
			(xy 6.138956 -262.97484) (xy 6.22617 -262.966221) (xy 6.26999 -262.965692) (xy 6.311097 -262.966163)
			(xy 6.39296 -262.973747) (xy 6.473774 -262.988851) (xy 6.552851 -263.011346) (xy 6.629515 -263.04104)
			(xy 6.703113 -263.07768) (xy 6.773016 -263.120953) (xy 6.83863 -263.17049) (xy 6.899394 -263.225869)
			(xy 6.95479 -263.286617) (xy 7.004346 -263.352217) (xy 7.047639 -263.422109) (xy 7.084299 -263.495696)
			(xy 7.114015 -263.572352) (xy 7.136532 -263.651422) (xy 7.151659 -263.732232) (xy 7.159266 -263.814093)
			(xy 7.159752 -263.8552) (xy 7.159123 -263.901602) (xy 7.149433 -263.993899) (xy 7.13018 -264.084685)
			(xy 7.101573 -264.17297) (xy 7.083298 -264.215626) (xy 7.079493 -264.225568) (xy 7.079493 -264.246832)
			(xy 7.083298 -264.256774) (xy 7.101562 -264.299434) (xy 7.130154 -264.387723) (xy 7.149411 -264.478506)
			(xy 7.150642 -264.4902) (xy 8.656578 -264.4902) (xy 8.660608 -264.405599) (xy 8.672661 -264.321764)
			(xy 8.692629 -264.239455) (xy 8.720331 -264.159416) (xy 8.755515 -264.082373) (xy 8.797864 -264.009023)
			(xy 8.846993 -263.940031) (xy 8.902458 -263.876021) (xy 8.963756 -263.817573) (xy 9.030332 -263.765217)
			(xy 9.101584 -263.719427) (xy 9.176865 -263.680616) (xy 9.255495 -263.649137) (xy 9.336762 -263.625276)
			(xy 9.419928 -263.609247) (xy 9.504242 -263.601196) (xy 9.54659 -263.600692) (xy 9.592985 -263.601278)
			(xy 9.685274 -263.610922) (xy 9.776058 -263.630117) (xy 9.864351 -263.658655) (xy 9.907016 -263.676892)
			(xy 9.916958 -263.680698) (xy 9.938222 -263.680698) (xy 9.948164 -263.676892) (xy 9.990828 -263.658651)
			(xy 10.079119 -263.630106) (xy 10.169904 -263.610912) (xy 10.262194 -263.601277) (xy 10.30859 -263.600692)
			(xy 10.350938 -263.601196) (xy 10.435252 -263.609247) (xy 10.518418 -263.625276) (xy 10.599685 -263.649137)
			(xy 10.678315 -263.680616) (xy 10.753596 -263.719427) (xy 10.824848 -263.765217) (xy 10.891424 -263.817573)
			(xy 10.952722 -263.876021) (xy 11.008187 -263.940031) (xy 11.057316 -264.009023) (xy 11.099665 -264.082373)
			(xy 11.134849 -264.159416) (xy 11.162551 -264.239455) (xy 11.182404 -264.32129) (xy 11.297412 -264.32129)
			(xy 11.297816 -264.283) (xy 11.304424 -264.206706) (xy 11.317574 -264.131264) (xy 11.337168 -264.057233)
			(xy 11.349736 -264.021062) (xy 11.352392 -264.012627) (xy 11.352389 -263.994955) (xy 11.349736 -263.986518)
			(xy 11.337184 -263.950343) (xy 11.317614 -263.876309) (xy 11.304469 -263.800868) (xy 11.297847 -263.724578)
			(xy 11.297412 -263.68629) (xy 11.297903 -263.645176) (xy 11.305491 -263.5633) (xy 11.320601 -263.482473)
			(xy 11.343104 -263.403385) (xy 11.372808 -263.32671) (xy 11.409459 -263.253103) (xy 11.452746 -263.183192)
			(xy 11.502299 -263.117573) (xy 11.557695 -263.056806) (xy 11.618461 -263.001409) (xy 11.684079 -262.951855)
			(xy 11.753989 -262.908567) (xy 11.827595 -262.871914) (xy 11.90427 -262.842209) (xy 11.983357 -262.819704)
			(xy 12.064184 -262.804593) (xy 12.14606 -262.797004) (xy 12.187174 -262.796528) (xy 12.226749 -262.796986)
			(xy 12.305583 -262.804053) (xy 12.383477 -262.818097) (xy 12.459814 -262.839008) (xy 12.497054 -262.852408)
			(xy 12.505723 -262.855238) (xy 12.523945 -262.855238) (xy 12.532614 -262.852408) (xy 12.569851 -262.839)
			(xy 12.646191 -262.818097) (xy 12.724086 -262.804054) (xy 12.802919 -262.796982) (xy 12.842494 -262.796528)
			(xy 12.880784 -262.796936) (xy 12.957078 -262.803543) (xy 13.03252 -262.816692) (xy 13.106551 -262.836284)
			(xy 13.142722 -262.848852) (xy 13.151159 -262.851503) (xy 13.168829 -262.851503) (xy 13.177266 -262.848852)
			(xy 13.213443 -262.836305) (xy 13.287476 -262.816734) (xy 13.362916 -262.803587) (xy 13.439206 -262.796964)
			(xy 13.477494 -262.796528) (xy 13.518608 -262.797019) (xy 13.600485 -262.804605) (xy 13.681312 -262.819714)
			(xy 13.760401 -262.842216) (xy 13.837077 -262.871919) (xy 13.910684 -262.908571) (xy 13.980596 -262.951857)
			(xy 14.046215 -263.00141) (xy 14.106983 -263.056806) (xy 14.16238 -263.117572) (xy 14.211934 -263.183191)
			(xy 14.255221 -263.253102) (xy 14.291874 -263.326709) (xy 14.321579 -263.403384) (xy 14.344083 -263.482472)
			(xy 14.359193 -263.563299) (xy 14.366781 -263.645176) (xy 14.367256 -263.68629) (xy 14.366848 -263.72458)
			(xy 14.360241 -263.800874) (xy 14.347092 -263.876316) (xy 14.3275 -263.950347) (xy 14.314932 -263.986518)
			(xy 14.312287 -263.994956) (xy 14.312283 -264.012625) (xy 14.314932 -264.021062) (xy 14.32179 -264.040874)
			(xy 14.326616 -264.055352) (xy 14.350238 -264.074148) (xy 14.473174 -264.085324) (xy 14.499844 -264.0711)
			(xy 14.50721 -264.057892) (xy 14.528471 -264.020264) (xy 14.577245 -263.948909) (xy 14.632708 -263.882619)
			(xy 14.694338 -263.822019) (xy 14.761554 -263.767682) (xy 14.833722 -263.720118) (xy 14.910162 -263.679776)
			(xy 14.990153 -263.647036) (xy 15.072942 -263.622208) (xy 15.157749 -263.605523) (xy 15.243774 -263.597141)
			(xy 15.28699 -263.596628) (xy 15.326559 -263.597061) (xy 15.405387 -263.604065) (xy 15.483281 -263.618043)
			(xy 15.559625 -263.638887) (xy 15.59687 -263.652254) (xy 15.605539 -263.655084) (xy 15.623761 -263.655084)
			(xy 15.63243 -263.652254) (xy 15.669679 -263.638896) (xy 15.746021 -263.618047) (xy 15.823914 -263.604061)
			(xy 15.902741 -263.59705) (xy 15.94231 -263.596628) (xy 15.980594 -263.597016) (xy 16.056883 -263.603556)
			(xy 16.132325 -263.616637) (xy 16.206362 -263.636163) (xy 16.242538 -263.648698) (xy 16.250975 -263.651349)
			(xy 16.268645 -263.651349) (xy 16.277082 -263.648698) (xy 16.313269 -263.636199) (xy 16.387306 -263.616684)
			(xy 16.462744 -263.603597) (xy 16.539027 -263.597033) (xy 16.57731 -263.596628) (xy 16.618417 -263.597103)
			(xy 16.700279 -263.604688) (xy 16.781093 -263.619793) (xy 16.860169 -263.642288) (xy 16.936832 -263.671982)
			(xy 17.010429 -263.708622) (xy 17.080333 -263.751895) (xy 17.145946 -263.801432) (xy 17.20671 -263.85681)
			(xy 17.262106 -263.917558) (xy 17.311662 -263.983158) (xy 17.354954 -264.053049) (xy 17.391615 -264.126635)
			(xy 17.421331 -264.20329) (xy 17.443849 -264.28236) (xy 17.458977 -264.363169) (xy 17.466585 -264.44503)
			(xy 17.467072 -264.486136) (xy 17.466647 -264.524425) (xy 17.460045 -264.600719) (xy 17.448323 -264.668)
			(xy 31.41472 -264.668) (xy 31.4153 -264.621604) (xy 31.424946 -264.529316) (xy 31.444142 -264.438532)
			(xy 31.472682 -264.350239) (xy 31.49092 -264.307574) (xy 31.494724 -264.297631) (xy 31.494724 -264.276369)
			(xy 31.49092 -264.266426) (xy 31.472677 -264.223763) (xy 31.444132 -264.135471) (xy 31.424938 -264.044686)
			(xy 31.415305 -263.952396) (xy 31.41472 -263.906) (xy 31.415152 -263.864896) (xy 31.422738 -263.783039)
			(xy 31.437844 -263.702231) (xy 31.460341 -263.623161) (xy 31.490039 -263.546505) (xy 31.526683 -263.472915)
			(xy 31.56996 -263.403021) (xy 31.619503 -263.337418) (xy 31.674887 -263.276667) (xy 31.73564 -263.221285)
			(xy 31.801244 -263.171745) (xy 31.87114 -263.128469) (xy 31.94473 -263.091827) (xy 32.021388 -263.062132)
			(xy 32.100458 -263.039637) (xy 32.181266 -263.024534) (xy 32.263124 -263.016951) (xy 32.304228 -263.016492)
			(xy 32.343996 -263.016903) (xy 32.423218 -263.023946) (xy 32.501494 -263.038034) (xy 32.5782 -263.059057)
			(xy 32.652722 -263.086846) (xy 32.688784 -263.103614) (xy 32.699285 -263.107946) (xy 32.721971 -263.107946)
			(xy 32.732472 -263.103614) (xy 32.76854 -263.08686) (xy 32.843064 -263.059082) (xy 32.919768 -263.038063)
			(xy 32.998042 -263.023969) (xy 33.077261 -263.016912) (xy 33.117028 -263.016492) (xy 33.163423 -263.0171)
			(xy 33.255711 -263.026738) (xy 33.346494 -263.045926) (xy 33.434789 -263.074458) (xy 33.477454 -263.092692)
			(xy 33.487396 -263.096498) (xy 33.50866 -263.096498) (xy 33.518602 -263.092692) (xy 33.56126 -263.074438)
			(xy 33.649554 -263.045896) (xy 33.74034 -263.026706) (xy 33.832632 -263.017075) (xy 33.879028 -263.016492)
			(xy 33.920131 -263.01694) (xy 34.001986 -263.024527) (xy 34.082792 -263.039635) (xy 34.161859 -263.062134)
			(xy 34.238513 -263.091832) (xy 34.3121 -263.128476) (xy 34.381992 -263.171753) (xy 34.447593 -263.221294)
			(xy 34.508343 -263.276677) (xy 34.563724 -263.337429) (xy 34.613263 -263.403031) (xy 34.656538 -263.472925)
			(xy 34.69318 -263.546513) (xy 34.722875 -263.623168) (xy 34.745372 -263.702236) (xy 34.760477 -263.783042)
			(xy 34.768061 -263.864897) (xy 34.768536 -263.906) (xy 34.767951 -263.952395) (xy 34.758306 -264.044684)
			(xy 34.739111 -264.135467) (xy 34.710573 -264.223761) (xy 34.692336 -264.266426) (xy 34.688529 -264.276368)
			(xy 34.688529 -264.297632) (xy 34.692336 -264.307574) (xy 34.710582 -264.350235) (xy 34.739126 -264.438528)
			(xy 34.758318 -264.529313) (xy 34.767951 -264.621604) (xy 34.768536 -264.668) (xy 34.768033 -264.709102)
			(xy 34.760449 -264.790954) (xy 34.745344 -264.871758) (xy 34.73105 -264.922) (xy 36.316372 -264.922)
			(xy 36.320402 -264.837396) (xy 36.332457 -264.753558) (xy 36.352426 -264.671245) (xy 36.380129 -264.591204)
			(xy 36.415315 -264.514158) (xy 36.457666 -264.440806) (xy 36.506798 -264.371812) (xy 36.562266 -264.307801)
			(xy 36.623567 -264.249352) (xy 36.690147 -264.196995) (xy 36.761402 -264.151204) (xy 36.836688 -264.112394)
			(xy 36.915321 -264.080916) (xy 36.996591 -264.057055) (xy 37.079761 -264.041028) (xy 37.164078 -264.032979)
			(xy 37.206428 -264.032492) (xy 37.252823 -264.0331) (xy 37.345111 -264.042738) (xy 37.435894 -264.061926)
			(xy 37.524189 -264.090458) (xy 37.566854 -264.108692) (xy 37.576796 -264.112498) (xy 37.59806 -264.112498)
			(xy 37.608002 -264.108692) (xy 37.65066 -264.090438) (xy 37.738954 -264.061896) (xy 37.82974 -264.042706)
			(xy 37.922032 -264.033075) (xy 37.968428 -264.032492) (xy 38.010776 -264.032997) (xy 38.095087 -264.04105)
			(xy 38.178252 -264.057081) (xy 38.259515 -264.080945) (xy 38.338143 -264.112425) (xy 38.413422 -264.151236)
			(xy 38.484672 -264.197027) (xy 38.551246 -264.249383) (xy 38.612542 -264.307831) (xy 38.624204 -264.32129)
			(xy 38.932104 -264.32129) (xy 38.932488 -264.283006) (xy 38.939028 -264.206717) (xy 38.952111 -264.131274)
			(xy 38.971638 -264.057238) (xy 38.984174 -264.021062) (xy 38.986829 -264.012626) (xy 38.986826 -263.994955)
			(xy 38.984174 -263.986518) (xy 38.971674 -263.950331) (xy 38.95216 -263.876294) (xy 38.939073 -263.800856)
			(xy 38.932509 -263.724573) (xy 38.932104 -263.68629) (xy 38.932603 -263.645184) (xy 38.940188 -263.563323)
			(xy 38.955292 -263.48251) (xy 38.977786 -263.403436) (xy 39.00748 -263.326774) (xy 39.044118 -263.253177)
			(xy 39.08739 -263.183275) (xy 39.136925 -263.117662) (xy 39.192302 -263.056899) (xy 39.253048 -263.001503)
			(xy 39.318645 -262.951947) (xy 39.388534 -262.908654) (xy 39.462119 -262.871992) (xy 39.538772 -262.842275)
			(xy 39.61784 -262.819756) (xy 39.698647 -262.804626) (xy 39.780506 -262.797016) (xy 39.821612 -262.796528)
			(xy 39.861187 -262.796975) (xy 39.940021 -262.804045) (xy 40.017915 -262.818092) (xy 40.094253 -262.839006)
			(xy 40.131492 -262.852408) (xy 40.140161 -262.855238) (xy 40.158383 -262.855238) (xy 40.167052 -262.852408)
			(xy 40.204295 -262.839018) (xy 40.280633 -262.81811) (xy 40.358525 -262.804062) (xy 40.437358 -262.796984)
			(xy 40.476932 -262.796528) (xy 40.515222 -262.796924) (xy 40.591516 -262.803535) (xy 40.666959 -262.816687)
			(xy 40.740989 -262.836283) (xy 40.77716 -262.848852) (xy 40.785597 -262.851503) (xy 40.803267 -262.851503)
			(xy 40.811704 -262.848852) (xy 40.847877 -262.836295) (xy 40.921912 -262.816726) (xy 40.997353 -262.803582)
			(xy 41.073644 -262.796962) (xy 41.111932 -262.796528) (xy 41.153044 -262.796922) (xy 41.234918 -262.804513)
			(xy 41.315741 -262.819627) (xy 41.394825 -262.842136) (xy 41.471493 -262.871847) (xy 41.545093 -262.908506)
			(xy 41.614996 -262.951802) (xy 41.680605 -263.001363) (xy 41.74136 -263.056768) (xy 41.796743 -263.117543)
			(xy 41.84628 -263.18317) (xy 41.88955 -263.253088) (xy 41.926183 -263.326701) (xy 41.955866 -263.403381)
			(xy 41.978346 -263.482473) (xy 41.993431 -263.563302) (xy 42.000993 -263.645178) (xy 42.00144 -263.68629)
			(xy 42.001048 -263.724574) (xy 41.994509 -263.800863) (xy 41.981429 -263.876305) (xy 41.961904 -263.950342)
			(xy 41.94937 -263.986518) (xy 41.946723 -263.994956) (xy 41.94672 -264.012625) (xy 41.94937 -264.021062)
			(xy 41.956228 -264.040874) (xy 41.961054 -264.055352) (xy 41.984676 -264.074148) (xy 42.107612 -264.085324)
			(xy 42.134282 -264.0711) (xy 42.141648 -264.057892) (xy 42.162881 -264.020248) (xy 42.211658 -263.948892)
			(xy 42.267124 -263.882602) (xy 42.328757 -263.822003) (xy 42.395975 -263.767666) (xy 42.468146 -263.720104)
			(xy 42.544589 -263.679763) (xy 42.624583 -263.647026) (xy 42.707375 -263.622199) (xy 42.792184 -263.605518)
			(xy 42.878211 -263.59714) (xy 42.921428 -263.596628) (xy 42.960997 -263.59705) (xy 43.039825 -263.604057)
			(xy 43.117719 -263.618038) (xy 43.194063 -263.638885) (xy 43.231308 -263.652254) (xy 43.239977 -263.655084)
			(xy 43.258199 -263.655084) (xy 43.266868 -263.652254) (xy 43.304113 -263.638885) (xy 43.380457 -263.618039)
			(xy 43.458351 -263.604056) (xy 43.537179 -263.597049) (xy 43.576748 -263.596628) (xy 43.615033 -263.597005)
			(xy 43.691321 -263.603548) (xy 43.766764 -263.616633) (xy 43.8408 -263.636162) (xy 43.876976 -263.648698)
			(xy 43.885413 -263.651349) (xy 43.903083 -263.651349) (xy 43.91152 -263.648698) (xy 43.947704 -263.636189)
			(xy 44.021741 -263.616676) (xy 44.097181 -263.603592) (xy 44.173465 -263.597032) (xy 44.211748 -263.596628)
			(xy 44.252852 -263.597021) (xy 44.33471 -263.604611) (xy 44.415518 -263.619721) (xy 44.494587 -263.642222)
			(xy 44.571243 -263.671923) (xy 44.644832 -263.70857) (xy 44.714725 -263.751851) (xy 44.780326 -263.801396)
			(xy 44.841077 -263.856783) (xy 44.896457 -263.917538) (xy 44.945996 -263.983145) (xy 44.98927 -264.053042)
			(xy 45.025911 -264.126634) (xy 45.055605 -264.203292) (xy 45.078099 -264.282364) (xy 45.093201 -264.363173)
			(xy 45.100783 -264.445032) (xy 45.101256 -264.486136) (xy 45.100876 -264.524421) (xy 45.094334 -264.600709)
			(xy 45.08125 -264.676152) (xy 45.061722 -264.750188) (xy 45.049186 -264.786364) (xy 45.046516 -264.794796)
			(xy 45.046527 -264.812471) (xy 45.049186 -264.820908) (xy 45.061691 -264.857093) (xy 45.081205 -264.93113)
			(xy 45.09429 -265.006569) (xy 45.100852 -265.082853) (xy 45.101256 -265.121136) (xy 45.100768 -265.162238)
			(xy 45.09318 -265.24409) (xy 45.078073 -265.324893) (xy 45.055575 -265.403958) (xy 45.025878 -265.48061)
			(xy 44.989236 -265.554195) (xy 44.945961 -265.624085) (xy 44.896423 -265.689685) (xy 44.841043 -265.750434)
			(xy 44.780294 -265.805815) (xy 44.714695 -265.855354) (xy 44.644805 -265.89863) (xy 44.571221 -265.935274)
			(xy 44.49457 -265.964971) (xy 44.415505 -265.98747) (xy 44.334702 -266.002578) (xy 44.25285 -266.010167)
			(xy 44.211748 -266.010644) (xy 44.172821 -266.010248) (xy 44.095264 -266.003465) (xy 44.018597 -265.989929)
			(xy 43.943406 -265.969745) (xy 43.906694 -265.956796) (xy 43.898145 -265.954032) (xy 43.880191 -265.954032)
			(xy 43.871642 -265.956796) (xy 43.834927 -265.969735) (xy 43.759736 -265.989918) (xy 43.68307 -266.003453)
			(xy 43.605514 -266.010238) (xy 43.566588 -266.010644) (xy 43.527662 -266.010236) (xy 43.450105 -266.003457)
			(xy 43.373438 -265.989924) (xy 43.298246 -265.969743) (xy 43.261534 -265.956796) (xy 43.252985 -265.954032)
			(xy 43.235031 -265.954032) (xy 43.226482 -265.956796) (xy 43.189773 -265.969752) (xy 43.11458 -265.98993)
			(xy 43.037912 -266.003461) (xy 42.960355 -266.01024) (xy 42.921428 -266.010644) (xy 42.880327 -266.010107)
			(xy 42.798476 -266.002525) (xy 42.717673 -265.987423) (xy 42.638608 -265.96493) (xy 42.561956 -265.935238)
			(xy 42.488371 -265.8986) (xy 42.41848 -265.855328) (xy 42.352879 -265.805793) (xy 42.292129 -265.750416)
			(xy 42.236748 -265.68967) (xy 42.187208 -265.624073) (xy 42.143932 -265.554185) (xy 42.107288 -265.480603)
			(xy 42.077591 -265.403953) (xy 42.055092 -265.32489) (xy 42.039984 -265.244088) (xy 42.032396 -265.162237)
			(xy 42.03192 -265.121136) (xy 42.032293 -265.082851) (xy 42.038837 -265.006563) (xy 42.051923 -264.93112)
			(xy 42.071453 -264.857084) (xy 42.08399 -264.820908) (xy 42.086622 -264.812467) (xy 42.086633 -264.794801)
			(xy 42.08399 -264.786364) (xy 42.077132 -264.766552) (xy 42.072306 -264.752074) (xy 42.048684 -264.733278)
			(xy 41.925748 -264.722102) (xy 41.899078 -264.736326) (xy 41.891712 -264.749534) (xy 41.870455 -264.787173)
			(xy 41.821704 -264.858563) (xy 41.766257 -264.924886) (xy 41.704637 -264.985518) (xy 41.637427 -265.039887)
			(xy 41.565259 -265.087479) (xy 41.488815 -265.127845) (xy 41.408815 -265.160606) (xy 41.326015 -265.185452)
			(xy 41.241195 -265.202148) (xy 41.155156 -265.210537) (xy 41.111932 -265.211052) (xy 41.073001 -265.210601)
			(xy 40.995438 -265.203762) (xy 40.918771 -265.19017) (xy 40.843585 -265.169927) (xy 40.806878 -265.15695)
			(xy 40.798329 -265.154186) (xy 40.780375 -265.154186) (xy 40.771826 -265.15695) (xy 40.735115 -265.169918)
			(xy 40.65993 -265.190162) (xy 40.583264 -265.203761) (xy 40.505703 -265.210612) (xy 40.466772 -265.211052)
			(xy 40.42784 -265.210619) (xy 40.350278 -265.203775) (xy 40.27361 -265.190177) (xy 40.198425 -265.16993)
			(xy 40.161718 -265.15695) (xy 40.153169 -265.154186) (xy 40.135215 -265.154186) (xy 40.126666 -265.15695)
			(xy 40.089961 -265.169935) (xy 40.014774 -265.190174) (xy 39.938106 -265.203769) (xy 39.860544 -265.210614)
			(xy 39.821612 -265.211052) (xy 39.780503 -265.210536) (xy 39.698635 -265.20295) (xy 39.617817 -265.187841)
			(xy 39.538738 -265.165339) (xy 39.462073 -265.135634) (xy 39.388477 -265.098982) (xy 39.318577 -265.055695)
			(xy 39.252969 -265.006141) (xy 39.192215 -264.950745) (xy 39.136832 -264.889978) (xy 39.087293 -264.82436)
			(xy 39.044021 -264.75445) (xy 39.007386 -264.680845) (xy 38.977699 -264.604174) (xy 38.955214 -264.52509)
			(xy 38.940123 -264.444268) (xy 38.932555 -264.362399) (xy 38.932104 -264.32129) (xy 38.624204 -264.32129)
			(xy 38.668004 -264.37184) (xy 38.717132 -264.440831) (xy 38.759479 -264.51418) (xy 38.794662 -264.591222)
			(xy 38.822362 -264.671259) (xy 38.842329 -264.753567) (xy 38.854383 -264.837401) (xy 38.858413 -264.922)
			(xy 38.854383 -265.006599) (xy 38.842329 -265.090433) (xy 38.822362 -265.172741) (xy 38.794662 -265.252778)
			(xy 38.759479 -265.32982) (xy 38.717132 -265.403169) (xy 38.668004 -265.47216) (xy 38.612542 -265.536169)
			(xy 38.551246 -265.594617) (xy 38.484672 -265.646973) (xy 38.413422 -265.692764) (xy 38.338143 -265.731575)
			(xy 38.259515 -265.763055) (xy 38.178252 -265.786919) (xy 38.095087 -265.80295) (xy 38.010776 -265.811003)
			(xy 37.968428 -265.811508) (xy 37.922033 -265.810915) (xy 37.829745 -265.801273) (xy 37.738961 -265.78208)
			(xy 37.650667 -265.753544) (xy 37.608002 -265.735308) (xy 37.59806 -265.731502) (xy 37.576796 -265.731502)
			(xy 37.566854 -265.735308) (xy 37.524188 -265.753544) (xy 37.435897 -265.78209) (xy 37.345113 -265.801286)
			(xy 37.252824 -265.810922) (xy 37.206428 -265.811508) (xy 37.164078 -265.811021) (xy 37.079761 -265.802972)
			(xy 36.996591 -265.786945) (xy 36.915321 -265.763084) (xy 36.836688 -265.731606) (xy 36.761402 -265.692796)
			(xy 36.690147 -265.647005) (xy 36.623567 -265.594648) (xy 36.562266 -265.536199) (xy 36.506798 -265.472188)
			(xy 36.457666 -265.403194) (xy 36.415315 -265.329842) (xy 36.380129 -265.252796) (xy 36.352426 -265.172755)
			(xy 36.332457 -265.090442) (xy 36.320402 -265.006604) (xy 36.316372 -264.922) (xy 34.73105 -264.922)
			(xy 34.722849 -264.950823) (xy 34.693154 -265.027476) (xy 34.656513 -265.101062) (xy 34.61324 -265.170953)
			(xy 34.563702 -265.236553) (xy 34.508323 -265.297303) (xy 34.447575 -265.352684) (xy 34.381976 -265.402224)
			(xy 34.312086 -265.4455) (xy 34.238502 -265.482143) (xy 34.16185 -265.51184) (xy 34.082785 -265.534338)
			(xy 34.001982 -265.549445) (xy 33.92013 -265.557032) (xy 33.879028 -265.557508) (xy 33.832633 -265.556915)
			(xy 33.740345 -265.547273) (xy 33.649561 -265.52808) (xy 33.561267 -265.499544) (xy 33.518602 -265.481308)
			(xy 33.50866 -265.477502) (xy 33.487396 -265.477502) (xy 33.477454 -265.481308) (xy 33.434788 -265.499544)
			(xy 33.346497 -265.52809) (xy 33.255713 -265.547286) (xy 33.163424 -265.556922) (xy 33.117028 -265.557508)
			(xy 33.077261 -265.557075) (xy 32.998039 -265.550038) (xy 32.919763 -265.535954) (xy 32.843057 -265.514936)
			(xy 32.768534 -265.487152) (xy 32.732472 -265.470386) (xy 32.721971 -265.466054) (xy 32.699285 -265.466054)
			(xy 32.688784 -265.470386) (xy 32.652723 -265.487156) (xy 32.578197 -265.51493) (xy 32.501491 -265.535947)
			(xy 32.423215 -265.550037) (xy 32.343995 -265.557089) (xy 32.304228 -265.557508) (xy 32.263125 -265.557021)
			(xy 32.18127 -265.549439) (xy 32.100464 -265.534336) (xy 32.021396 -265.511841) (xy 31.944741 -265.482147)
			(xy 31.871153 -265.445507) (xy 31.80126 -265.402232) (xy 31.735658 -265.352694) (xy 31.674906 -265.297313)
			(xy 31.619524 -265.236564) (xy 31.569983 -265.170963) (xy 31.526707 -265.101071) (xy 31.490064 -265.027484)
			(xy 31.460368 -264.95083) (xy 31.437871 -264.871763) (xy 31.422765 -264.790957) (xy 31.41518 -264.709103)
			(xy 31.41472 -264.668) (xy 17.448323 -264.668) (xy 17.446901 -264.676162) (xy 17.427313 -264.750193)
			(xy 17.414748 -264.786364) (xy 17.412079 -264.794796) (xy 17.412091 -264.812471) (xy 17.414748 -264.820908)
			(xy 17.427278 -264.85709) (xy 17.446855 -264.931121) (xy 17.460005 -265.00656) (xy 17.466634 -265.082848)
			(xy 17.467072 -265.121136) (xy 17.466682 -265.162248) (xy 17.45909 -265.244122) (xy 17.443976 -265.324945)
			(xy 17.421467 -265.404029) (xy 17.391756 -265.480698) (xy 17.355096 -265.554298) (xy 17.3118 -265.6242)
			(xy 17.262238 -265.689809) (xy 17.206833 -265.750564) (xy 17.146058 -265.805947) (xy 17.080431 -265.855484)
			(xy 17.010513 -265.898754) (xy 16.936899 -265.935387) (xy 16.86022 -265.96507) (xy 16.781128 -265.98755)
			(xy 16.700299 -266.002635) (xy 16.618422 -266.010197) (xy 16.57731 -266.010644) (xy 16.538384 -266.010229)
			(xy 16.460827 -266.003452) (xy 16.38416 -265.989922) (xy 16.308969 -265.969742) (xy 16.272256 -265.956796)
			(xy 16.263707 -265.954032) (xy 16.245753 -265.954032) (xy 16.237204 -265.956796) (xy 16.200492 -265.969745)
			(xy 16.125301 -265.989926) (xy 16.048633 -266.003458) (xy 15.971076 -266.010239) (xy 15.93215 -266.010644)
			(xy 15.893223 -266.010247) (xy 15.815666 -266.003465) (xy 15.738999 -265.989929) (xy 15.663808 -265.969745)
			(xy 15.627096 -265.956796) (xy 15.618547 -265.954032) (xy 15.600593 -265.954032) (xy 15.592044 -265.956796)
			(xy 15.555329 -265.969734) (xy 15.480138 -265.989917) (xy 15.403472 -266.003453) (xy 15.325916 -266.010238)
			(xy 15.28699 -266.010644) (xy 15.245883 -266.010197) (xy 15.164018 -266.002612) (xy 15.083203 -265.987506)
			(xy 15.004126 -265.96501) (xy 14.927461 -265.935315) (xy 14.853863 -265.898674) (xy 14.783958 -265.855399)
			(xy 14.718344 -265.80586) (xy 14.65758 -265.75048) (xy 14.602184 -265.68973) (xy 14.552629 -265.624128)
			(xy 14.509336 -265.554235) (xy 14.472677 -265.480646) (xy 14.442962 -265.403989) (xy 14.420445 -265.324917)
			(xy 14.40532 -265.244106) (xy 14.397713 -265.162243) (xy 14.397228 -265.121136) (xy 14.397645 -265.082846)
			(xy 14.404249 -265.006553) (xy 14.417395 -264.93111) (xy 14.436985 -264.857079) (xy 14.449552 -264.820908)
			(xy 14.452185 -264.812467) (xy 14.452196 -264.7948) (xy 14.449552 -264.786364) (xy 14.442694 -264.766552)
			(xy 14.437868 -264.752074) (xy 14.414246 -264.733278) (xy 14.29131 -264.722102) (xy 14.26464 -264.736326)
			(xy 14.257274 -264.749534) (xy 14.236045 -264.78719) (xy 14.187291 -264.85858) (xy 14.131841 -264.924903)
			(xy 14.070219 -264.985535) (xy 14.003005 -265.039902) (xy 13.930835 -265.087493) (xy 13.854388 -265.127858)
			(xy 13.774385 -265.160617) (xy 13.691583 -265.18546) (xy 13.60676 -265.202153) (xy 13.520719 -265.210539)
			(xy 13.477494 -265.211052) (xy 13.438562 -265.210612) (xy 13.361 -265.20377) (xy 13.284332 -265.190175)
			(xy 13.209147 -265.169929) (xy 13.17244 -265.15695) (xy 13.163891 -265.154186) (xy 13.145937 -265.154186)
			(xy 13.137388 -265.15695) (xy 13.100681 -265.169929) (xy 13.025494 -265.19017) (xy 12.948827 -265.203766)
			(xy 12.871265 -265.210613) (xy 12.832334 -265.211052) (xy 12.793403 -265.2106) (xy 12.715841 -265.203762)
			(xy 12.639173 -265.19017) (xy 12.563987 -265.169927) (xy 12.52728 -265.15695) (xy 12.518731 -265.154186)
			(xy 12.500777 -265.154186) (xy 12.492228 -265.15695) (xy 12.455517 -265.169918) (xy 12.380332 -265.190161)
			(xy 12.303666 -265.203761) (xy 12.226105 -265.210612) (xy 12.187174 -265.211052) (xy 12.146059 -265.210612)
			(xy 12.06418 -265.203022) (xy 11.983351 -265.18791) (xy 11.904261 -265.165405) (xy 11.827584 -265.135698)
			(xy 11.753976 -265.099044) (xy 11.684064 -265.055753) (xy 11.618444 -265.006197) (xy 11.557676 -264.950798)
			(xy 11.50228 -264.890029) (xy 11.452726 -264.824407) (xy 11.409439 -264.754493) (xy 11.372787 -264.680883)
			(xy 11.343083 -264.604205) (xy 11.320581 -264.525114) (xy 11.305473 -264.444284) (xy 11.297886 -264.362405)
			(xy 11.297412 -264.32129) (xy 11.182404 -264.32129) (xy 11.182519 -264.321764) (xy 11.194572 -264.405599)
			(xy 11.198603 -264.4902) (xy 11.194572 -264.574801) (xy 11.182519 -264.658636) (xy 11.162551 -264.740945)
			(xy 11.134849 -264.820984) (xy 11.099665 -264.898027) (xy 11.057316 -264.971377) (xy 11.008187 -265.040369)
			(xy 10.952722 -265.104379) (xy 10.891424 -265.162827) (xy 10.824848 -265.215183) (xy 10.753596 -265.260973)
			(xy 10.678315 -265.299784) (xy 10.599685 -265.331263) (xy 10.518418 -265.355124) (xy 10.435252 -265.371153)
			(xy 10.350938 -265.379204) (xy 10.30859 -265.379708) (xy 10.262194 -265.379129) (xy 10.169906 -265.369483)
			(xy 10.079122 -265.350286) (xy 9.990829 -265.321746) (xy 9.948164 -265.303508) (xy 9.938222 -265.299702)
			(xy 9.916958 -265.299702) (xy 9.907016 -265.303508) (xy 9.864355 -265.321756) (xy 9.776062 -265.350299)
			(xy 9.685277 -265.369491) (xy 9.592986 -265.379124) (xy 9.54659 -265.379708) (xy 9.504242 -265.379204)
			(xy 9.419928 -265.371153) (xy 9.336762 -265.355124) (xy 9.255495 -265.331263) (xy 9.176865 -265.299784)
			(xy 9.101584 -265.260973) (xy 9.030332 -265.215183) (xy 8.963756 -265.162827) (xy 8.902458 -265.104379)
			(xy 8.846993 -265.040369) (xy 8.797864 -264.971377) (xy 8.755515 -264.898027) (xy 8.720331 -264.820984)
			(xy 8.692629 -264.740945) (xy 8.672661 -264.658636) (xy 8.660608 -264.574801) (xy 8.656578 -264.4902)
			(xy 7.150642 -264.4902) (xy 7.159123 -264.570799) (xy 7.159752 -264.6172) (xy 7.159288 -264.658311)
			(xy 7.1517 -264.740181) (xy 7.136589 -264.821001) (xy 7.114084 -264.900082) (xy 7.084378 -264.976749)
			(xy 7.047722 -265.050347) (xy 7.004432 -265.120249) (xy 6.954875 -265.185857) (xy 6.899475 -265.246612)
			(xy 6.838705 -265.301995) (xy 6.773083 -265.351533) (xy 6.703169 -265.394804) (xy 6.62956 -265.431439)
			(xy 6.552885 -265.461124) (xy 6.473798 -265.483606) (xy 6.392973 -265.498694) (xy 6.311101 -265.506259)
			(xy 6.26999 -265.506708) (xy 6.231566 -265.506323) (xy 6.155003 -265.499731) (xy 6.079295 -265.486552)
			(xy 6.005007 -265.466887) (xy 5.932695 -265.44088) (xy 5.897626 -265.425174) (xy 5.886671 -265.420782)
			(xy 5.863105 -265.421444) (xy 5.852414 -265.426444) (xy 5.813556 -265.446705) (xy 5.732619 -265.480319)
			(xy 5.648772 -265.50582) (xy 5.562825 -265.522962) (xy 5.47561 -265.53158) (xy 5.43179 -265.532108)
			(xy 5.392023 -265.53169) (xy 5.312801 -265.524649) (xy 5.234524 -265.510562) (xy 5.157818 -265.489541)
			(xy 5.083296 -265.461754) (xy 5.047234 -265.444986) (xy 5.036733 -265.440654) (xy 5.014047 -265.440654)
			(xy 5.003546 -265.444986) (xy 4.967476 -265.461733) (xy 4.892952 -265.489512) (xy 4.816248 -265.510534)
			(xy 4.737975 -265.524629) (xy 4.658756 -265.531687) (xy 4.61899 -265.532108) (xy 4.583863 -265.531813)
			(xy 4.513823 -265.526345) (xy 4.444434 -265.515356) (xy 4.410202 -265.50747) (xy 4.396994 -265.504168)
			(xy 4.37134 -265.511534) (xy 4.29133 -265.593068) (xy 4.284472 -265.618468) (xy 4.288028 -265.631676)
			(xy 4.297104 -265.668316) (xy 4.309776 -265.742735) (xy 4.316106 -265.817959) (xy 4.316476 -265.855704)
			(xy 4.316047 -265.895273) (xy 4.309042 -265.974101) (xy 4.295062 -266.051995) (xy 4.274218 -266.128339)
			(xy 4.26085 -266.165584) (xy 4.258039 -266.174257) (xy 4.258027 -266.192476) (xy 4.26085 -266.201144)
			(xy 4.274212 -266.238392) (xy 4.29506 -266.314734) (xy 4.309044 -266.392627) (xy 4.316054 -266.471455)
			(xy 4.316476 -266.511024) (xy 4.316091 -266.549308) (xy 4.309551 -266.625597) (xy 4.296468 -266.701039)
			(xy 4.276941 -266.775076) (xy 4.264406 -266.811252) (xy 4.261745 -266.819686) (xy 4.261753 -266.837359)
			(xy 4.264406 -266.845796) (xy 4.276909 -266.881982) (xy 4.296423 -266.956019) (xy 4.309509 -267.031458)
			(xy 4.316071 -267.107741) (xy 4.316476 -267.146024) (xy 4.315972 -267.188372) (xy 4.307921 -267.272686)
			(xy 4.291892 -267.355852) (xy 4.268031 -267.437119) (xy 4.236552 -267.515749) (xy 4.197741 -267.59103)
			(xy 4.151951 -267.662282) (xy 4.099595 -267.728858) (xy 4.041147 -267.790156) (xy 3.977137 -267.845621)
			(xy 3.908145 -267.89475) (xy 3.834795 -267.937099) (xy 3.762751 -267.97) (xy 31.414217 -267.97) (xy 31.418248 -267.885399)
			(xy 31.430301 -267.801564) (xy 31.450269 -267.719255) (xy 31.477971 -267.639216) (xy 31.513155 -267.562173)
			(xy 31.555503 -267.488824) (xy 31.604632 -267.419831) (xy 31.660097 -267.355822) (xy 31.721395 -267.297374)
			(xy 31.787971 -267.245018) (xy 31.859223 -267.199227) (xy 31.934504 -267.160417) (xy 32.013134 -267.128938)
			(xy 32.0944 -267.105076) (xy 32.177566 -267.089047) (xy 32.26188 -267.080996) (xy 32.304228 -267.080492)
			(xy 32.343996 -267.080903) (xy 32.423218 -267.087946) (xy 32.501494 -267.102034) (xy 32.5782 -267.123057)
			(xy 32.652722 -267.150846) (xy 32.688784 -267.167614) (xy 32.699285 -267.171946) (xy 32.721971 -267.171946)
			(xy 32.732472 -267.167614) (xy 32.76854 -267.15086) (xy 32.843064 -267.123082) (xy 32.919768 -267.102063)
			(xy 32.998042 -267.087969) (xy 33.077261 -267.080912) (xy 33.117028 -267.080492) (xy 33.163423 -267.0811)
			(xy 33.255711 -267.090738) (xy 33.346494 -267.109926) (xy 33.434789 -267.138458) (xy 33.477454 -267.156692)
			(xy 33.487396 -267.160498) (xy 33.50866 -267.160498) (xy 33.518602 -267.156692) (xy 33.56126 -267.138438)
			(xy 33.649554 -267.109896) (xy 33.74034 -267.090706) (xy 33.832632 -267.081075) (xy 33.879028 -267.080492)
			(xy 33.921377 -267.08098) (xy 34.005692 -267.089031) (xy 34.08886 -267.10506) (xy 34.170128 -267.128922)
			(xy 34.24876 -267.160401) (xy 34.324043 -267.199212) (xy 34.395296 -267.245004) (xy 34.461874 -267.297361)
			(xy 34.523173 -267.35581) (xy 34.578639 -267.419821) (xy 34.627769 -267.488814) (xy 34.670118 -267.562165)
			(xy 34.705303 -267.63921) (xy 34.733006 -267.71925) (xy 34.752974 -267.801561) (xy 34.765028 -267.885397)
			(xy 34.769058 -267.97) (xy 34.765028 -268.054603) (xy 34.752974 -268.138439) (xy 34.733006 -268.22075)
			(xy 34.705303 -268.30079) (xy 34.670118 -268.377835) (xy 34.627769 -268.451186) (xy 34.578639 -268.520179)
			(xy 34.523173 -268.58419) (xy 34.461874 -268.642639) (xy 34.395296 -268.694996) (xy 34.324043 -268.740788)
			(xy 34.24876 -268.779599) (xy 34.170128 -268.811078) (xy 34.08886 -268.83494) (xy 34.005692 -268.850969)
			(xy 33.921377 -268.85902) (xy 33.879028 -268.859508) (xy 33.832633 -268.858915) (xy 33.740345 -268.849273)
			(xy 33.649561 -268.83008) (xy 33.561267 -268.801544) (xy 33.518602 -268.783308) (xy 33.50866 -268.779502)
			(xy 33.487396 -268.779502) (xy 33.477454 -268.783308) (xy 33.434788 -268.801544) (xy 33.346497 -268.83009)
			(xy 33.255713 -268.849286) (xy 33.163424 -268.858922) (xy 33.117028 -268.859508) (xy 33.077261 -268.859075)
			(xy 32.998039 -268.852038) (xy 32.919763 -268.837954) (xy 32.843057 -268.816936) (xy 32.768534 -268.789152)
			(xy 32.732472 -268.772386) (xy 32.721971 -268.768054) (xy 32.699285 -268.768054) (xy 32.688784 -268.772386)
			(xy 32.652723 -268.789156) (xy 32.578197 -268.81693) (xy 32.501491 -268.837947) (xy 32.423215 -268.852037)
			(xy 32.343995 -268.859089) (xy 32.304228 -268.859508) (xy 32.26188 -268.859004) (xy 32.177566 -268.850953)
			(xy 32.0944 -268.834924) (xy 32.013134 -268.811062) (xy 31.934504 -268.779583) (xy 31.859223 -268.740773)
			(xy 31.787971 -268.694982) (xy 31.721395 -268.642626) (xy 31.660097 -268.584178) (xy 31.604632 -268.520169)
			(xy 31.555503 -268.451176) (xy 31.513155 -268.377827) (xy 31.477971 -268.300784) (xy 31.450269 -268.220745)
			(xy 31.430301 -268.138436) (xy 31.418248 -268.054601) (xy 31.414217 -267.97) (xy 3.762751 -267.97)
			(xy 3.757752 -267.972283) (xy 3.677713 -267.999985) (xy 3.595404 -268.019953) (xy 3.511569 -268.032006)
			(xy 3.426968 -268.036037) (xy 3.342367 -268.032006) (xy 3.258532 -268.019953) (xy 3.176223 -267.999985)
			(xy 3.096184 -267.972283) (xy 3.019141 -267.937099) (xy 2.945791 -267.89475) (xy 2.876799 -267.845621)
			(xy 2.812789 -267.790156) (xy 2.754341 -267.728858) (xy 2.701985 -267.662282) (xy 2.656195 -267.59103)
			(xy 2.617384 -267.515749) (xy 2.585905 -267.437119) (xy 2.562044 -267.355852) (xy 2.546015 -267.272686)
			(xy 2.537964 -267.188372) (xy 2.53746 -267.146024) (xy 0.509016 -267.146024) (xy 0.509016 -274.139406)
			(xy 13.258292 -274.139406) (xy 13.258752 -274.096822) (xy 13.266866 -274.012043) (xy 13.283048 -273.928428)
			(xy 13.30715 -273.846742) (xy 13.338952 -273.767736) (xy 13.358114 -273.729704) (xy 13.36332 -273.718524)
			(xy 13.363324 -273.693891) (xy 13.358114 -273.682714) (xy 13.33897 -273.644674) (xy 13.307179 -273.565667)
			(xy 13.283083 -273.483983) (xy 13.266901 -273.40037) (xy 13.258782 -273.315594) (xy 13.258292 -273.273012)
			(xy 13.258761 -273.230474) (xy 13.26684 -273.145783) (xy 13.282974 -273.062251) (xy 13.307015 -272.980643)
			(xy 13.338744 -272.901705) (xy 13.377869 -272.826159) (xy 13.400532 -272.790158) (xy 13.405487 -272.781745)
			(xy 13.409223 -272.762599) (xy 13.405487 -272.743453) (xy 13.400532 -272.73504) (xy 13.377896 -272.699048)
			(xy 13.338805 -272.623536) (xy 13.307095 -272.54464) (xy 13.283055 -272.463079) (xy 13.266904 -272.379597)
			(xy 13.258789 -272.294955) (xy 13.258292 -272.25244) (xy 13.258811 -272.209852) (xy 13.266975 -272.125067)
			(xy 13.283204 -272.041451) (xy 13.307349 -271.959768) (xy 13.339189 -271.880767) (xy 13.358368 -271.842738)
			(xy 13.363547 -271.831549) (xy 13.363566 -271.806926) (xy 13.358368 -271.795748) (xy 13.339186 -271.757721)
			(xy 13.307343 -271.678719) (xy 13.283196 -271.597036) (xy 13.266967 -271.51342) (xy 13.258803 -271.428634)
			(xy 13.258292 -271.386046) (xy 13.258857 -271.344934) (xy 13.266439 -271.26306) (xy 13.281544 -271.182235)
			(xy 13.304041 -271.103149) (xy 13.33374 -271.026475) (xy 13.370387 -270.952869) (xy 13.413669 -270.882959)
			(xy 13.463216 -270.81734) (xy 13.518607 -270.756572) (xy 13.579369 -270.701175) (xy 13.644983 -270.651621)
			(xy 13.714889 -270.608332) (xy 13.788491 -270.571677) (xy 13.865161 -270.541971) (xy 13.944245 -270.519465)
			(xy 14.025069 -270.504352) (xy 14.106942 -270.496761) (xy 14.148054 -270.496284) (xy 14.19152 -270.496839)
			(xy 14.278031 -270.505397) (xy 14.363297 -270.522339) (xy 14.446508 -270.547503) (xy 14.48689 -270.563594)
			(xy 14.500098 -270.568928) (xy 14.527276 -270.564864) (xy 14.618462 -270.491204) (xy 14.628114 -270.46555)
			(xy 14.625574 -270.45158) (xy 14.619032 -270.412731) (xy 14.612037 -270.334255) (xy 14.611604 -270.294862)
			(xy 14.612142 -270.252274) (xy 14.620303 -270.167491) (xy 14.636528 -270.083875) (xy 14.660669 -270.002192)
			(xy 14.692504 -269.923189) (xy 14.71168 -269.88516) (xy 14.716911 -269.87399) (xy 14.716896 -269.849349)
			(xy 14.71168 -269.83817) (xy 14.692507 -269.800138) (xy 14.660662 -269.721138) (xy 14.636514 -269.639456)
			(xy 14.620282 -269.555841) (xy 14.612116 -269.471056) (xy 14.611604 -269.428468) (xy 14.612108 -269.386107)
			(xy 14.620161 -269.30177) (xy 14.636195 -269.21858) (xy 14.660063 -269.13729) (xy 14.691551 -269.058638)
			(xy 14.730373 -268.983335) (xy 14.776176 -268.912063) (xy 14.828547 -268.845467) (xy 14.887012 -268.784152)
			(xy 14.95104 -268.728671) (xy 15.020052 -268.679528) (xy 15.093422 -268.637168) (xy 15.170487 -268.601973)
			(xy 15.250549 -268.574264) (xy 15.332882 -268.55429) (xy 15.416741 -268.542233) (xy 15.501366 -268.538202)
			(xy 15.585991 -268.542233) (xy 15.66985 -268.55429) (xy 15.752183 -268.574264) (xy 15.832245 -268.601973)
			(xy 15.90931 -268.637168) (xy 15.98268 -268.679528) (xy 16.051692 -268.728671) (xy 16.11572 -268.784152)
			(xy 16.174185 -268.845467) (xy 16.226556 -268.912063) (xy 16.272359 -268.983335) (xy 16.311181 -269.058638)
			(xy 16.342669 -269.13729) (xy 16.366537 -269.21858) (xy 16.382571 -269.30177) (xy 16.390624 -269.386107)
			(xy 16.391128 -269.428468) (xy 16.39061 -269.471056) (xy 16.382445 -269.555841) (xy 16.366216 -269.639457)
			(xy 16.342071 -269.72114) (xy 16.310231 -269.800141) (xy 16.291052 -269.83817) (xy 16.286066 -269.849402)
			(xy 16.286051 -269.873936) (xy 16.291052 -269.88516) (xy 16.310231 -269.923189) (xy 16.342075 -270.00219)
			(xy 16.366223 -270.083872) (xy 16.382453 -270.167489) (xy 16.390617 -270.252274) (xy 16.391128 -270.294862)
			(xy 16.390665 -270.335977) (xy 16.383081 -270.417857) (xy 16.367974 -270.498688) (xy 16.345473 -270.57778)
			(xy 16.31577 -270.654459) (xy 16.279118 -270.728069) (xy 16.23583 -270.797983) (xy 16.186275 -270.863605)
			(xy 16.130877 -270.924375) (xy 16.070108 -270.979773) (xy 16.004487 -271.029328) (xy 15.934573 -271.072616)
			(xy 15.860962 -271.109268) (xy 15.784284 -271.138972) (xy 15.705192 -271.161473) (xy 15.624361 -271.176581)
			(xy 15.542481 -271.184165) (xy 15.501366 -271.184624) (xy 15.4579 -271.184062) (xy 15.37139 -271.175506)
			(xy 15.286124 -271.158566) (xy 15.202912 -271.133404) (xy 15.16253 -271.117314) (xy 15.149322 -271.11198)
			(xy 15.122144 -271.116044) (xy 15.030958 -271.189704) (xy 15.021306 -271.215358) (xy 15.023846 -271.229328)
			(xy 15.030389 -271.268177) (xy 15.037383 -271.346653) (xy 15.037816 -271.386046) (xy 15.03729 -271.428634)
			(xy 15.029128 -271.513418) (xy 15.0129 -271.597034) (xy 14.988757 -271.678717) (xy 14.956918 -271.757719)
			(xy 14.93774 -271.795748) (xy 14.932703 -271.806962) (xy 14.932722 -271.831513) (xy 14.93774 -271.842738)
			(xy 14.956918 -271.880767) (xy 14.957254 -271.8816) (xy 35.06978 -271.8816) (xy 35.070168 -271.843316)
			(xy 35.076707 -271.767027) (xy 35.089789 -271.691585) (xy 35.109315 -271.617548) (xy 35.12185 -271.581372)
			(xy 35.124501 -271.572935) (xy 35.124501 -271.555265) (xy 35.12185 -271.546828) (xy 35.109324 -271.51065)
			(xy 35.089817 -271.43661) (xy 35.076737 -271.361169) (xy 35.070182 -271.284883) (xy 35.06978 -271.2466)
			(xy 35.070284 -271.204252) (xy 35.078335 -271.119938) (xy 35.094364 -271.036772) (xy 35.118225 -270.955505)
			(xy 35.149704 -270.876875) (xy 35.188515 -270.801594) (xy 35.234305 -270.730342) (xy 35.286661 -270.663766)
			(xy 35.345109 -270.602468) (xy 35.409119 -270.547003) (xy 35.478111 -270.497874) (xy 35.551461 -270.455525)
			(xy 35.628504 -270.420341) (xy 35.708543 -270.392639) (xy 35.790852 -270.372671) (xy 35.874687 -270.360618)
			(xy 35.959288 -270.356588) (xy 36.043889 -270.360618) (xy 36.127724 -270.372671) (xy 36.210033 -270.392639)
			(xy 36.290072 -270.420341) (xy 36.367115 -270.455525) (xy 36.440465 -270.497874) (xy 36.509457 -270.547003)
			(xy 36.573467 -270.602468) (xy 36.631915 -270.663766) (xy 36.684271 -270.730342) (xy 36.730061 -270.801594)
			(xy 36.768872 -270.876875) (xy 36.800351 -270.955505) (xy 36.824212 -271.036772) (xy 36.840241 -271.119938)
			(xy 36.848292 -271.204252) (xy 36.848796 -271.2466) (xy 36.848409 -271.284884) (xy 36.84187 -271.361173)
			(xy 36.828788 -271.436615) (xy 36.809261 -271.510652) (xy 36.796726 -271.546828) (xy 36.794076 -271.555265)
			(xy 36.794076 -271.572935) (xy 36.796726 -271.581372) (xy 36.808338 -271.614766) (xy 36.826862 -271.683004)
			(xy 36.839896 -271.7525) (xy 36.84397 -271.78762) (xy 36.845629 -271.798121) (xy 36.856273 -271.816498)
			(xy 36.864544 -271.82318) (xy 36.89808 -271.848219) (xy 36.960767 -271.903681) (xy 37.017965 -271.964787)
			(xy 37.06917 -272.030997) (xy 37.113927 -272.101724) (xy 37.151842 -272.176344) (xy 37.182578 -272.254196)
			(xy 37.205864 -272.334591) (xy 37.221494 -272.416818) (xy 37.22933 -272.50015) (xy 37.229796 -272.542)
			(xy 37.229409 -272.580284) (xy 37.22287 -272.656573) (xy 37.209788 -272.732015) (xy 37.190261 -272.806052)
			(xy 37.177726 -272.842228) (xy 37.175076 -272.850665) (xy 37.175076 -272.868335) (xy 37.177726 -272.876772)
			(xy 37.190251 -272.912951) (xy 37.209759 -272.98699) (xy 37.222839 -273.062431) (xy 37.229394 -273.138717)
			(xy 37.229796 -273.177) (xy 37.229409 -273.215284) (xy 37.22287 -273.291573) (xy 37.209788 -273.367015)
			(xy 37.190261 -273.441052) (xy 37.177726 -273.477228) (xy 37.175076 -273.485665) (xy 37.175076 -273.503335)
			(xy 37.177726 -273.511772) (xy 37.190251 -273.547951) (xy 37.209759 -273.62199) (xy 37.222839 -273.697431)
			(xy 37.229394 -273.773717) (xy 37.229796 -273.812) (xy 37.229292 -273.854348) (xy 37.221241 -273.938662)
			(xy 37.205212 -274.021828) (xy 37.181351 -274.103095) (xy 37.149872 -274.181725) (xy 37.111061 -274.257006)
			(xy 37.065271 -274.328258) (xy 37.012915 -274.394834) (xy 36.954467 -274.456132) (xy 36.890457 -274.511597)
			(xy 36.821465 -274.560726) (xy 36.748115 -274.603075) (xy 36.671072 -274.638259) (xy 36.591033 -274.665961)
			(xy 36.508724 -274.685929) (xy 36.424889 -274.697982) (xy 36.340288 -274.702013) (xy 36.255687 -274.697982)
			(xy 36.171852 -274.685929) (xy 36.089543 -274.665961) (xy 36.009504 -274.638259) (xy 35.932461 -274.603075)
			(xy 35.859111 -274.560726) (xy 35.790119 -274.511597) (xy 35.726109 -274.456132) (xy 35.667661 -274.394834)
			(xy 35.615305 -274.328258) (xy 35.569515 -274.257006) (xy 35.530704 -274.181725) (xy 35.499225 -274.103095)
			(xy 35.475364 -274.021828) (xy 35.459335 -273.938662) (xy 35.451284 -273.854348) (xy 35.45078 -273.812)
			(xy 35.451168 -273.773716) (xy 35.457707 -273.697427) (xy 35.470789 -273.621985) (xy 35.490315 -273.547948)
			(xy 35.50285 -273.511772) (xy 35.505501 -273.503335) (xy 35.505501 -273.485665) (xy 35.50285 -273.477228)
			(xy 35.490324 -273.44105) (xy 35.470817 -273.36701) (xy 35.457737 -273.291569) (xy 35.451182 -273.215283)
			(xy 35.45078 -273.177) (xy 35.451168 -273.138716) (xy 35.457707 -273.062427) (xy 35.470789 -272.986985)
			(xy 35.490315 -272.912948) (xy 35.50285 -272.876772) (xy 35.505501 -272.868335) (xy 35.505501 -272.850665)
			(xy 35.50285 -272.842228) (xy 35.491237 -272.808834) (xy 35.472714 -272.740596) (xy 35.45968 -272.6711)
			(xy 35.455606 -272.63598) (xy 35.453956 -272.625477) (xy 35.443306 -272.6071) (xy 35.435032 -272.60042)
			(xy 35.40149 -272.575388) (xy 35.338805 -272.519925) (xy 35.281607 -272.458817) (xy 35.230404 -272.392607)
			(xy 35.185647 -272.321878) (xy 35.147733 -272.247258) (xy 35.116997 -272.169406) (xy 35.093711 -272.08901)
			(xy 35.078081 -272.006782) (xy 35.070246 -271.92345) (xy 35.06978 -271.8816) (xy 14.957254 -271.8816)
			(xy 14.988761 -271.959768) (xy 15.012909 -272.041451) (xy 15.029139 -272.125067) (xy 15.037304 -272.209852)
			(xy 15.037816 -272.25244) (xy 15.037301 -272.294982) (xy 15.029153 -272.379674) (xy 15.012965 -272.463203)
			(xy 14.988883 -272.544808) (xy 14.957128 -272.623744) (xy 14.917989 -272.69929) (xy 14.895322 -272.735294)
			(xy 14.890471 -272.743746) (xy 14.886786 -272.76286) (xy 14.890442 -272.78198) (xy 14.895322 -272.790412)
			(xy 14.917954 -272.8264) (xy 14.957014 -272.901917) (xy 14.988686 -272.980818) (xy 15.012682 -273.062382)
			(xy 15.028783 -273.145864) (xy 15.036841 -273.230501) (xy 15.037308 -273.273012) (xy 15.036814 -273.315595)
			(xy 15.028708 -273.400373) (xy 15.012534 -273.483988) (xy 14.988439 -273.565674) (xy 14.956644 -273.644681)
			(xy 14.937486 -273.682714) (xy 14.932476 -273.693937) (xy 14.93248 -273.718479) (xy 14.937486 -273.729704)
			(xy 14.956636 -273.76774) (xy 14.988426 -273.846749) (xy 15.012521 -273.928434) (xy 15.028702 -274.012047)
			(xy 15.036819 -274.096824) (xy 15.037308 -274.139406) (xy 15.036804 -274.181754) (xy 15.028753 -274.266068)
			(xy 15.012724 -274.349234) (xy 14.988863 -274.430501) (xy 14.957384 -274.509131) (xy 14.918573 -274.584412)
			(xy 14.872783 -274.655664) (xy 14.820427 -274.72224) (xy 14.761979 -274.783538) (xy 14.697969 -274.839003)
			(xy 14.628977 -274.888132) (xy 14.555627 -274.930481) (xy 14.478584 -274.965665) (xy 14.398545 -274.993367)
			(xy 14.316236 -275.013335) (xy 14.232401 -275.025388) (xy 14.1478 -275.029419) (xy 14.063199 -275.025388)
			(xy 13.979364 -275.013335) (xy 13.897055 -274.993367) (xy 13.817016 -274.965665) (xy 13.739973 -274.930481)
			(xy 13.666623 -274.888132) (xy 13.597631 -274.839003) (xy 13.533621 -274.783538) (xy 13.475173 -274.72224)
			(xy 13.422817 -274.655664) (xy 13.377027 -274.584412) (xy 13.338216 -274.509131) (xy 13.306737 -274.430501)
			(xy 13.282876 -274.349234) (xy 13.266847 -274.266068) (xy 13.258796 -274.181754) (xy 13.258292 -274.139406)
			(xy 0.509016 -274.139406) (xy 0.509016 -277.895304) (xy 13.241528 -277.895304) (xy 13.242039 -277.852716)
			(xy 13.250206 -277.767931) (xy 13.266437 -277.684315) (xy 13.290584 -277.602632) (xy 13.322425 -277.523631)
			(xy 13.341604 -277.485602) (xy 13.346812 -277.474423) (xy 13.346815 -277.449789) (xy 13.341604 -277.438612)
			(xy 13.322411 -277.40059) (xy 13.29057 -277.321587) (xy 13.266425 -277.239903) (xy 13.250198 -277.156285)
			(xy 13.242037 -277.071499) (xy 13.241528 -277.02891) (xy 13.242032 -276.986549) (xy 13.250085 -276.902212)
			(xy 13.266119 -276.819022) (xy 13.289987 -276.737732) (xy 13.321475 -276.65908) (xy 13.360297 -276.583777)
			(xy 13.4061 -276.512505) (xy 13.458471 -276.445909) (xy 13.516936 -276.384594) (xy 13.580964 -276.329113)
			(xy 13.649976 -276.27997) (xy 13.723346 -276.23761) (xy 13.800411 -276.202415) (xy 13.880473 -276.174706)
			(xy 13.962806 -276.154732) (xy 14.046665 -276.142675) (xy 14.13129 -276.138644) (xy 14.215915 -276.142675)
			(xy 14.299774 -276.154732) (xy 14.382107 -276.174706) (xy 14.462169 -276.202415) (xy 14.539234 -276.23761)
			(xy 14.612604 -276.27997) (xy 14.681616 -276.329113) (xy 14.745644 -276.384594) (xy 14.804109 -276.445909)
			(xy 14.85648 -276.512505) (xy 14.902283 -276.583777) (xy 14.941105 -276.65908) (xy 14.972593 -276.737732)
			(xy 14.996461 -276.819022) (xy 15.012495 -276.902212) (xy 15.020548 -276.986549) (xy 15.021052 -277.02891)
			(xy 15.020549 -277.071499) (xy 15.01238 -277.156283) (xy 14.996148 -277.2399) (xy 14.971999 -277.321582)
			(xy 14.940156 -277.400583) (xy 14.920976 -277.438612) (xy 14.915968 -277.449836) (xy 14.915971 -277.474377)
			(xy 14.920976 -277.485602) (xy 14.940173 -277.523622) (xy 14.972013 -277.602626) (xy 14.996157 -277.68431)
			(xy 15.012383 -277.767929) (xy 15.020543 -277.852715) (xy 15.021052 -277.895304) (xy 15.020548 -277.937665)
			(xy 15.012495 -278.022002) (xy 14.996461 -278.105192) (xy 14.972593 -278.186482) (xy 14.941105 -278.265134)
			(xy 14.902283 -278.340437) (xy 14.85648 -278.411709) (xy 14.804109 -278.478305) (xy 14.745644 -278.53962)
			(xy 14.681616 -278.595101) (xy 14.612604 -278.644244) (xy 14.539234 -278.686604) (xy 14.462169 -278.721799)
			(xy 14.382107 -278.749508) (xy 14.318249 -278.765) (xy 35.45078 -278.765) (xy 35.451168 -278.726716)
			(xy 35.457707 -278.650427) (xy 35.470789 -278.574985) (xy 35.490315 -278.500948) (xy 35.50285 -278.464772)
			(xy 35.505501 -278.456335) (xy 35.505501 -278.438665) (xy 35.50285 -278.430228) (xy 35.490324 -278.39405)
			(xy 35.470817 -278.32001) (xy 35.457737 -278.244569) (xy 35.451182 -278.168283) (xy 35.45078 -278.13)
			(xy 35.451168 -278.091716) (xy 35.457707 -278.015427) (xy 35.470789 -277.939985) (xy 35.490315 -277.865948)
			(xy 35.50285 -277.829772) (xy 35.505501 -277.821335) (xy 35.505501 -277.803665) (xy 35.50285 -277.795228)
			(xy 35.490324 -277.75905) (xy 35.470817 -277.68501) (xy 35.457737 -277.609569) (xy 35.451182 -277.533283)
			(xy 35.45078 -277.495) (xy 35.451284 -277.452652) (xy 35.459335 -277.368338) (xy 35.475364 -277.285172)
			(xy 35.499225 -277.203905) (xy 35.530704 -277.125275) (xy 35.569515 -277.049994) (xy 35.615305 -276.978742)
			(xy 35.667661 -276.912166) (xy 35.726109 -276.850868) (xy 35.790119 -276.795403) (xy 35.859111 -276.746274)
			(xy 35.932461 -276.703925) (xy 36.009504 -276.668741) (xy 36.089543 -276.641039) (xy 36.171852 -276.621071)
			(xy 36.255687 -276.609018) (xy 36.340288 -276.604988) (xy 36.424889 -276.609018) (xy 36.508724 -276.621071)
			(xy 36.591033 -276.641039) (xy 36.671072 -276.668741) (xy 36.748115 -276.703925) (xy 36.821465 -276.746274)
			(xy 36.890457 -276.795403) (xy 36.954467 -276.850868) (xy 37.012915 -276.912166) (xy 37.065271 -276.978742)
			(xy 37.111061 -277.049994) (xy 37.149872 -277.125275) (xy 37.181351 -277.203905) (xy 37.205212 -277.285172)
			(xy 37.221241 -277.368338) (xy 37.229292 -277.452652) (xy 37.229796 -277.495) (xy 37.229409 -277.533284)
			(xy 37.22287 -277.609573) (xy 37.209788 -277.685015) (xy 37.190261 -277.759052) (xy 37.177726 -277.795228)
			(xy 37.175076 -277.803665) (xy 37.175076 -277.821335) (xy 37.177726 -277.829772) (xy 37.190251 -277.865951)
			(xy 37.209759 -277.93999) (xy 37.222839 -278.015431) (xy 37.229394 -278.091717) (xy 37.229796 -278.13)
			(xy 37.229409 -278.168284) (xy 37.22287 -278.244573) (xy 37.209788 -278.320015) (xy 37.190261 -278.394052)
			(xy 37.177726 -278.430228) (xy 37.175076 -278.438665) (xy 37.175076 -278.456335) (xy 37.177726 -278.464772)
			(xy 37.190251 -278.500951) (xy 37.209759 -278.57499) (xy 37.222839 -278.650431) (xy 37.229394 -278.726717)
			(xy 37.229796 -278.765) (xy 37.229292 -278.807348) (xy 37.221241 -278.891662) (xy 37.205212 -278.974828)
			(xy 37.181351 -279.056095) (xy 37.149872 -279.134725) (xy 37.111061 -279.210006) (xy 37.065271 -279.281258)
			(xy 37.012915 -279.347834) (xy 36.954467 -279.409132) (xy 36.890457 -279.464597) (xy 36.821465 -279.513726)
			(xy 36.748115 -279.556075) (xy 36.671072 -279.591259) (xy 36.591033 -279.618961) (xy 36.508724 -279.638929)
			(xy 36.424889 -279.650982) (xy 36.340288 -279.655013) (xy 36.255687 -279.650982) (xy 36.171852 -279.638929)
			(xy 36.089543 -279.618961) (xy 36.009504 -279.591259) (xy 35.932461 -279.556075) (xy 35.859111 -279.513726)
			(xy 35.790119 -279.464597) (xy 35.726109 -279.409132) (xy 35.667661 -279.347834) (xy 35.615305 -279.281258)
			(xy 35.569515 -279.210006) (xy 35.530704 -279.134725) (xy 35.499225 -279.056095) (xy 35.475364 -278.974828)
			(xy 35.459335 -278.891662) (xy 35.451284 -278.807348) (xy 35.45078 -278.765) (xy 14.318249 -278.765)
			(xy 14.299774 -278.769482) (xy 14.215915 -278.781539) (xy 14.13129 -278.785571) (xy 14.046665 -278.781539)
			(xy 13.962806 -278.769482) (xy 13.880473 -278.749508) (xy 13.800411 -278.721799) (xy 13.723346 -278.686604)
			(xy 13.649976 -278.644244) (xy 13.580964 -278.595101) (xy 13.516936 -278.53962) (xy 13.458471 -278.478305)
			(xy 13.4061 -278.411709) (xy 13.360297 -278.340437) (xy 13.321475 -278.265134) (xy 13.289987 -278.186482)
			(xy 13.266119 -278.105192) (xy 13.250085 -278.022002) (xy 13.242032 -277.937665) (xy 13.241528 -277.895304)
			(xy 0.509016 -277.895304) (xy 0.509016 -281.2542) (xy 3.936492 -281.2542) (xy 3.937075 -281.207804)
			(xy 3.94672 -281.115516) (xy 3.965916 -281.024732) (xy 3.994454 -280.936439) (xy 4.012692 -280.893774)
			(xy 4.016498 -280.883832) (xy 4.016498 -280.862568) (xy 4.012692 -280.852626) (xy 3.994447 -280.809964)
			(xy 3.965903 -280.721671) (xy 3.94671 -280.630886) (xy 3.937077 -280.538596) (xy 3.936492 -280.4922)
			(xy 3.936967 -280.451098) (xy 3.944552 -280.369243) (xy 3.959657 -280.288438) (xy 3.982153 -280.209371)
			(xy 4.011849 -280.132717) (xy 4.048491 -280.05913) (xy 4.091766 -279.989238) (xy 4.141306 -279.923637)
			(xy 4.196687 -279.862887) (xy 4.257437 -279.807506) (xy 4.323038 -279.757966) (xy 4.39293 -279.714691)
			(xy 4.466517 -279.678049) (xy 4.543171 -279.648353) (xy 4.622238 -279.625857) (xy 4.703043 -279.610752)
			(xy 4.784898 -279.603167) (xy 4.826 -279.602692) (xy 4.872396 -279.603275) (xy 4.964684 -279.61292)
			(xy 5.055468 -279.632116) (xy 5.143761 -279.660654) (xy 5.186426 -279.678892) (xy 5.196368 -279.682698)
			(xy 5.217632 -279.682698) (xy 5.227574 -279.678892) (xy 5.270236 -279.660647) (xy 5.358529 -279.632103)
			(xy 5.449314 -279.61291) (xy 5.541604 -279.603277) (xy 5.588 -279.602692) (xy 5.634396 -279.603275)
			(xy 5.726684 -279.61292) (xy 5.817468 -279.632116) (xy 5.905761 -279.660654) (xy 5.948426 -279.678892)
			(xy 5.958368 -279.682698) (xy 5.979632 -279.682698) (xy 5.989574 -279.678892) (xy 6.032236 -279.660647)
			(xy 6.120529 -279.632103) (xy 6.211314 -279.61291) (xy 6.303604 -279.603277) (xy 6.35 -279.602692)
			(xy 6.391102 -279.603167) (xy 6.472957 -279.610752) (xy 6.553762 -279.625857) (xy 6.632829 -279.648353)
			(xy 6.709483 -279.678049) (xy 6.78307 -279.714691) (xy 6.852962 -279.757966) (xy 6.918563 -279.807506)
			(xy 6.979313 -279.862887) (xy 7.034694 -279.923637) (xy 7.084234 -279.989238) (xy 7.127509 -280.05913)
			(xy 7.164151 -280.132717) (xy 7.193847 -280.209371) (xy 7.216343 -280.288438) (xy 7.231448 -280.369243)
			(xy 7.239033 -280.451098) (xy 7.239508 -280.4922) (xy 7.238925 -280.538596) (xy 7.22928 -280.630884)
			(xy 7.210084 -280.721668) (xy 7.181546 -280.809961) (xy 7.163308 -280.852626) (xy 7.159502 -280.862568)
			(xy 7.159502 -280.883832) (xy 7.163308 -280.893774) (xy 7.181553 -280.936436) (xy 7.210097 -281.024729)
			(xy 7.22435 -281.092148) (xy 44.946824 -281.092148) (xy 44.947421 -281.045753) (xy 44.957062 -280.953465)
			(xy 44.976253 -280.862681) (xy 45.004788 -280.774387) (xy 45.023024 -280.731722) (xy 45.026799 -280.721771)
			(xy 45.026818 -280.700516) (xy 45.023024 -280.690574) (xy 45.004797 -280.647904) (xy 44.976248 -280.559615)
			(xy 44.95705 -280.468832) (xy 44.947411 -280.376543) (xy 44.946824 -280.330148) (xy 44.947298 -280.289045)
			(xy 44.954879 -280.207188) (xy 44.969981 -280.126381) (xy 44.992475 -280.047312) (xy 45.022169 -279.970655)
			(xy 45.058809 -279.897066) (xy 45.102084 -279.827172) (xy 45.151623 -279.761568) (xy 45.207005 -279.700816)
			(xy 45.267756 -279.645434) (xy 45.333358 -279.595893) (xy 45.403252 -279.552617) (xy 45.476841 -279.515975)
			(xy 45.553496 -279.48628) (xy 45.632565 -279.463785) (xy 45.713373 -279.448681) (xy 45.795229 -279.441099)
			(xy 45.836332 -279.44064) (xy 45.882727 -279.441243) (xy 45.975015 -279.450881) (xy 46.065799 -279.470071)
			(xy 46.154093 -279.498605) (xy 46.196758 -279.51684) (xy 46.2067 -279.520646) (xy 46.227964 -279.520646)
			(xy 46.237906 -279.51684) (xy 46.280565 -279.498588) (xy 46.368858 -279.470045) (xy 46.459645 -279.450854)
			(xy 46.551936 -279.441223) (xy 46.598332 -279.44064) (xy 46.644727 -279.441243) (xy 46.737015 -279.450881)
			(xy 46.827799 -279.470071) (xy 46.916093 -279.498605) (xy 46.958758 -279.51684) (xy 46.9687 -279.520646)
			(xy 46.989964 -279.520646) (xy 46.999906 -279.51684) (xy 47.042565 -279.498588) (xy 47.130858 -279.470045)
			(xy 47.221645 -279.450854) (xy 47.313936 -279.441223) (xy 47.360332 -279.44064) (xy 47.401437 -279.441022)
			(xy 47.483296 -279.44861) (xy 47.564106 -279.463719) (xy 47.643177 -279.48622) (xy 47.719835 -279.515921)
			(xy 47.793425 -279.552568) (xy 47.86332 -279.595849) (xy 47.928923 -279.645395) (xy 47.989674 -279.700782)
			(xy 48.045056 -279.761539) (xy 48.094596 -279.827146) (xy 48.137871 -279.897045) (xy 48.174511 -279.970638)
			(xy 48.204205 -280.047299) (xy 48.226699 -280.126372) (xy 48.241801 -280.207183) (xy 48.249382 -280.289043)
			(xy 48.24984 -280.330148) (xy 48.249245 -280.376543) (xy 48.239604 -280.468831) (xy 48.220412 -280.559615)
			(xy 48.191877 -280.647909) (xy 48.17364 -280.690574) (xy 48.169804 -280.700507) (xy 48.169823 -280.72178)
			(xy 48.17364 -280.731722) (xy 48.19187 -280.77439) (xy 48.220417 -280.862681) (xy 48.239614 -280.953464)
			(xy 48.249252 -281.045752) (xy 48.24984 -281.092148) (xy 48.249379 -281.13325) (xy 48.24179 -281.215104)
			(xy 48.226682 -281.295908) (xy 48.204182 -281.374974) (xy 48.174484 -281.451627) (xy 48.13784 -281.525212)
			(xy 48.094563 -281.595103) (xy 48.045023 -281.660703) (xy 47.989641 -281.721453) (xy 47.928891 -281.776833)
			(xy 47.86329 -281.826373) (xy 47.793398 -281.869648) (xy 47.719812 -281.906291) (xy 47.643159 -281.935987)
			(xy 47.564093 -281.958485) (xy 47.483288 -281.973593) (xy 47.401434 -281.98118) (xy 47.360332 -281.981656)
			(xy 47.313937 -281.981066) (xy 47.221648 -281.971424) (xy 47.130864 -281.95223) (xy 47.042571 -281.923693)
			(xy 46.999906 -281.905456) (xy 46.989964 -281.90165) (xy 46.9687 -281.90165) (xy 46.958758 -281.905456)
			(xy 46.91609 -281.923687) (xy 46.8278 -281.952235) (xy 46.737017 -281.971432) (xy 46.644728 -281.981069)
			(xy 46.598332 -281.981656) (xy 46.551937 -281.981066) (xy 46.459648 -281.971424) (xy 46.368864 -281.95223)
			(xy 46.280571 -281.923693) (xy 46.237906 -281.905456) (xy 46.227964 -281.90165) (xy 46.2067 -281.90165)
			(xy 46.196758 -281.905456) (xy 46.15409 -281.923687) (xy 46.0658 -281.952235) (xy 45.975017 -281.971432)
			(xy 45.882728 -281.981069) (xy 45.836332 -281.981656) (xy 45.795231 -281.981103) (xy 45.713381 -281.973521)
			(xy 45.632579 -281.95842) (xy 45.553515 -281.935928) (xy 45.476863 -281.906236) (xy 45.403278 -281.869599)
			(xy 45.333388 -281.826329) (xy 45.267788 -281.776795) (xy 45.207038 -281.721419) (xy 45.151657 -281.660674)
			(xy 45.102116 -281.595078) (xy 45.05884 -281.525192) (xy 45.022196 -281.45161) (xy 44.992498 -281.374961)
			(xy 44.969998 -281.295899) (xy 44.95489 -281.215099) (xy 44.947301 -281.133249) (xy 44.946824 -281.092148)
			(xy 7.22435 -281.092148) (xy 7.22929 -281.115514) (xy 7.238923 -281.207804) (xy 7.239508 -281.2542)
			(xy 7.239033 -281.295302) (xy 7.231448 -281.377157) (xy 7.216343 -281.457962) (xy 7.193847 -281.537029)
			(xy 7.164151 -281.613683) (xy 7.127509 -281.68727) (xy 7.084234 -281.757162) (xy 7.034694 -281.822763)
			(xy 6.979313 -281.883513) (xy 6.918563 -281.938894) (xy 6.852962 -281.988434) (xy 6.78307 -282.031709)
			(xy 6.709483 -282.068351) (xy 6.632829 -282.098047) (xy 6.553762 -282.120543) (xy 6.472957 -282.135648)
			(xy 6.391102 -282.143233) (xy 6.35 -282.143708) (xy 6.303604 -282.143125) (xy 6.211316 -282.13348)
			(xy 6.120532 -282.114284) (xy 6.032239 -282.085746) (xy 5.989574 -282.067508) (xy 5.979632 -282.063702)
			(xy 5.958368 -282.063702) (xy 5.948426 -282.067508) (xy 5.905764 -282.085753) (xy 5.817471 -282.114297)
			(xy 5.726686 -282.13349) (xy 5.634396 -282.143123) (xy 5.588 -282.143708) (xy 5.541604 -282.143125)
			(xy 5.449316 -282.13348) (xy 5.358532 -282.114284) (xy 5.270239 -282.085746) (xy 5.227574 -282.067508)
			(xy 5.217632 -282.063702) (xy 5.196368 -282.063702) (xy 5.186426 -282.067508) (xy 5.143764 -282.085753)
			(xy 5.055471 -282.114297) (xy 4.964686 -282.13349) (xy 4.872396 -282.143123) (xy 4.826 -282.143708)
			(xy 4.784898 -282.143233) (xy 4.703043 -282.135648) (xy 4.622238 -282.120543) (xy 4.543171 -282.098047)
			(xy 4.466517 -282.068351) (xy 4.39293 -282.031709) (xy 4.323038 -281.988434) (xy 4.257437 -281.938894)
			(xy 4.196687 -281.883513) (xy 4.141306 -281.822763) (xy 4.091766 -281.757162) (xy 4.048491 -281.68727)
			(xy 4.011849 -281.613683) (xy 3.982153 -281.537029) (xy 3.959657 -281.457962) (xy 3.944552 -281.377157)
			(xy 3.936967 -281.295302) (xy 3.936492 -281.2542) (xy 0.509016 -281.2542) (xy 0.509016 -287.410144)
			(xy 6.441451 -287.410144) (xy 6.445429 -287.310151) (xy 6.457339 -287.210791) (xy 6.477106 -287.11269)
			(xy 6.504605 -287.016471) (xy 6.539661 -286.92274) (xy 6.582053 -286.832091) (xy 6.631514 -286.745097)
			(xy 6.68773 -286.662307) (xy 6.750346 -286.584245) (xy 6.818965 -286.511405) (xy 6.893156 -286.444247)
			(xy 6.972447 -286.383195) (xy 7.056338 -286.328637) (xy 7.144299 -286.280916) (xy 7.235773 -286.240334)
			(xy 7.330182 -286.207148) (xy 7.426929 -286.181568) (xy 7.525403 -286.163755) (xy 7.624981 -286.153823)
			(xy 7.725033 -286.151833) (xy 7.824927 -286.157799) (xy 7.924031 -286.171683) (xy 8.021719 -286.193396)
			(xy 8.117373 -286.222802) (xy 8.210388 -286.259715) (xy 8.300176 -286.303901) (xy 8.38617 -286.355082)
			(xy 8.467826 -286.412932) (xy 8.544627 -286.477088) (xy 8.616089 -286.547142) (xy 8.681759 -286.622653)
			(xy 8.741221 -286.703143) (xy 8.794101 -286.788102) (xy 8.840064 -286.876994) (xy 8.878819 -286.969257)
			(xy 8.910121 -287.064307) (xy 8.933773 -287.161544) (xy 8.949624 -287.260353) (xy 8.957574 -287.360108)
			(xy 8.958072 -287.410144) (xy 8.957574 -287.46018) (xy 8.949624 -287.559935) (xy 8.933773 -287.658744)
			(xy 8.910121 -287.755981) (xy 8.878819 -287.851031) (xy 8.840064 -287.943294) (xy 8.838096 -287.9471)
			(xy 18.94205 -287.9471) (xy 18.94246 -287.906019) (xy 18.950041 -287.824207) (xy 18.965139 -287.743444)
			(xy 18.987625 -287.664418) (xy 19.017306 -287.587805) (xy 19.05393 -287.514257) (xy 19.097185 -287.444402)
			(xy 19.1467 -287.378836) (xy 19.202054 -287.318119) (xy 19.262774 -287.262768) (xy 19.328343 -287.213256)
			(xy 19.3982 -287.170006) (xy 19.47175 -287.133386) (xy 19.548366 -287.103709) (xy 19.627393 -287.081228)
			(xy 19.708157 -287.066135) (xy 19.789969 -287.058558) (xy 19.83105 -287.0581) (xy 19.870063 -287.05851)
			(xy 19.947792 -287.065313) (xy 20.024625 -287.078906) (xy 20.099971 -287.099184) (xy 20.173247 -287.125991)
			(xy 20.208748 -287.142174) (xy 20.213384 -287.144246) (xy 20.223239 -287.146683) (xy 20.228306 -287.147)
			(xy 20.270825 -287.149195) (xy 20.355189 -287.160702) (xy 20.438068 -287.180216) (xy 20.518704 -287.20756)
			(xy 20.596358 -287.242482) (xy 20.670321 -287.284663) (xy 20.739915 -287.333718) (xy 20.804505 -287.389198)
			(xy 20.863498 -287.450595) (xy 20.916356 -287.517347) (xy 20.962594 -287.588843) (xy 21.00179 -287.66443)
			(xy 21.033585 -287.743416) (xy 21.057689 -287.825079) (xy 21.07388 -287.908671) (xy 21.082011 -287.993427)
			(xy 21.082508 -288.036) (xy 21.082033 -288.077102) (xy 21.074448 -288.158957) (xy 21.059343 -288.239762)
			(xy 21.036847 -288.318829) (xy 21.007151 -288.395483) (xy 20.970509 -288.46907) (xy 20.927234 -288.538962)
			(xy 20.877694 -288.604563) (xy 20.822313 -288.665313) (xy 20.761563 -288.720694) (xy 20.695962 -288.770234)
			(xy 20.62607 -288.813509) (xy 20.552483 -288.850151) (xy 20.475829 -288.879847) (xy 20.396762 -288.902343)
			(xy 20.315957 -288.917448) (xy 20.234458 -288.925) (xy 30.478988 -288.925) (xy 30.483018 -288.840399)
			(xy 30.495071 -288.756564) (xy 30.515039 -288.674255) (xy 30.542741 -288.594216) (xy 30.577925 -288.517173)
			(xy 30.620274 -288.443823) (xy 30.669403 -288.374831) (xy 30.724868 -288.310821) (xy 30.786166 -288.252373)
			(xy 30.852742 -288.200017) (xy 30.923994 -288.154227) (xy 30.999275 -288.115416) (xy 31.077905 -288.083937)
			(xy 31.159172 -288.060076) (xy 31.242338 -288.044047) (xy 31.326652 -288.035996) (xy 31.369 -288.035492)
			(xy 31.412701 -288.03601) (xy 31.499683 -288.044548) (xy 31.58541 -288.061571) (xy 31.669056 -288.086916)
			(xy 31.749814 -288.120338) (xy 31.826907 -288.161515) (xy 31.863538 -288.185352) (xy 31.872793 -288.190951)
			(xy 31.894112 -288.194494) (xy 31.904686 -288.19221) (xy 31.94168 -288.18291) (xy 32.01685 -288.169911)
			(xy 32.092857 -288.163397) (xy 32.131 -288.163) (xy 32.173324 -288.163504) (xy 32.25759 -288.17155)
			(xy 32.340709 -288.18757) (xy 32.421928 -288.211418) (xy 32.500513 -288.242879) (xy 32.575752 -288.281667)
			(xy 32.646963 -288.327431) (xy 32.713501 -288.379758) (xy 32.774764 -288.438172) (xy 32.830197 -288.502145)
			(xy 32.879298 -288.571098) (xy 32.921623 -288.644406) (xy 32.956787 -288.721405) (xy 32.984473 -288.801398)
			(xy 33.00443 -288.88366) (xy 33.016476 -288.967447) (xy 33.020504 -289.052) (xy 33.016476 -289.136553)
			(xy 33.00443 -289.22034) (xy 32.984473 -289.302602) (xy 32.956787 -289.382595) (xy 32.921623 -289.459594)
			(xy 32.879298 -289.532902) (xy 32.830197 -289.601855) (xy 32.774764 -289.665828) (xy 32.713501 -289.724242)
			(xy 32.646963 -289.776569) (xy 32.575752 -289.822333) (xy 32.500513 -289.861121) (xy 32.421928 -289.892582)
			(xy 32.340709 -289.91643) (xy 32.25759 -289.93245) (xy 32.173324 -289.940496) (xy 32.131 -289.941)
			(xy 32.087445 -289.940479) (xy 32.000752 -289.931972) (xy 31.915306 -289.915028) (xy 31.831926 -289.889812)
			(xy 31.751411 -289.856563) (xy 31.674532 -289.815601) (xy 31.637986 -289.791902) (xy 31.628726 -289.786315)
			(xy 31.607411 -289.782766) (xy 31.596838 -289.785044) (xy 31.559601 -289.794444) (xy 31.483927 -289.807574)
			(xy 31.407403 -289.814134) (xy 31.369 -289.814508) (xy 31.326652 -289.814004) (xy 31.242338 -289.805953)
			(xy 31.159172 -289.789924) (xy 31.077905 -289.766063) (xy 30.999275 -289.734584) (xy 30.923994 -289.695773)
			(xy 30.852742 -289.649983) (xy 30.786166 -289.597627) (xy 30.724868 -289.539179) (xy 30.669403 -289.475169)
			(xy 30.620274 -289.406177) (xy 30.577925 -289.332827) (xy 30.542741 -289.255784) (xy 30.515039 -289.175745)
			(xy 30.495071 -289.093436) (xy 30.483018 -289.009601) (xy 30.478988 -288.925) (xy 20.234458 -288.925)
			(xy 20.234102 -288.925033) (xy 20.193 -288.925508) (xy 20.153679 -288.925088) (xy 20.075343 -288.918178)
			(xy 19.997922 -288.904376) (xy 19.922024 -288.88379) (xy 19.84824 -288.856581) (xy 19.812508 -288.840164)
			(xy 19.807876 -288.838082) (xy 19.798019 -288.835651) (xy 19.79295 -288.835338) (xy 19.750554 -288.833021)
			(xy 19.666452 -288.821301) (xy 19.583852 -288.801616) (xy 19.503504 -288.774146) (xy 19.426142 -288.73914)
			(xy 19.352469 -288.696918) (xy 19.283158 -288.647865) (xy 19.218839 -288.592426) (xy 19.160098 -288.531108)
			(xy 19.107471 -288.464469) (xy 19.061438 -288.393116) (xy 19.022417 -288.317699) (xy 18.990764 -288.238905)
			(xy 18.966767 -288.157453) (xy 18.950646 -288.074083) (xy 18.942546 -287.989557) (xy 18.94205 -287.9471)
			(xy 8.838096 -287.9471) (xy 8.794101 -288.032186) (xy 8.741221 -288.117145) (xy 8.681759 -288.197635)
			(xy 8.616089 -288.273146) (xy 8.544627 -288.3432) (xy 8.467826 -288.407356) (xy 8.38617 -288.465206)
			(xy 8.300176 -288.516387) (xy 8.210388 -288.560573) (xy 8.117373 -288.597486) (xy 8.021719 -288.626892)
			(xy 7.924031 -288.648605) (xy 7.824927 -288.662489) (xy 7.725033 -288.668455) (xy 7.624981 -288.666465)
			(xy 7.525403 -288.656533) (xy 7.426929 -288.63872) (xy 7.330182 -288.61314) (xy 7.235773 -288.579954)
			(xy 7.144299 -288.539372) (xy 7.056338 -288.491651) (xy 6.972447 -288.437093) (xy 6.893156 -288.376041)
			(xy 6.818965 -288.308883) (xy 6.750346 -288.236043) (xy 6.68773 -288.157981) (xy 6.631514 -288.075191)
			(xy 6.582053 -287.988197) (xy 6.539661 -287.897548) (xy 6.504605 -287.803817) (xy 6.477106 -287.707598)
			(xy 6.457339 -287.609497) (xy 6.445429 -287.510137) (xy 6.441451 -287.410144) (xy 0.509016 -287.410144)
			(xy 0.509016 -293.310056) (xy 43.677851 -293.310056) (xy 43.681826 -293.207606) (xy 43.693729 -293.105773)
			(xy 43.713487 -293.005168) (xy 43.740982 -292.906397) (xy 43.776048 -292.810053) (xy 43.818474 -292.716717)
			(xy 43.868006 -292.626949) (xy 43.924346 -292.541289) (xy 43.987154 -292.460253) (xy 44.056052 -292.384327)
			(xy 44.130628 -292.313969) (xy 44.210431 -292.249601) (xy 44.294982 -292.191612) (xy 44.383773 -292.140348)
			(xy 44.476269 -292.09612) (xy 44.571914 -292.059192) (xy 44.670134 -292.029787) (xy 44.770337 -292.008082)
			(xy 44.87192 -291.994206) (xy 44.974274 -291.988245) (xy 45.076781 -291.990233) (xy 45.178826 -292.000159)
			(xy 45.279795 -292.017962) (xy 45.379081 -292.043537) (xy 45.476086 -292.076728) (xy 45.570228 -292.117337)
			(xy 45.66094 -292.165119) (xy 45.747676 -292.219787) (xy 45.829915 -292.281011) (xy 45.907162 -292.348425)
			(xy 45.978953 -292.421622) (xy 46.044856 -292.500162) (xy 46.104475 -292.583572) (xy 46.15745 -292.671352)
			(xy 46.203464 -292.762974) (xy 46.24224 -292.857885) (xy 46.273544 -292.955516) (xy 46.297188 -293.055279)
			(xy 46.31303 -293.156574) (xy 46.320975 -293.258793) (xy 46.321472 -293.310056) (xy 46.320975 -293.361319)
			(xy 46.31303 -293.463538) (xy 46.297188 -293.564833) (xy 46.273544 -293.664596) (xy 46.24224 -293.762227)
			(xy 46.203464 -293.857138) (xy 46.15745 -293.94876) (xy 46.104475 -294.03654) (xy 46.044856 -294.11995)
			(xy 45.978953 -294.19849) (xy 45.907162 -294.271687) (xy 45.829915 -294.339101) (xy 45.747676 -294.400325)
			(xy 45.66094 -294.454993) (xy 45.570228 -294.502775) (xy 45.476086 -294.543384) (xy 45.379081 -294.576575)
			(xy 45.279795 -294.60215) (xy 45.178826 -294.619953) (xy 45.076781 -294.629879) (xy 44.974274 -294.631867)
			(xy 44.87192 -294.625906) (xy 44.770337 -294.61203) (xy 44.670134 -294.590325) (xy 44.571914 -294.56092)
			(xy 44.476269 -294.523992) (xy 44.383773 -294.479764) (xy 44.294982 -294.4285) (xy 44.210431 -294.370511)
			(xy 44.130628 -294.306143) (xy 44.056052 -294.235785) (xy 43.987154 -294.159859) (xy 43.924346 -294.078823)
			(xy 43.868006 -293.993163) (xy 43.818474 -293.903395) (xy 43.776048 -293.810059) (xy 43.740982 -293.713715)
			(xy 43.713487 -293.614944) (xy 43.693729 -293.514339) (xy 43.681826 -293.412506) (xy 43.677851 -293.310056)
			(xy 0.509016 -293.310056) (xy 0.509016 -295.310052) (xy 41.677855 -295.310052) (xy 41.68183 -295.207602)
			(xy 41.693733 -295.105769) (xy 41.713491 -295.005164) (xy 41.740986 -294.906393) (xy 41.776052 -294.810049)
			(xy 41.818478 -294.716713) (xy 41.86801 -294.626945) (xy 41.92435 -294.541285) (xy 41.987158 -294.460249)
			(xy 42.056056 -294.384323) (xy 42.130632 -294.313965) (xy 42.210435 -294.249597) (xy 42.294986 -294.191608)
			(xy 42.383777 -294.140344) (xy 42.476273 -294.096116) (xy 42.571918 -294.059188) (xy 42.670138 -294.029783)
			(xy 42.770341 -294.008078) (xy 42.871924 -293.994202) (xy 42.974278 -293.988241) (xy 43.076785 -293.990229)
			(xy 43.17883 -294.000155) (xy 43.279799 -294.017958) (xy 43.379085 -294.043533) (xy 43.47609 -294.076724)
			(xy 43.570232 -294.117333) (xy 43.660944 -294.165115) (xy 43.74768 -294.219783) (xy 43.829919 -294.281007)
			(xy 43.907166 -294.348421) (xy 43.978957 -294.421618) (xy 44.04486 -294.500158) (xy 44.104479 -294.583568)
			(xy 44.157454 -294.671348) (xy 44.203468 -294.76297) (xy 44.242244 -294.857881) (xy 44.273548 -294.955512)
			(xy 44.297192 -295.055275) (xy 44.313034 -295.15657) (xy 44.320979 -295.258789) (xy 44.321476 -295.310052)
			(xy 44.320979 -295.361315) (xy 44.313034 -295.463534) (xy 44.297192 -295.564829) (xy 44.273548 -295.664592)
			(xy 44.242244 -295.762223) (xy 44.203468 -295.857134) (xy 44.157454 -295.948756) (xy 44.104479 -296.036536)
			(xy 44.04486 -296.119946) (xy 43.978957 -296.198486) (xy 43.907166 -296.271683) (xy 43.829919 -296.339097)
			(xy 43.74768 -296.400321) (xy 43.660944 -296.454989) (xy 43.570232 -296.502771) (xy 43.47609 -296.54338)
			(xy 43.379085 -296.576571) (xy 43.279799 -296.602146) (xy 43.17883 -296.619949) (xy 43.076785 -296.629875)
			(xy 42.974278 -296.631863) (xy 42.871924 -296.625902) (xy 42.770341 -296.612026) (xy 42.670138 -296.590321)
			(xy 42.571918 -296.560916) (xy 42.476273 -296.523988) (xy 42.383777 -296.47976) (xy 42.294986 -296.428496)
			(xy 42.210435 -296.370507) (xy 42.130632 -296.306139) (xy 42.056056 -296.235781) (xy 41.987158 -296.159855)
			(xy 41.92435 -296.078819) (xy 41.86801 -295.993159) (xy 41.818478 -295.903391) (xy 41.776052 -295.810055)
			(xy 41.740986 -295.713711) (xy 41.713491 -295.61494) (xy 41.693733 -295.514335) (xy 41.68183 -295.412502)
			(xy 41.677855 -295.310052) (xy 0.509016 -295.310052) (xy 0.509016 -297.310048) (xy 7.377949 -297.310048)
			(xy 7.381924 -297.207598) (xy 7.393827 -297.105765) (xy 7.413585 -297.00516) (xy 7.44108 -296.906389)
			(xy 7.476146 -296.810045) (xy 7.518572 -296.716709) (xy 7.568104 -296.626941) (xy 7.624444 -296.541281)
			(xy 7.687252 -296.460245) (xy 7.75615 -296.384319) (xy 7.830726 -296.313961) (xy 7.910529 -296.249593)
			(xy 7.99508 -296.191604) (xy 8.083871 -296.14034) (xy 8.176367 -296.096112) (xy 8.272012 -296.059184)
			(xy 8.370232 -296.029779) (xy 8.470435 -296.008074) (xy 8.572018 -295.994198) (xy 8.674372 -295.988237)
			(xy 8.776879 -295.990225) (xy 8.878924 -296.000151) (xy 8.979893 -296.017954) (xy 9.079179 -296.043529)
			(xy 9.176184 -296.07672) (xy 9.270326 -296.117329) (xy 9.361038 -296.165111) (xy 9.447774 -296.219779)
			(xy 9.530013 -296.281003) (xy 9.60726 -296.348417) (xy 9.679051 -296.421614) (xy 9.744954 -296.500154)
			(xy 9.804573 -296.583564) (xy 9.857548 -296.671344) (xy 9.903562 -296.762966) (xy 9.942338 -296.857877)
			(xy 9.973642 -296.955508) (xy 9.997286 -297.055271) (xy 10.013128 -297.156566) (xy 10.021073 -297.258785)
			(xy 10.02157 -297.310048) (xy 10.021073 -297.361311) (xy 10.013128 -297.46353) (xy 9.997286 -297.564825)
			(xy 9.973642 -297.664588) (xy 9.942338 -297.762219) (xy 9.903562 -297.85713) (xy 9.857548 -297.948752)
			(xy 9.804573 -298.036532) (xy 9.744954 -298.119942) (xy 9.679051 -298.198482) (xy 9.60726 -298.271679)
			(xy 9.530013 -298.339093) (xy 9.447774 -298.400317) (xy 9.361038 -298.454985) (xy 9.270326 -298.502767)
			(xy 9.176184 -298.543376) (xy 9.079179 -298.576567) (xy 8.979893 -298.602142) (xy 8.878924 -298.619945)
			(xy 8.776879 -298.629871) (xy 8.674372 -298.631859) (xy 8.572018 -298.625898) (xy 8.470435 -298.612022)
			(xy 8.370232 -298.590317) (xy 8.272012 -298.560912) (xy 8.176367 -298.523984) (xy 8.083871 -298.479756)
			(xy 7.99508 -298.428492) (xy 7.910529 -298.370503) (xy 7.830726 -298.306135) (xy 7.75615 -298.235777)
			(xy 7.687252 -298.159851) (xy 7.624444 -298.078815) (xy 7.568104 -297.993155) (xy 7.518572 -297.903387)
			(xy 7.476146 -297.810051) (xy 7.44108 -297.713707) (xy 7.413585 -297.614936) (xy 7.393827 -297.514331)
			(xy 7.381924 -297.412498) (xy 7.377949 -297.310048) (xy 0.509016 -297.310048) (xy 0.509016 -299.310044)
			(xy 5.377953 -299.310044) (xy 5.381928 -299.207594) (xy 5.393831 -299.105761) (xy 5.413589 -299.005156)
			(xy 5.441084 -298.906385) (xy 5.47615 -298.810041) (xy 5.518576 -298.716705) (xy 5.568108 -298.626937)
			(xy 5.624448 -298.541277) (xy 5.687256 -298.460241) (xy 5.756154 -298.384315) (xy 5.83073 -298.313957)
			(xy 5.910533 -298.249589) (xy 5.995084 -298.1916) (xy 6.083875 -298.140336) (xy 6.176371 -298.096108)
			(xy 6.272016 -298.05918) (xy 6.370236 -298.029775) (xy 6.470439 -298.00807) (xy 6.572022 -297.994194)
			(xy 6.674376 -297.988233) (xy 6.776883 -297.990221) (xy 6.878928 -298.000147) (xy 6.979897 -298.01795)
			(xy 7.079183 -298.043525) (xy 7.176188 -298.076716) (xy 7.27033 -298.117325) (xy 7.361042 -298.165107)
			(xy 7.447778 -298.219775) (xy 7.530017 -298.280999) (xy 7.607264 -298.348413) (xy 7.679055 -298.42161)
			(xy 7.744958 -298.50015) (xy 7.804577 -298.58356) (xy 7.857552 -298.67134) (xy 7.903566 -298.762962)
			(xy 7.942342 -298.857873) (xy 7.973646 -298.955504) (xy 7.99729 -299.055267) (xy 8.013132 -299.156562)
			(xy 8.021077 -299.258781) (xy 8.021574 -299.310044) (xy 8.021077 -299.361307) (xy 8.013132 -299.463526)
			(xy 7.99729 -299.564821) (xy 7.973646 -299.664584) (xy 7.942342 -299.762215) (xy 7.903566 -299.857126)
			(xy 7.857552 -299.948748) (xy 7.842312 -299.974) (xy 30.352492 -299.974) (xy 30.352931 -299.93248)
			(xy 30.360686 -299.849804) (xy 30.37611 -299.76821) (xy 30.399068 -299.688407) (xy 30.429361 -299.61109)
			(xy 30.466726 -299.536932) (xy 30.510837 -299.466578) (xy 30.561311 -299.400639) (xy 30.617709 -299.33969)
			(xy 30.679539 -299.284259) (xy 30.746265 -299.23483) (xy 30.817306 -299.191833) (xy 30.892043 -299.155641)
			(xy 30.969827 -299.12657) (xy 31.049982 -299.104872) (xy 31.131809 -299.090735) (xy 31.173166 -299.087032)
			(xy 31.177635 -299.086561) (xy 31.18632 -299.084258) (xy 31.190438 -299.08246) (xy 31.225448 -299.066822)
			(xy 31.297618 -299.040905) (xy 31.371752 -299.021302) (xy 31.4473 -299.008159) (xy 31.523699 -299.001573)
			(xy 31.56204 -299.00118) (xy 31.603119 -299.001636) (xy 31.684927 -299.00922) (xy 31.765685 -299.024319)
			(xy 31.844706 -299.046806) (xy 31.921316 -299.076487) (xy 31.99486 -299.11311) (xy 32.064711 -299.156362)
			(xy 32.130274 -299.205875) (xy 32.190989 -299.261225) (xy 32.246338 -299.321941) (xy 32.295849 -299.387505)
			(xy 32.3391 -299.457358) (xy 32.375721 -299.530902) (xy 32.405401 -299.607513) (xy 32.427885 -299.686534)
			(xy 32.442983 -299.767293) (xy 32.450565 -299.849101) (xy 32.45104 -299.89018) (xy 32.450492 -299.931563)
			(xy 32.442783 -300.01397) (xy 32.427448 -300.095304) (xy 32.404621 -300.174861) (xy 32.374498 -300.251951)
			(xy 32.33734 -300.325909) (xy 32.29347 -300.396092) (xy 32.243266 -300.461895) (xy 32.187164 -300.522746)
			(xy 32.12565 -300.57812) (xy 32.059255 -300.627538) (xy 31.988554 -300.67057) (xy 31.91416 -300.706845)
			(xy 31.836717 -300.736049) (xy 31.756894 -300.757929) (xy 31.675384 -300.772295) (xy 31.634176 -300.776132)
			(xy 31.62971 -300.776617) (xy 31.621026 -300.778916) (xy 31.616904 -300.780704) (xy 31.581628 -300.796634)
			(xy 31.508851 -300.823008) (xy 31.43406 -300.842968) (xy 31.35782 -300.856361) (xy 31.280704 -300.863087)
			(xy 31.242 -300.863508) (xy 31.200898 -300.863033) (xy 31.119043 -300.855448) (xy 31.038238 -300.840343)
			(xy 30.959171 -300.817847) (xy 30.882517 -300.788151) (xy 30.80893 -300.751509) (xy 30.739038 -300.708234)
			(xy 30.673437 -300.658694) (xy 30.612687 -300.603313) (xy 30.557306 -300.542563) (xy 30.507766 -300.476962)
			(xy 30.464491 -300.40707) (xy 30.427849 -300.333483) (xy 30.398153 -300.256829) (xy 30.375657 -300.177762)
			(xy 30.360552 -300.096957) (xy 30.352967 -300.015102) (xy 30.352492 -299.974) (xy 7.842312 -299.974)
			(xy 7.804577 -300.036528) (xy 7.744958 -300.119938) (xy 7.679055 -300.198478) (xy 7.607264 -300.271675)
			(xy 7.530017 -300.339089) (xy 7.447778 -300.400313) (xy 7.361042 -300.454981) (xy 7.27033 -300.502763)
			(xy 7.176188 -300.543372) (xy 7.079183 -300.576563) (xy 6.979897 -300.602138) (xy 6.878928 -300.619941)
			(xy 6.776883 -300.629867) (xy 6.674376 -300.631855) (xy 6.572022 -300.625894) (xy 6.470439 -300.612018)
			(xy 6.370236 -300.590313) (xy 6.272016 -300.560908) (xy 6.176371 -300.52398) (xy 6.083875 -300.479752)
			(xy 5.995084 -300.428488) (xy 5.910533 -300.370499) (xy 5.83073 -300.306131) (xy 5.756154 -300.235773)
			(xy 5.687256 -300.159847) (xy 5.624448 -300.078811) (xy 5.568108 -299.993151) (xy 5.518576 -299.903383)
			(xy 5.47615 -299.810047) (xy 5.441084 -299.713703) (xy 5.413589 -299.614932) (xy 5.393831 -299.514327)
			(xy 5.381928 -299.412494) (xy 5.377953 -299.310044) (xy 0.509016 -299.310044) (xy 0.509016 -301.103538)
			(xy 18.063972 -301.103538) (xy 18.064496 -301.06246) (xy 18.072073 -300.980653) (xy 18.087166 -300.899895)
			(xy 18.109646 -300.820874) (xy 18.139321 -300.744264) (xy 18.175939 -300.67072) (xy 18.219186 -300.600867)
			(xy 18.268694 -300.535303) (xy 18.32404 -300.474587) (xy 18.384752 -300.419236) (xy 18.450313 -300.369723)
			(xy 18.520162 -300.326471) (xy 18.593704 -300.289848) (xy 18.670312 -300.260167) (xy 18.749331 -300.237681)
			(xy 18.830088 -300.222582) (xy 18.911894 -300.214999) (xy 18.952972 -300.214538) (xy 18.995213 -300.215016)
			(xy 19.079314 -300.223028) (xy 19.162276 -300.238983) (xy 19.24335 -300.262736) (xy 19.321804 -300.294074)
			(xy 19.396932 -300.332714) (xy 19.468055 -300.378307) (xy 19.534532 -300.430442) (xy 19.595762 -300.488648)
			(xy 19.651195 -300.552401) (xy 19.700329 -300.621125) (xy 19.742722 -300.694201) (xy 19.777991 -300.770969)
			(xy 19.805817 -300.850737) (xy 19.82595 -300.932785) (xy 19.832574 -300.974506) (xy 19.834848 -300.985648)
			(xy 19.847507 -301.004504) (xy 19.856958 -301.010828) (xy 19.892904 -301.032565) (xy 19.960952 -301.081831)
			(xy 20.024051 -301.137293) (xy 20.081641 -301.198458) (xy 20.133207 -301.264779) (xy 20.178291 -301.335666)
			(xy 20.216491 -301.410489) (xy 20.247467 -301.488579) (xy 20.270942 -301.569242) (xy 20.286707 -301.651759)
			(xy 20.294623 -301.735395) (xy 20.295108 -301.7774) (xy 20.294633 -301.818502) (xy 20.287048 -301.900357)
			(xy 20.271943 -301.981162) (xy 20.249447 -302.060229) (xy 20.219751 -302.136883) (xy 20.183109 -302.21047)
			(xy 20.139834 -302.280362) (xy 20.090294 -302.345963) (xy 20.034913 -302.406713) (xy 19.974163 -302.462094)
			(xy 19.908562 -302.511634) (xy 19.83867 -302.554909) (xy 19.765083 -302.591551) (xy 19.688429 -302.621247)
			(xy 19.609362 -302.643743) (xy 19.528557 -302.658848) (xy 19.446702 -302.666433) (xy 19.4056 -302.666908)
			(xy 19.363299 -302.666402) (xy 19.279081 -302.658354) (xy 19.196007 -302.642348) (xy 19.114828 -302.618531)
			(xy 19.036275 -302.587116) (xy 18.961058 -302.548387) (xy 18.889857 -302.502694) (xy 18.823314 -302.45045)
			(xy 18.76203 -302.392126) (xy 18.706558 -302.328249) (xy 18.657399 -302.259396) (xy 18.614996 -302.186187)
			(xy 18.579734 -302.109285) (xy 18.55193 -302.029382) (xy 18.531834 -301.947202) (xy 18.525236 -301.905416)
			(xy 18.522983 -301.89421) (xy 18.51034 -301.875211) (xy 18.500852 -301.86884) (xy 18.465024 -301.847076)
			(xy 18.397167 -301.797846) (xy 18.334248 -301.742445) (xy 18.276825 -301.681364) (xy 18.22541 -301.615147)
			(xy 18.180459 -301.544383) (xy 18.142372 -301.4697) (xy 18.111488 -301.391763) (xy 18.08808 -301.311263)
			(xy 18.072357 -301.228916) (xy 18.064458 -301.145455) (xy 18.063972 -301.103538) (xy 0.509016 -301.103538)
			(xy 0.509016 -305.209956) (xy 42.741353 -305.209956) (xy 42.745331 -305.109963) (xy 42.757241 -305.010603)
			(xy 42.777008 -304.912502) (xy 42.804507 -304.816283) (xy 42.839563 -304.722552) (xy 42.881955 -304.631903)
			(xy 42.931416 -304.544909) (xy 42.987632 -304.462119) (xy 43.050248 -304.384057) (xy 43.118867 -304.311217)
			(xy 43.193058 -304.244059) (xy 43.272349 -304.183007) (xy 43.35624 -304.128449) (xy 43.444201 -304.080728)
			(xy 43.535675 -304.040146) (xy 43.630084 -304.00696) (xy 43.726831 -303.98138) (xy 43.825305 -303.963567)
			(xy 43.924883 -303.953635) (xy 44.024935 -303.951645) (xy 44.124829 -303.957611) (xy 44.223933 -303.971495)
			(xy 44.321621 -303.993208) (xy 44.417275 -304.022614) (xy 44.51029 -304.059527) (xy 44.600078 -304.103713)
			(xy 44.686072 -304.154894) (xy 44.767728 -304.212744) (xy 44.844529 -304.2769) (xy 44.915991 -304.346954)
			(xy 44.981661 -304.422465) (xy 45.041123 -304.502955) (xy 45.094003 -304.587914) (xy 45.139966 -304.676806)
			(xy 45.178721 -304.769069) (xy 45.210023 -304.864119) (xy 45.233675 -304.961356) (xy 45.249526 -305.060165)
			(xy 45.257476 -305.15992) (xy 45.257974 -305.209956) (xy 45.257476 -305.259992) (xy 45.249526 -305.359747)
			(xy 45.233675 -305.458556) (xy 45.210023 -305.555793) (xy 45.178721 -305.650843) (xy 45.139966 -305.743106)
			(xy 45.094003 -305.831998) (xy 45.041123 -305.916957) (xy 44.981661 -305.997447) (xy 44.915991 -306.072958)
			(xy 44.844529 -306.143012) (xy 44.767728 -306.207168) (xy 44.686072 -306.265018) (xy 44.600078 -306.316199)
			(xy 44.51029 -306.360385) (xy 44.417275 -306.397298) (xy 44.321621 -306.426704) (xy 44.223933 -306.448417)
			(xy 44.124829 -306.462301) (xy 44.024935 -306.468267) (xy 43.924883 -306.466277) (xy 43.825305 -306.456345)
			(xy 43.726831 -306.438532) (xy 43.630084 -306.412952) (xy 43.535675 -306.379766) (xy 43.444201 -306.339184)
			(xy 43.35624 -306.291463) (xy 43.272349 -306.236905) (xy 43.193058 -306.175853) (xy 43.118867 -306.108695)
			(xy 43.050248 -306.035855) (xy 42.987632 -305.957793) (xy 42.931416 -305.875003) (xy 42.881955 -305.788009)
			(xy 42.839563 -305.69736) (xy 42.804507 -305.603629) (xy 42.777008 -305.50741) (xy 42.757241 -305.409309)
			(xy 42.745331 -305.309949) (xy 42.741353 -305.209956) (xy 0.509016 -305.209956) (xy 0.509016 -312.436961)
			(xy 41.147742 -312.436961) (xy 41.147742 -312.352239) (xy 41.155795 -312.267902) (xy 41.171829 -312.184712)
			(xy 41.195697 -312.103422) (xy 41.227185 -312.02477) (xy 41.266007 -311.949467) (xy 41.31181 -311.878195)
			(xy 41.364181 -311.811599) (xy 41.422646 -311.750284) (xy 41.486674 -311.694803) (xy 41.555686 -311.64566)
			(xy 41.629056 -311.6033) (xy 41.706121 -311.568105) (xy 41.786183 -311.540396) (xy 41.868516 -311.520422)
			(xy 41.952375 -311.508365) (xy 42.037 -311.504334) (xy 42.121625 -311.508365) (xy 42.205484 -311.520422)
			(xy 42.287817 -311.540396) (xy 42.367879 -311.568105) (xy 42.444944 -311.6033) (xy 42.518314 -311.64566)
			(xy 42.587326 -311.694803) (xy 42.651354 -311.750284) (xy 42.709819 -311.811599) (xy 42.76219 -311.878195)
			(xy 42.807993 -311.949467) (xy 42.846815 -312.02477) (xy 42.878303 -312.103422) (xy 42.902171 -312.184712)
			(xy 42.918205 -312.267902) (xy 42.926258 -312.352239) (xy 42.926762 -312.3946) (xy 42.926258 -312.436961)
			(xy 42.918205 -312.521298) (xy 42.902171 -312.604488) (xy 42.878303 -312.685778) (xy 42.846815 -312.76443)
			(xy 42.807993 -312.839733) (xy 42.76219 -312.911005) (xy 42.709819 -312.977601) (xy 42.651354 -313.038916)
			(xy 42.587326 -313.094397) (xy 42.518314 -313.14354) (xy 42.444944 -313.1859) (xy 42.367879 -313.221095)
			(xy 42.287817 -313.248804) (xy 42.205484 -313.268778) (xy 42.121625 -313.280835) (xy 42.037 -313.284867)
			(xy 41.952375 -313.280835) (xy 41.868516 -313.268778) (xy 41.786183 -313.248804) (xy 41.706121 -313.221095)
			(xy 41.629056 -313.1859) (xy 41.555686 -313.14354) (xy 41.486674 -313.094397) (xy 41.422646 -313.038916)
			(xy 41.364181 -312.977601) (xy 41.31181 -312.911005) (xy 41.266007 -312.839733) (xy 41.227185 -312.76443)
			(xy 41.195697 -312.685778) (xy 41.171829 -312.604488) (xy 41.155795 -312.521298) (xy 41.147742 -312.436961)
			(xy 0.509016 -312.436961) (xy 0.509016 -332.04257) (xy 2.984235 -332.04257) (xy 2.984235 -331.91343)
			(xy 2.992185 -331.784535) (xy 3.008055 -331.656375) (xy 3.031784 -331.529434) (xy 3.063283 -331.404195)
			(xy 3.102432 -331.281132) (xy 3.149083 -331.160713) (xy 3.203058 -331.043394) (xy 3.264153 -330.92962)
			(xy 3.332136 -330.819823) (xy 3.40675 -330.71442) (xy 3.487711 -330.61381) (xy 3.574711 -330.518375)
			(xy 3.667422 -330.428476) (xy 3.765492 -330.344455) (xy 3.868547 -330.266631) (xy 3.976198 -330.195299)
			(xy 4.088037 -330.130729) (xy 4.203638 -330.073167) (xy 4.322563 -330.02283) (xy 4.444362 -329.97991)
			(xy 4.568572 -329.944569) (xy 4.694721 -329.916942) (xy 4.822333 -329.897133) (xy 4.950922 -329.885217)
			(xy 5.08 -329.881241) (xy 5.209078 -329.885217) (xy 5.337667 -329.897133) (xy 5.465279 -329.916942)
			(xy 5.591428 -329.944569) (xy 5.715638 -329.97991) (xy 5.837437 -330.02283) (xy 5.956362 -330.073167)
			(xy 6.071963 -330.130729) (xy 6.183802 -330.195299) (xy 6.291453 -330.266631) (xy 6.394508 -330.344455)
			(xy 6.492578 -330.428476) (xy 6.585289 -330.518375) (xy 6.672289 -330.61381) (xy 6.75325 -330.71442)
			(xy 6.827864 -330.819823) (xy 6.895847 -330.92962) (xy 6.956942 -331.043394) (xy 7.010917 -331.160713)
			(xy 7.057568 -331.281132) (xy 7.096717 -331.404195) (xy 7.128216 -331.529434) (xy 7.151945 -331.656375)
			(xy 7.167815 -331.784535) (xy 7.175765 -331.91343) (xy 7.176262 -331.978) (xy 7.175765 -332.04257)
			(xy 7.167815 -332.171465) (xy 7.151945 -332.299625) (xy 7.128216 -332.426566) (xy 7.096717 -332.551805)
			(xy 7.057568 -332.674868) (xy 7.010917 -332.795287) (xy 6.956942 -332.912606) (xy 6.895847 -333.02638)
			(xy 6.827864 -333.136177) (xy 6.75325 -333.24158) (xy 6.672289 -333.34219) (xy 6.585289 -333.437625)
			(xy 6.492578 -333.527524) (xy 6.394508 -333.611545) (xy 6.291453 -333.689369) (xy 6.183802 -333.760701)
			(xy 6.071963 -333.825271) (xy 5.956362 -333.882833) (xy 5.837437 -333.93317) (xy 5.715638 -333.97609)
			(xy 5.591428 -334.011431) (xy 5.465279 -334.039058) (xy 5.337667 -334.058867) (xy 5.209078 -334.070783)
			(xy 5.08 -334.07476) (xy 4.950922 -334.070783) (xy 4.822333 -334.058867) (xy 4.694721 -334.039058)
			(xy 4.568572 -334.011431) (xy 4.444362 -333.97609) (xy 4.322563 -333.93317) (xy 4.203638 -333.882833)
			(xy 4.088037 -333.825271) (xy 3.976198 -333.760701) (xy 3.868547 -333.689369) (xy 3.765492 -333.611545)
			(xy 3.667422 -333.527524) (xy 3.574711 -333.437625) (xy 3.487711 -333.34219) (xy 3.40675 -333.24158)
			(xy 3.332136 -333.136177) (xy 3.264153 -333.02638) (xy 3.203058 -332.912606) (xy 3.149083 -332.795287)
			(xy 3.102432 -332.674868) (xy 3.063283 -332.551805) (xy 3.031784 -332.426566) (xy 3.008055 -332.299625)
			(xy 2.992185 -332.171465) (xy 2.984235 -332.04257) (xy 0.509016 -332.04257) (xy 0.509016 -333.000096)
			(xy 0.509503 -333.083185) (xy 0.51741 -333.249175) (xy 0.533206 -333.414601) (xy 0.556856 -333.579088)
			(xy 0.588305 -333.742263) (xy 0.627483 -333.903757) (xy 0.674301 -334.063204) (xy 0.728652 -334.220243)
			(xy 0.790415 -334.374517) (xy 0.859448 -334.525678) (xy 0.935595 -334.673383) (xy 1.018684 -334.817298)
			(xy 1.108527 -334.957096) (xy 1.20492 -335.092461) (xy 1.307644 -335.223086) (xy 1.416468 -335.348675)
			(xy 1.531144 -335.468944) (xy 1.651413 -335.58362) (xy 1.777002 -335.692444) (xy 1.907627 -335.795168)
			(xy 2.042992 -335.891561) (xy 2.18279 -335.981404) (xy 2.326705 -336.064493) (xy 2.47441 -336.14064)
			(xy 2.625571 -336.209673) (xy 2.779845 -336.271436) (xy 2.936884 -336.325787) (xy 3.096331 -336.372605)
			(xy 3.257825 -336.411783) (xy 3.421 -336.443232) (xy 3.585487 -336.466882) (xy 3.750913 -336.482678)
			(xy 3.916903 -336.490585) (xy 3.999992 -336.491072)
		)
		(stroke
			(width 0)
			(type solid)
		)
		(fill yes)
		(layer "In4.Cu")
		(net "GND")
	)
	(gr_circle
		(center 1.905 -11.176)
		(end 2.794 -11.176)
		(stroke
			(width 0.2)
			(type default)
		)
		(fill no)
		(layer "In4.Cu")
	)
	(gr_circle
		(center 3.426968 -267.146024)
		(end 4.315968 -267.146024)
		(stroke
			(width 0.2)
			(type default)
		)
		(fill no)
		(layer "In4.Cu")
	)
	(gr_circle
		(center 3.426968 -266.511024)
		(end 4.315968 -266.511024)
		(stroke
			(width 0.2)
			(type default)
		)
		(fill no)
		(layer "In4.Cu")
	)
	(gr_circle
		(center 3.426968 -265.855704)
		(end 4.315968 -265.855704)
		(stroke
			(width 0.2)
			(type default)
		)
		(fill no)
		(layer "In4.Cu")
	)
	(gr_circle
		(center 3.429 -219.075)
		(end 4.318 -219.075)
		(stroke
			(width 0.2)
			(type default)
		)
		(fill no)
		(layer "In4.Cu")
	)
	(gr_circle
		(center 3.705098 -243.513864)
		(end 4.594098 -243.513864)
		(stroke
			(width 0.2)
			(type default)
		)
		(fill no)
		(layer "In4.Cu")
	)
	(gr_circle
		(center 3.705098 -242.878864)
		(end 4.594098 -242.878864)
		(stroke
			(width 0.2)
			(type default)
		)
		(fill no)
		(layer "In4.Cu")
	)
	(gr_circle
		(center 3.705098 -58.913776)
		(end 4.594098 -58.913776)
		(stroke
			(width 0.2)
			(type default)
		)
		(fill no)
		(layer "In4.Cu")
	)
	(gr_circle
		(center 3.705098 -58.278776)
		(end 4.594098 -58.278776)
		(stroke
			(width 0.2)
			(type default)
		)
		(fill no)
		(layer "In4.Cu")
	)
	(gr_circle
		(center 4.340098 -243.513864)
		(end 5.229098 -243.513864)
		(stroke
			(width 0.2)
			(type default)
		)
		(fill no)
		(layer "In4.Cu")
	)
	(gr_circle
		(center 4.340098 -58.913776)
		(end 5.229098 -58.913776)
		(stroke
			(width 0.2)
			(type default)
		)
		(fill no)
		(layer "In4.Cu")
	)
	(gr_circle
		(center 4.350258 -242.878864)
		(end 5.239258 -242.878864)
		(stroke
			(width 0.2)
			(type default)
		)
		(fill no)
		(layer "In4.Cu")
	)
	(gr_circle
		(center 4.350258 -58.278776)
		(end 5.239258 -58.278776)
		(stroke
			(width 0.2)
			(type default)
		)
		(fill no)
		(layer "In4.Cu")
	)
	(gr_circle
		(center 4.445 -91.878912)
		(end 5.334 -91.878912)
		(stroke
			(width 0.2)
			(type default)
		)
		(fill no)
		(layer "In4.Cu")
	)
	(gr_circle
		(center 4.445 -91.116912)
		(end 5.334 -91.116912)
		(stroke
			(width 0.2)
			(type default)
		)
		(fill no)
		(layer "In4.Cu")
	)
	(gr_circle
		(center 4.61899 -264.6426)
		(end 5.50799 -264.6426)
		(stroke
			(width 0.2)
			(type default)
		)
		(fill no)
		(layer "In4.Cu")
	)
	(gr_circle
		(center 4.61899 -263.8806)
		(end 5.50799 -263.8806)
		(stroke
			(width 0.2)
			(type default)
		)
		(fill no)
		(layer "In4.Cu")
	)
	(gr_circle
		(center 4.61899 -80.067912)
		(end 5.50799 -80.067912)
		(stroke
			(width 0.2)
			(type default)
		)
		(fill no)
		(layer "In4.Cu")
	)
	(gr_circle
		(center 4.61899 -79.305912)
		(end 5.50799 -79.305912)
		(stroke
			(width 0.2)
			(type default)
		)
		(fill no)
		(layer "In4.Cu")
	)
	(gr_circle
		(center 4.826 -281.2542)
		(end 5.715 -281.2542)
		(stroke
			(width 0.2)
			(type default)
		)
		(fill no)
		(layer "In4.Cu")
	)
	(gr_circle
		(center 4.826 -280.4922)
		(end 5.715 -280.4922)
		(stroke
			(width 0.2)
			(type default)
		)
		(fill no)
		(layer "In4.Cu")
	)
	(gr_circle
		(center 4.995418 -243.513864)
		(end 5.884418 -243.513864)
		(stroke
			(width 0.2)
			(type default)
		)
		(fill no)
		(layer "In4.Cu")
	)
	(gr_circle
		(center 4.995418 -242.878864)
		(end 5.884418 -242.878864)
		(stroke
			(width 0.2)
			(type default)
		)
		(fill no)
		(layer "In4.Cu")
	)
	(gr_circle
		(center 4.995418 -58.913776)
		(end 5.884418 -58.913776)
		(stroke
			(width 0.2)
			(type default)
		)
		(fill no)
		(layer "In4.Cu")
	)
	(gr_circle
		(center 4.995418 -58.278776)
		(end 5.884418 -58.278776)
		(stroke
			(width 0.2)
			(type default)
		)
		(fill no)
		(layer "In4.Cu")
	)
	(gr_circle
		(center 5.207 -91.878912)
		(end 6.096 -91.878912)
		(stroke
			(width 0.2)
			(type default)
		)
		(fill no)
		(layer "In4.Cu")
	)
	(gr_circle
		(center 5.207 -91.116912)
		(end 6.096 -91.116912)
		(stroke
			(width 0.2)
			(type default)
		)
		(fill no)
		(layer "In4.Cu")
	)
	(gr_circle
		(center 5.38099 -80.067912)
		(end 6.26999 -80.067912)
		(stroke
			(width 0.2)
			(type default)
		)
		(fill no)
		(layer "In4.Cu")
	)
	(gr_circle
		(center 5.38099 -79.305912)
		(end 6.26999 -79.305912)
		(stroke
			(width 0.2)
			(type default)
		)
		(fill no)
		(layer "In4.Cu")
	)
	(gr_circle
		(center 5.43179 -264.6426)
		(end 6.32079 -264.6426)
		(stroke
			(width 0.2)
			(type default)
		)
		(fill no)
		(layer "In4.Cu")
	)
	(gr_circle
		(center 5.43179 -263.8806)
		(end 6.32079 -263.8806)
		(stroke
			(width 0.2)
			(type default)
		)
		(fill no)
		(layer "In4.Cu")
	)
	(gr_circle
		(center 5.588 -281.2542)
		(end 6.477 -281.2542)
		(stroke
			(width 0.2)
			(type default)
		)
		(fill no)
		(layer "In4.Cu")
	)
	(gr_circle
		(center 5.588 -280.4922)
		(end 6.477 -280.4922)
		(stroke
			(width 0.2)
			(type default)
		)
		(fill no)
		(layer "In4.Cu")
	)
	(gr_circle
		(center 5.842 -193.04)
		(end 6.731 -193.04)
		(stroke
			(width 0.2)
			(type default)
		)
		(fill no)
		(layer "In4.Cu")
	)
	(gr_circle
		(center 5.969 -91.878912)
		(end 6.858 -91.878912)
		(stroke
			(width 0.2)
			(type default)
		)
		(fill no)
		(layer "In4.Cu")
	)
	(gr_circle
		(center 5.969 -91.116912)
		(end 6.858 -91.116912)
		(stroke
			(width 0.2)
			(type default)
		)
		(fill no)
		(layer "In4.Cu")
	)
	(gr_circle
		(center 6.14299 -80.067912)
		(end 7.03199 -80.067912)
		(stroke
			(width 0.2)
			(type default)
		)
		(fill no)
		(layer "In4.Cu")
	)
	(gr_circle
		(center 6.14299 -79.305912)
		(end 7.03199 -79.305912)
		(stroke
			(width 0.2)
			(type default)
		)
		(fill no)
		(layer "In4.Cu")
	)
	(gr_circle
		(center 6.26999 -264.6172)
		(end 7.15899 -264.6172)
		(stroke
			(width 0.2)
			(type default)
		)
		(fill no)
		(layer "In4.Cu")
	)
	(gr_circle
		(center 6.26999 -263.8552)
		(end 7.15899 -263.8552)
		(stroke
			(width 0.2)
			(type default)
		)
		(fill no)
		(layer "In4.Cu")
	)
	(gr_circle
		(center 6.35 -281.2542)
		(end 7.239 -281.2542)
		(stroke
			(width 0.2)
			(type default)
		)
		(fill no)
		(layer "In4.Cu")
	)
	(gr_circle
		(center 6.35 -280.4922)
		(end 7.239 -280.4922)
		(stroke
			(width 0.2)
			(type default)
		)
		(fill no)
		(layer "In4.Cu")
	)
	(gr_circle
		(center 6.700012 -299.310044)
		(end 8.020812 -299.310044)
		(stroke
			(width 0.2)
			(type default)
		)
		(fill no)
		(layer "In4.Cu")
	)
	(gr_circle
		(center 6.700012 -207.01)
		(end 8.020812 -207.01)
		(stroke
			(width 0.2)
			(type default)
		)
		(fill no)
		(layer "In4.Cu")
	)
	(gr_circle
		(center 6.700012 -114.709956)
		(end 8.020812 -114.709956)
		(stroke
			(width 0.2)
			(type default)
		)
		(fill no)
		(layer "In4.Cu")
	)
	(gr_circle
		(center 6.700012 -22.409912)
		(end 8.020812 -22.409912)
		(stroke
			(width 0.2)
			(type default)
		)
		(fill no)
		(layer "In4.Cu")
	)
	(gr_circle
		(center 6.731 -91.878912)
		(end 7.62 -91.878912)
		(stroke
			(width 0.2)
			(type default)
		)
		(fill no)
		(layer "In4.Cu")
	)
	(gr_circle
		(center 6.731 -91.116912)
		(end 7.62 -91.116912)
		(stroke
			(width 0.2)
			(type default)
		)
		(fill no)
		(layer "In4.Cu")
	)
	(gr_circle
		(center 6.804914 -244.31371)
		(end 7.693914 -244.31371)
		(stroke
			(width 0.2)
			(type default)
		)
		(fill no)
		(layer "In4.Cu")
	)
	(gr_circle
		(center 6.804914 -243.67871)
		(end 7.693914 -243.67871)
		(stroke
			(width 0.2)
			(type default)
		)
		(fill no)
		(layer "In4.Cu")
	)
	(gr_circle
		(center 6.804914 -59.713622)
		(end 7.693914 -59.713622)
		(stroke
			(width 0.2)
			(type default)
		)
		(fill no)
		(layer "In4.Cu")
	)
	(gr_circle
		(center 6.804914 -59.078622)
		(end 7.693914 -59.078622)
		(stroke
			(width 0.2)
			(type default)
		)
		(fill no)
		(layer "In4.Cu")
	)
	(gr_circle
		(center 6.90499 -80.067912)
		(end 7.79399 -80.067912)
		(stroke
			(width 0.2)
			(type default)
		)
		(fill no)
		(layer "In4.Cu")
	)
	(gr_circle
		(center 6.90499 -79.305912)
		(end 7.79399 -79.305912)
		(stroke
			(width 0.2)
			(type default)
		)
		(fill no)
		(layer "In4.Cu")
	)
	(gr_circle
		(center 7.007098 -238.20501)
		(end 7.896098 -238.20501)
		(stroke
			(width 0.2)
			(type default)
		)
		(fill no)
		(layer "In4.Cu")
	)
	(gr_circle
		(center 7.007098 -237.44301)
		(end 7.896098 -237.44301)
		(stroke
			(width 0.2)
			(type default)
		)
		(fill no)
		(layer "In4.Cu")
	)
	(gr_circle
		(center 7.414514 -53.448712)
		(end 8.303514 -53.448712)
		(stroke
			(width 0.2)
			(type default)
		)
		(fill no)
		(layer "In4.Cu")
	)
	(gr_circle
		(center 7.414514 -52.686712)
		(end 8.303514 -52.686712)
		(stroke
			(width 0.2)
			(type default)
		)
		(fill no)
		(layer "In4.Cu")
	)
	(gr_circle
		(center 7.439914 -244.31371)
		(end 8.328914 -244.31371)
		(stroke
			(width 0.2)
			(type default)
		)
		(fill no)
		(layer "In4.Cu")
	)
	(gr_circle
		(center 7.439914 -59.713622)
		(end 8.328914 -59.713622)
		(stroke
			(width 0.2)
			(type default)
		)
		(fill no)
		(layer "In4.Cu")
	)
	(gr_circle
		(center 7.450074 -243.67871)
		(end 8.339074 -243.67871)
		(stroke
			(width 0.2)
			(type default)
		)
		(fill no)
		(layer "In4.Cu")
	)
	(gr_circle
		(center 7.450074 -59.078622)
		(end 8.339074 -59.078622)
		(stroke
			(width 0.2)
			(type default)
		)
		(fill no)
		(layer "In4.Cu")
	)
	(gr_circle
		(center 8.095234 -244.31371)
		(end 8.984234 -244.31371)
		(stroke
			(width 0.2)
			(type default)
		)
		(fill no)
		(layer "In4.Cu")
	)
	(gr_circle
		(center 8.095234 -243.67871)
		(end 8.984234 -243.67871)
		(stroke
			(width 0.2)
			(type default)
		)
		(fill no)
		(layer "In4.Cu")
	)
	(gr_circle
		(center 8.095234 -59.713622)
		(end 8.984234 -59.713622)
		(stroke
			(width 0.2)
			(type default)
		)
		(fill no)
		(layer "In4.Cu")
	)
	(gr_circle
		(center 8.095234 -59.078622)
		(end 8.984234 -59.078622)
		(stroke
			(width 0.2)
			(type default)
		)
		(fill no)
		(layer "In4.Cu")
	)
	(gr_circle
		(center 8.26135 -230.439214)
		(end 9.15035 -230.439214)
		(stroke
			(width 0.2)
			(type default)
		)
		(fill no)
		(layer "In4.Cu")
	)
	(gr_circle
		(center 8.26135 -229.677214)
		(end 9.15035 -229.677214)
		(stroke
			(width 0.2)
			(type default)
		)
		(fill no)
		(layer "In4.Cu")
	)
	(gr_circle
		(center 8.28675 -235.773214)
		(end 9.17575 -235.773214)
		(stroke
			(width 0.2)
			(type default)
		)
		(fill no)
		(layer "In4.Cu")
	)
	(gr_circle
		(center 8.28675 -235.011214)
		(end 9.17575 -235.011214)
		(stroke
			(width 0.2)
			(type default)
		)
		(fill no)
		(layer "In4.Cu")
	)
	(gr_circle
		(center 8.33755 -233.131614)
		(end 9.22655 -233.131614)
		(stroke
			(width 0.2)
			(type default)
		)
		(fill no)
		(layer "In4.Cu")
	)
	(gr_circle
		(center 8.33755 -232.369614)
		(end 9.22655 -232.369614)
		(stroke
			(width 0.2)
			(type default)
		)
		(fill no)
		(layer "In4.Cu")
	)
	(gr_circle
		(center 8.700008 -297.310048)
		(end 10.020808 -297.310048)
		(stroke
			(width 0.2)
			(type default)
		)
		(fill no)
		(layer "In4.Cu")
	)
	(gr_circle
		(center 8.700008 -205.010004)
		(end 10.020808 -205.010004)
		(stroke
			(width 0.2)
			(type default)
		)
		(fill no)
		(layer "In4.Cu")
	)
	(gr_circle
		(center 8.700008 -112.70996)
		(end 10.020808 -112.70996)
		(stroke
			(width 0.2)
			(type default)
		)
		(fill no)
		(layer "In4.Cu")
	)
	(gr_circle
		(center 8.700008 -20.409916)
		(end 10.020808 -20.409916)
		(stroke
			(width 0.2)
			(type default)
		)
		(fill no)
		(layer "In4.Cu")
	)
	(gr_circle
		(center 8.73252 -46.391322)
		(end 9.62152 -46.391322)
		(stroke
			(width 0.2)
			(type default)
		)
		(fill no)
		(layer "In4.Cu")
	)
	(gr_circle
		(center 8.73252 -45.629322)
		(end 9.62152 -45.629322)
		(stroke
			(width 0.2)
			(type default)
		)
		(fill no)
		(layer "In4.Cu")
	)
	(gr_circle
		(center 8.75792 -51.369722)
		(end 9.64692 -51.369722)
		(stroke
			(width 0.2)
			(type default)
		)
		(fill no)
		(layer "In4.Cu")
	)
	(gr_circle
		(center 8.75792 -50.607722)
		(end 9.64692 -50.607722)
		(stroke
			(width 0.2)
			(type default)
		)
		(fill no)
		(layer "In4.Cu")
	)
	(gr_circle
		(center 8.774176 -48.90516)
		(end 9.663176 -48.90516)
		(stroke
			(width 0.2)
			(type default)
		)
		(fill no)
		(layer "In4.Cu")
	)
	(gr_circle
		(center 8.774176 -48.14316)
		(end 9.663176 -48.14316)
		(stroke
			(width 0.2)
			(type default)
		)
		(fill no)
		(layer "In4.Cu")
	)
	(gr_circle
		(center 9.44499 -80.321912)
		(end 10.33399 -80.321912)
		(stroke
			(width 0.2)
			(type default)
		)
		(fill no)
		(layer "In4.Cu")
	)
	(gr_circle
		(center 9.54659 -264.4902)
		(end 10.43559 -264.4902)
		(stroke
			(width 0.2)
			(type default)
		)
		(fill no)
		(layer "In4.Cu")
	)
	(gr_circle
		(center 9.948418 -243.4336)
		(end 10.837418 -243.4336)
		(stroke
			(width 0.2)
			(type default)
		)
		(fill no)
		(layer "In4.Cu")
	)
	(gr_circle
		(center 9.948418 -58.477912)
		(end 10.837418 -58.477912)
		(stroke
			(width 0.2)
			(type default)
		)
		(fill no)
		(layer "In4.Cu")
	)
	(gr_circle
		(center 10.20699 -80.321912)
		(end 11.09599 -80.321912)
		(stroke
			(width 0.2)
			(type default)
		)
		(fill no)
		(layer "In4.Cu")
	)
	(gr_circle
		(center 10.30859 -264.4902)
		(end 11.19759 -264.4902)
		(stroke
			(width 0.2)
			(type default)
		)
		(fill no)
		(layer "In4.Cu")
	)
	(gr_circle
		(center 10.710418 -243.4336)
		(end 11.599418 -243.4336)
		(stroke
			(width 0.2)
			(type default)
		)
		(fill no)
		(layer "In4.Cu")
	)
	(gr_circle
		(center 10.710418 -58.477912)
		(end 11.599418 -58.477912)
		(stroke
			(width 0.2)
			(type default)
		)
		(fill no)
		(layer "In4.Cu")
	)
	(gr_circle
		(center 11.277346 -38.649656)
		(end 12.166346 -38.649656)
		(stroke
			(width 0.2)
			(type default)
		)
		(fill no)
		(layer "In4.Cu")
	)
	(gr_circle
		(center 11.277346 -38.014656)
		(end 12.166346 -38.014656)
		(stroke
			(width 0.2)
			(type default)
		)
		(fill no)
		(layer "In4.Cu")
	)
	(gr_circle
		(center 11.277346 -37.303456)
		(end 12.166346 -37.303456)
		(stroke
			(width 0.2)
			(type default)
		)
		(fill no)
		(layer "In4.Cu")
	)
	(gr_circle
		(center 11.299698 -44.263056)
		(end 12.188698 -44.263056)
		(stroke
			(width 0.2)
			(type default)
		)
		(fill no)
		(layer "In4.Cu")
	)
	(gr_circle
		(center 11.299698 -43.501056)
		(end 12.188698 -43.501056)
		(stroke
			(width 0.2)
			(type default)
		)
		(fill no)
		(layer "In4.Cu")
	)
	(gr_circle
		(center 12.039346 -38.649656)
		(end 12.928346 -38.649656)
		(stroke
			(width 0.2)
			(type default)
		)
		(fill no)
		(layer "In4.Cu")
	)
	(gr_circle
		(center 12.039346 -38.014656)
		(end 12.928346 -38.014656)
		(stroke
			(width 0.2)
			(type default)
		)
		(fill no)
		(layer "In4.Cu")
	)
	(gr_circle
		(center 12.039346 -37.303456)
		(end 12.928346 -37.303456)
		(stroke
			(width 0.2)
			(type default)
		)
		(fill no)
		(layer "In4.Cu")
	)
	(gr_circle
		(center 12.060174 -79.721202)
		(end 12.949174 -79.721202)
		(stroke
			(width 0.2)
			(type default)
		)
		(fill no)
		(layer "In4.Cu")
	)
	(gr_circle
		(center 12.060174 -79.086202)
		(end 12.949174 -79.086202)
		(stroke
			(width 0.2)
			(type default)
		)
		(fill no)
		(layer "In4.Cu")
	)
	(gr_circle
		(center 12.061698 -44.263056)
		(end 12.950698 -44.263056)
		(stroke
			(width 0.2)
			(type default)
		)
		(fill no)
		(layer "In4.Cu")
	)
	(gr_circle
		(center 12.061698 -43.501056)
		(end 12.950698 -43.501056)
		(stroke
			(width 0.2)
			(type default)
		)
		(fill no)
		(layer "In4.Cu")
	)
	(gr_circle
		(center 12.187174 -264.32129)
		(end 13.076174 -264.32129)
		(stroke
			(width 0.2)
			(type default)
		)
		(fill no)
		(layer "In4.Cu")
	)
	(gr_circle
		(center 12.187174 -263.68629)
		(end 13.076174 -263.68629)
		(stroke
			(width 0.2)
			(type default)
		)
		(fill no)
		(layer "In4.Cu")
	)
	(gr_circle
		(center 12.270232 -224.38741)
		(end 13.159232 -224.38741)
		(stroke
			(width 0.2)
			(type default)
		)
		(fill no)
		(layer "In4.Cu")
	)
	(gr_circle
		(center 12.270232 -223.62541)
		(end 13.159232 -223.62541)
		(stroke
			(width 0.2)
			(type default)
		)
		(fill no)
		(layer "In4.Cu")
	)
	(gr_circle
		(center 12.270232 -222.86341)
		(end 13.159232 -222.86341)
		(stroke
			(width 0.2)
			(type default)
		)
		(fill no)
		(layer "In4.Cu")
	)
	(gr_circle
		(center 12.307824 -58.474356)
		(end 13.196824 -58.474356)
		(stroke
			(width 0.2)
			(type default)
		)
		(fill no)
		(layer "In4.Cu")
	)
	(gr_circle
		(center 12.313158 -59.298078)
		(end 13.202158 -59.298078)
		(stroke
			(width 0.2)
			(type default)
		)
		(fill no)
		(layer "In4.Cu")
	)
	(gr_circle
		(center 12.352274 -246.305578)
		(end 13.241274 -246.305578)
		(stroke
			(width 0.2)
			(type default)
		)
		(fill no)
		(layer "In4.Cu")
	)
	(gr_circle
		(center 12.352274 -245.670578)
		(end 13.241274 -245.670578)
		(stroke
			(width 0.2)
			(type default)
		)
		(fill no)
		(layer "In4.Cu")
	)
	(gr_circle
		(center 12.352274 -245.010178)
		(end 13.241274 -245.010178)
		(stroke
			(width 0.2)
			(type default)
		)
		(fill no)
		(layer "In4.Cu")
	)
	(gr_circle
		(center 12.352274 -244.375178)
		(end 13.241274 -244.375178)
		(stroke
			(width 0.2)
			(type default)
		)
		(fill no)
		(layer "In4.Cu")
	)
	(gr_circle
		(center 12.377674 -247.600978)
		(end 13.266674 -247.600978)
		(stroke
			(width 0.2)
			(type default)
		)
		(fill no)
		(layer "In4.Cu")
	)
	(gr_circle
		(center 12.377674 -246.965978)
		(end 13.266674 -246.965978)
		(stroke
			(width 0.2)
			(type default)
		)
		(fill no)
		(layer "In4.Cu")
	)
	(gr_circle
		(center 12.377674 -243.714778)
		(end 13.266674 -243.714778)
		(stroke
			(width 0.2)
			(type default)
		)
		(fill no)
		(layer "In4.Cu")
	)
	(gr_circle
		(center 12.377674 -243.079778)
		(end 13.266674 -243.079778)
		(stroke
			(width 0.2)
			(type default)
		)
		(fill no)
		(layer "In4.Cu")
	)
	(gr_circle
		(center 12.705334 -79.721202)
		(end 13.594334 -79.721202)
		(stroke
			(width 0.2)
			(type default)
		)
		(fill no)
		(layer "In4.Cu")
	)
	(gr_circle
		(center 12.715494 -79.086202)
		(end 13.604494 -79.086202)
		(stroke
			(width 0.2)
			(type default)
		)
		(fill no)
		(layer "In4.Cu")
	)
	(gr_circle
		(center 12.832334 -264.32129)
		(end 13.721334 -264.32129)
		(stroke
			(width 0.2)
			(type default)
		)
		(fill no)
		(layer "In4.Cu")
	)
	(gr_circle
		(center 12.842494 -263.68629)
		(end 13.731494 -263.68629)
		(stroke
			(width 0.2)
			(type default)
		)
		(fill no)
		(layer "In4.Cu")
	)
	(gr_circle
		(center 12.905232 -224.38741)
		(end 13.794232 -224.38741)
		(stroke
			(width 0.2)
			(type default)
		)
		(fill no)
		(layer "In4.Cu")
	)
	(gr_circle
		(center 12.905232 -223.62541)
		(end 13.794232 -223.62541)
		(stroke
			(width 0.2)
			(type default)
		)
		(fill no)
		(layer "In4.Cu")
	)
	(gr_circle
		(center 12.905232 -222.86341)
		(end 13.794232 -222.86341)
		(stroke
			(width 0.2)
			(type default)
		)
		(fill no)
		(layer "In4.Cu")
	)
	(gr_circle
		(center 12.945618 -62.541912)
		(end 13.834618 -62.541912)
		(stroke
			(width 0.2)
			(type default)
		)
		(fill no)
		(layer "In4.Cu")
	)
	(gr_circle
		(center 13.069824 -58.474356)
		(end 13.958824 -58.474356)
		(stroke
			(width 0.2)
			(type default)
		)
		(fill no)
		(layer "In4.Cu")
	)
	(gr_circle
		(center 13.075158 -59.298078)
		(end 13.964158 -59.298078)
		(stroke
			(width 0.2)
			(type default)
		)
		(fill no)
		(layer "In4.Cu")
	)
	(gr_circle
		(center 13.350494 -79.721202)
		(end 14.239494 -79.721202)
		(stroke
			(width 0.2)
			(type default)
		)
		(fill no)
		(layer "In4.Cu")
	)
	(gr_circle
		(center 13.350494 -79.086202)
		(end 14.239494 -79.086202)
		(stroke
			(width 0.2)
			(type default)
		)
		(fill no)
		(layer "In4.Cu")
	)
	(gr_circle
		(center 13.462 -93.979238)
		(end 14.351 -93.979238)
		(stroke
			(width 0.2)
			(type default)
		)
		(fill no)
		(layer "In4.Cu")
	)
	(gr_circle
		(center 13.462 -93.344238)
		(end 14.351 -93.344238)
		(stroke
			(width 0.2)
			(type default)
		)
		(fill no)
		(layer "In4.Cu")
	)
	(gr_circle
		(center 13.462 -92.709238)
		(end 14.351 -92.709238)
		(stroke
			(width 0.2)
			(type default)
		)
		(fill no)
		(layer "In4.Cu")
	)
	(gr_circle
		(center 13.462 -89.153238)
		(end 14.351 -89.153238)
		(stroke
			(width 0.2)
			(type default)
		)
		(fill no)
		(layer "In4.Cu")
	)
	(gr_circle
		(center 13.462 -88.518238)
		(end 14.351 -88.518238)
		(stroke
			(width 0.2)
			(type default)
		)
		(fill no)
		(layer "In4.Cu")
	)
	(gr_circle
		(center 13.462 -87.883238)
		(end 14.351 -87.883238)
		(stroke
			(width 0.2)
			(type default)
		)
		(fill no)
		(layer "In4.Cu")
	)
	(gr_circle
		(center 13.477494 -264.32129)
		(end 14.366494 -264.32129)
		(stroke
			(width 0.2)
			(type default)
		)
		(fill no)
		(layer "In4.Cu")
	)
	(gr_circle
		(center 13.477494 -263.68629)
		(end 14.366494 -263.68629)
		(stroke
			(width 0.2)
			(type default)
		)
		(fill no)
		(layer "In4.Cu")
	)
	(gr_circle
		(center 13.707618 -62.541912)
		(end 14.596618 -62.541912)
		(stroke
			(width 0.2)
			(type default)
		)
		(fill no)
		(layer "In4.Cu")
	)
	(gr_circle
		(center 13.831824 -58.474356)
		(end 14.720824 -58.474356)
		(stroke
			(width 0.2)
			(type default)
		)
		(fill no)
		(layer "In4.Cu")
	)
	(gr_circle
		(center 13.837158 -59.298078)
		(end 14.726158 -59.298078)
		(stroke
			(width 0.2)
			(type default)
		)
		(fill no)
		(layer "In4.Cu")
	)
	(gr_circle
		(center 14.13129 -277.895304)
		(end 15.02029 -277.895304)
		(stroke
			(width 0.2)
			(type default)
		)
		(fill no)
		(layer "In4.Cu")
	)
	(gr_circle
		(center 14.13129 -277.02891)
		(end 15.02029 -277.02891)
		(stroke
			(width 0.2)
			(type default)
		)
		(fill no)
		(layer "In4.Cu")
	)
	(gr_circle
		(center 14.1478 -274.139406)
		(end 15.0368 -274.139406)
		(stroke
			(width 0.2)
			(type default)
		)
		(fill no)
		(layer "In4.Cu")
	)
	(gr_circle
		(center 14.1478 -273.273012)
		(end 15.0368 -273.273012)
		(stroke
			(width 0.2)
			(type default)
		)
		(fill no)
		(layer "In4.Cu")
	)
	(gr_circle
		(center 14.1478 -86.995)
		(end 15.0368 -86.995)
		(stroke
			(width 0.2)
			(type default)
		)
		(fill no)
		(layer "In4.Cu")
	)
	(gr_circle
		(center 14.148054 -272.25244)
		(end 15.037054 -272.25244)
		(stroke
			(width 0.2)
			(type default)
		)
		(fill no)
		(layer "In4.Cu")
	)
	(gr_circle
		(center 14.148054 -271.386046)
		(end 15.037054 -271.386046)
		(stroke
			(width 0.2)
			(type default)
		)
		(fill no)
		(layer "In4.Cu")
	)
	(gr_circle
		(center 14.469618 -62.541912)
		(end 15.358618 -62.541912)
		(stroke
			(width 0.2)
			(type default)
		)
		(fill no)
		(layer "In4.Cu")
	)
	(gr_circle
		(center 15.15999 -80.521048)
		(end 16.04899 -80.521048)
		(stroke
			(width 0.2)
			(type default)
		)
		(fill no)
		(layer "In4.Cu")
	)
	(gr_circle
		(center 15.15999 -79.886048)
		(end 16.04899 -79.886048)
		(stroke
			(width 0.2)
			(type default)
		)
		(fill no)
		(layer "In4.Cu")
	)
	(gr_circle
		(center 15.24 -202.67295)
		(end 16.129 -202.67295)
		(stroke
			(width 0.2)
			(type default)
		)
		(fill no)
		(layer "In4.Cu")
	)
	(gr_circle
		(center 15.28699 -265.121136)
		(end 16.17599 -265.121136)
		(stroke
			(width 0.2)
			(type default)
		)
		(fill no)
		(layer "In4.Cu")
	)
	(gr_circle
		(center 15.28699 -264.486136)
		(end 16.17599 -264.486136)
		(stroke
			(width 0.2)
			(type default)
		)
		(fill no)
		(layer "In4.Cu")
	)
	(gr_circle
		(center 15.501366 -270.294862)
		(end 16.390366 -270.294862)
		(stroke
			(width 0.2)
			(type default)
		)
		(fill no)
		(layer "In4.Cu")
	)
	(gr_circle
		(center 15.501366 -269.428468)
		(end 16.390366 -269.428468)
		(stroke
			(width 0.2)
			(type default)
		)
		(fill no)
		(layer "In4.Cu")
	)
	(gr_circle
		(center 15.80515 -80.521048)
		(end 16.69415 -80.521048)
		(stroke
			(width 0.2)
			(type default)
		)
		(fill no)
		(layer "In4.Cu")
	)
	(gr_circle
		(center 15.81531 -79.886048)
		(end 16.70431 -79.886048)
		(stroke
			(width 0.2)
			(type default)
		)
		(fill no)
		(layer "In4.Cu")
	)
	(gr_circle
		(center 15.93215 -265.121136)
		(end 16.82115 -265.121136)
		(stroke
			(width 0.2)
			(type default)
		)
		(fill no)
		(layer "In4.Cu")
	)
	(gr_circle
		(center 15.94231 -264.486136)
		(end 16.83131 -264.486136)
		(stroke
			(width 0.2)
			(type default)
		)
		(fill no)
		(layer "In4.Cu")
	)
	(gr_circle
		(center 16.45031 -80.521048)
		(end 17.33931 -80.521048)
		(stroke
			(width 0.2)
			(type default)
		)
		(fill no)
		(layer "In4.Cu")
	)
	(gr_circle
		(center 16.45031 -79.886048)
		(end 17.33931 -79.886048)
		(stroke
			(width 0.2)
			(type default)
		)
		(fill no)
		(layer "In4.Cu")
	)
	(gr_circle
		(center 16.57731 -265.121136)
		(end 17.46631 -265.121136)
		(stroke
			(width 0.2)
			(type default)
		)
		(fill no)
		(layer "In4.Cu")
	)
	(gr_circle
		(center 16.57731 -264.486136)
		(end 17.46631 -264.486136)
		(stroke
			(width 0.2)
			(type default)
		)
		(fill no)
		(layer "In4.Cu")
	)
	(gr_circle
		(center 17.272 -204.369924)
		(end 18.161 -204.369924)
		(stroke
			(width 0.2)
			(type default)
		)
		(fill no)
		(layer "In4.Cu")
	)
	(gr_circle
		(center 17.907 -112.649)
		(end 18.796 -112.649)
		(stroke
			(width 0.2)
			(type default)
		)
		(fill no)
		(layer "In4.Cu")
	)
	(gr_circle
		(center 18.034 -108.458)
		(end 18.923 -108.458)
		(stroke
			(width 0.2)
			(type default)
		)
		(fill no)
		(layer "In4.Cu")
	)
	(gr_circle
		(center 18.1102 -116.84)
		(end 18.9992 -116.84)
		(stroke
			(width 0.2)
			(type default)
		)
		(fill no)
		(layer "In4.Cu")
	)
	(gr_circle
		(center 19.177 -216.535)
		(end 20.066 -216.535)
		(stroke
			(width 0.2)
			(type default)
		)
		(fill no)
		(layer "In4.Cu")
	)
	(gr_circle
		(center 19.304 -33.909)
		(end 20.193 -33.909)
		(stroke
			(width 0.2)
			(type default)
		)
		(fill no)
		(layer "In4.Cu")
	)
	(gr_circle
		(center 19.4056 -301.7774)
		(end 20.2946 -301.7774)
		(stroke
			(width 0.2)
			(type default)
		)
		(fill no)
		(layer "In4.Cu")
	)
	(gr_circle
		(center 19.492722 -29.591)
		(end 20.381722 -29.591)
		(stroke
			(width 0.2)
			(type default)
		)
		(fill no)
		(layer "In4.Cu")
	)
	(gr_circle
		(center 19.558 -209.169)
		(end 20.447 -209.169)
		(stroke
			(width 0.2)
			(type default)
		)
		(fill no)
		(layer "In4.Cu")
	)
	(gr_circle
		(center 19.6596 -196.85)
		(end 20.5486 -196.85)
		(stroke
			(width 0.2)
			(type default)
		)
		(fill no)
		(layer "In4.Cu")
	)
	(gr_circle
		(center 20.193 -288.036)
		(end 21.082 -288.036)
		(stroke
			(width 0.2)
			(type default)
		)
		(fill no)
		(layer "In4.Cu")
	)
	(gr_circle
		(center 20.32 -210.439)
		(end 21.209 -210.439)
		(stroke
			(width 0.2)
			(type default)
		)
		(fill no)
		(layer "In4.Cu")
	)
	(gr_circle
		(center 20.447 -18.796)
		(end 21.336 -18.796)
		(stroke
			(width 0.2)
			(type default)
		)
		(fill no)
		(layer "In4.Cu")
	)
	(gr_circle
		(center 20.828 -105.41)
		(end 21.717 -105.41)
		(stroke
			(width 0.2)
			(type default)
		)
		(fill no)
		(layer "In4.Cu")
	)
	(gr_circle
		(center 20.955 -101.092)
		(end 21.844 -101.092)
		(stroke
			(width 0.2)
			(type default)
		)
		(fill no)
		(layer "In4.Cu")
	)
	(gr_circle
		(center 21.336 -214.6173)
		(end 22.225 -214.6173)
		(stroke
			(width 0.2)
			(type default)
		)
		(fill no)
		(layer "In4.Cu")
	)
	(gr_circle
		(center 26.035 -248.793)
		(end 26.924 -248.793)
		(stroke
			(width 0.2)
			(type default)
		)
		(fill no)
		(layer "In4.Cu")
	)
	(gr_circle
		(center 27.178 -98.933)
		(end 28.067 -98.933)
		(stroke
			(width 0.2)
			(type default)
		)
		(fill no)
		(layer "In4.Cu")
	)
	(gr_circle
		(center 28.326588 -13.2842)
		(end 29.215588 -13.2842)
		(stroke
			(width 0.2)
			(type default)
		)
		(fill no)
		(layer "In4.Cu")
	)
	(gr_circle
		(center 28.326588 -12.6492)
		(end 29.215588 -12.6492)
		(stroke
			(width 0.2)
			(type default)
		)
		(fill no)
		(layer "In4.Cu")
	)
	(gr_circle
		(center 28.326588 -12.0142)
		(end 29.215588 -12.0142)
		(stroke
			(width 0.2)
			(type default)
		)
		(fill no)
		(layer "In4.Cu")
	)
	(gr_circle
		(center 28.326588 -11.3792)
		(end 29.215588 -11.3792)
		(stroke
			(width 0.2)
			(type default)
		)
		(fill no)
		(layer "In4.Cu")
	)
	(gr_circle
		(center 28.326588 -10.7442)
		(end 29.215588 -10.7442)
		(stroke
			(width 0.2)
			(type default)
		)
		(fill no)
		(layer "In4.Cu")
	)
	(gr_circle
		(center 28.326588 -10.1092)
		(end 29.215588 -10.1092)
		(stroke
			(width 0.2)
			(type default)
		)
		(fill no)
		(layer "In4.Cu")
	)
	(gr_circle
		(center 29.088588 -13.2842)
		(end 29.977588 -13.2842)
		(stroke
			(width 0.2)
			(type default)
		)
		(fill no)
		(layer "In4.Cu")
	)
	(gr_circle
		(center 29.088588 -12.6492)
		(end 29.977588 -12.6492)
		(stroke
			(width 0.2)
			(type default)
		)
		(fill no)
		(layer "In4.Cu")
	)
	(gr_circle
		(center 29.088588 -12.0142)
		(end 29.977588 -12.0142)
		(stroke
			(width 0.2)
			(type default)
		)
		(fill no)
		(layer "In4.Cu")
	)
	(gr_circle
		(center 29.088588 -11.3792)
		(end 29.977588 -11.3792)
		(stroke
			(width 0.2)
			(type default)
		)
		(fill no)
		(layer "In4.Cu")
	)
	(gr_circle
		(center 29.088588 -10.7442)
		(end 29.977588 -10.7442)
		(stroke
			(width 0.2)
			(type default)
		)
		(fill no)
		(layer "In4.Cu")
	)
	(gr_circle
		(center 29.088588 -10.1092)
		(end 29.977588 -10.1092)
		(stroke
			(width 0.2)
			(type default)
		)
		(fill no)
		(layer "In4.Cu")
	)
	(gr_circle
		(center 29.845 -101.219)
		(end 30.734 -101.219)
		(stroke
			(width 0.2)
			(type default)
		)
		(fill no)
		(layer "In4.Cu")
	)
	(gr_circle
		(center 30.988 -117.602)
		(end 31.877 -117.602)
		(stroke
			(width 0.2)
			(type default)
		)
		(fill no)
		(layer "In4.Cu")
	)
	(gr_circle
		(center 31.115 -25.908)
		(end 32.004 -25.908)
		(stroke
			(width 0.2)
			(type default)
		)
		(fill no)
		(layer "In4.Cu")
	)
	(gr_circle
		(center 31.242 -299.974)
		(end 32.131 -299.974)
		(stroke
			(width 0.2)
			(type default)
		)
		(fill no)
		(layer "In4.Cu")
	)
	(gr_circle
		(center 31.242 -210.594956)
		(end 32.131 -210.594956)
		(stroke
			(width 0.2)
			(type default)
		)
		(fill no)
		(layer "In4.Cu")
	)
	(gr_circle
		(center 31.369 -288.925)
		(end 32.258 -288.925)
		(stroke
			(width 0.2)
			(type default)
		)
		(fill no)
		(layer "In4.Cu")
	)
	(gr_circle
		(center 31.369 -15.113)
		(end 32.258 -15.113)
		(stroke
			(width 0.2)
			(type default)
		)
		(fill no)
		(layer "In4.Cu")
	)
	(gr_circle
		(center 32.304228 -267.97)
		(end 33.193228 -267.97)
		(stroke
			(width 0.2)
			(type default)
		)
		(fill no)
		(layer "In4.Cu")
	)
	(gr_circle
		(center 32.304228 -264.668)
		(end 33.193228 -264.668)
		(stroke
			(width 0.2)
			(type default)
		)
		(fill no)
		(layer "In4.Cu")
	)
	(gr_circle
		(center 32.304228 -263.906)
		(end 33.193228 -263.906)
		(stroke
			(width 0.2)
			(type default)
		)
		(fill no)
		(layer "In4.Cu")
	)
	(gr_circle
		(center 32.380428 -80.067912)
		(end 33.269428 -80.067912)
		(stroke
			(width 0.2)
			(type default)
		)
		(fill no)
		(layer "In4.Cu")
	)
	(gr_circle
		(center 32.380428 -79.305912)
		(end 33.269428 -79.305912)
		(stroke
			(width 0.2)
			(type default)
		)
		(fill no)
		(layer "In4.Cu")
	)
	(gr_circle
		(center 32.385 -32.893)
		(end 33.274 -32.893)
		(stroke
			(width 0.2)
			(type default)
		)
		(fill no)
		(layer "In4.Cu")
	)
	(gr_circle
		(center 33.117028 -267.97)
		(end 34.006028 -267.97)
		(stroke
			(width 0.2)
			(type default)
		)
		(fill no)
		(layer "In4.Cu")
	)
	(gr_circle
		(center 33.117028 -264.668)
		(end 34.006028 -264.668)
		(stroke
			(width 0.2)
			(type default)
		)
		(fill no)
		(layer "In4.Cu")
	)
	(gr_circle
		(center 33.117028 -263.906)
		(end 34.006028 -263.906)
		(stroke
			(width 0.2)
			(type default)
		)
		(fill no)
		(layer "In4.Cu")
	)
	(gr_circle
		(center 33.142428 -80.067912)
		(end 34.031428 -80.067912)
		(stroke
			(width 0.2)
			(type default)
		)
		(fill no)
		(layer "In4.Cu")
	)
	(gr_circle
		(center 33.142428 -79.305912)
		(end 34.031428 -79.305912)
		(stroke
			(width 0.2)
			(type default)
		)
		(fill no)
		(layer "In4.Cu")
	)
	(gr_circle
		(center 33.655 -25.146)
		(end 34.544 -25.146)
		(stroke
			(width 0.2)
			(type default)
		)
		(fill no)
		(layer "In4.Cu")
	)
	(gr_circle
		(center 33.879028 -267.97)
		(end 34.768028 -267.97)
		(stroke
			(width 0.2)
			(type default)
		)
		(fill no)
		(layer "In4.Cu")
	)
	(gr_circle
		(center 33.879028 -264.668)
		(end 34.768028 -264.668)
		(stroke
			(width 0.2)
			(type default)
		)
		(fill no)
		(layer "In4.Cu")
	)
	(gr_circle
		(center 33.879028 -263.906)
		(end 34.768028 -263.906)
		(stroke
			(width 0.2)
			(type default)
		)
		(fill no)
		(layer "In4.Cu")
	)
	(gr_circle
		(center 33.904428 -80.067912)
		(end 34.793428 -80.067912)
		(stroke
			(width 0.2)
			(type default)
		)
		(fill no)
		(layer "In4.Cu")
	)
	(gr_circle
		(center 33.904428 -79.305912)
		(end 34.793428 -79.305912)
		(stroke
			(width 0.2)
			(type default)
		)
		(fill no)
		(layer "In4.Cu")
	)
	(gr_circle
		(center 34.0106 -197.104)
		(end 34.8996 -197.104)
		(stroke
			(width 0.2)
			(type default)
		)
		(fill no)
		(layer "In4.Cu")
	)
	(gr_circle
		(center 34.4805 -33.7185)
		(end 35.3695 -33.7185)
		(stroke
			(width 0.2)
			(type default)
		)
		(fill no)
		(layer "In4.Cu")
	)
	(gr_circle
		(center 35.102292 -58.913776)
		(end 35.991292 -58.913776)
		(stroke
			(width 0.2)
			(type default)
		)
		(fill no)
		(layer "In4.Cu")
	)
	(gr_circle
		(center 35.112452 -58.278776)
		(end 36.001452 -58.278776)
		(stroke
			(width 0.2)
			(type default)
		)
		(fill no)
		(layer "In4.Cu")
	)
	(gr_circle
		(center 35.122612 -244.31371)
		(end 36.011612 -244.31371)
		(stroke
			(width 0.2)
			(type default)
		)
		(fill no)
		(layer "In4.Cu")
	)
	(gr_circle
		(center 35.122612 -243.67871)
		(end 36.011612 -243.67871)
		(stroke
			(width 0.2)
			(type default)
		)
		(fill no)
		(layer "In4.Cu")
	)
	(gr_circle
		(center 35.757612 -244.31371)
		(end 36.646612 -244.31371)
		(stroke
			(width 0.2)
			(type default)
		)
		(fill no)
		(layer "In4.Cu")
	)
	(gr_circle
		(center 35.757612 -58.913776)
		(end 36.646612 -58.913776)
		(stroke
			(width 0.2)
			(type default)
		)
		(fill no)
		(layer "In4.Cu")
	)
	(gr_circle
		(center 35.767772 -243.67871)
		(end 36.656772 -243.67871)
		(stroke
			(width 0.2)
			(type default)
		)
		(fill no)
		(layer "In4.Cu")
	)
	(gr_circle
		(center 35.767772 -58.278776)
		(end 36.656772 -58.278776)
		(stroke
			(width 0.2)
			(type default)
		)
		(fill no)
		(layer "In4.Cu")
	)
	(gr_circle
		(center 35.959288 -271.8816)
		(end 36.848288 -271.8816)
		(stroke
			(width 0.2)
			(type default)
		)
		(fill no)
		(layer "In4.Cu")
	)
	(gr_circle
		(center 35.959288 -271.2466)
		(end 36.848288 -271.2466)
		(stroke
			(width 0.2)
			(type default)
		)
		(fill no)
		(layer "In4.Cu")
	)
	(gr_circle
		(center 36.340288 -278.765)
		(end 37.229288 -278.765)
		(stroke
			(width 0.2)
			(type default)
		)
		(fill no)
		(layer "In4.Cu")
	)
	(gr_circle
		(center 36.340288 -278.13)
		(end 37.229288 -278.13)
		(stroke
			(width 0.2)
			(type default)
		)
		(fill no)
		(layer "In4.Cu")
	)
	(gr_circle
		(center 36.340288 -277.495)
		(end 37.229288 -277.495)
		(stroke
			(width 0.2)
			(type default)
		)
		(fill no)
		(layer "In4.Cu")
	)
	(gr_circle
		(center 36.340288 -273.812)
		(end 37.229288 -273.812)
		(stroke
			(width 0.2)
			(type default)
		)
		(fill no)
		(layer "In4.Cu")
	)
	(gr_circle
		(center 36.340288 -273.177)
		(end 37.229288 -273.177)
		(stroke
			(width 0.2)
			(type default)
		)
		(fill no)
		(layer "In4.Cu")
	)
	(gr_circle
		(center 36.340288 -272.542)
		(end 37.229288 -272.542)
		(stroke
			(width 0.2)
			(type default)
		)
		(fill no)
		(layer "In4.Cu")
	)
	(gr_circle
		(center 36.412932 -244.31371)
		(end 37.301932 -244.31371)
		(stroke
			(width 0.2)
			(type default)
		)
		(fill no)
		(layer "In4.Cu")
	)
	(gr_circle
		(center 36.412932 -243.67871)
		(end 37.301932 -243.67871)
		(stroke
			(width 0.2)
			(type default)
		)
		(fill no)
		(layer "In4.Cu")
	)
	(gr_circle
		(center 36.412932 -58.913776)
		(end 37.301932 -58.913776)
		(stroke
			(width 0.2)
			(type default)
		)
		(fill no)
		(layer "In4.Cu")
	)
	(gr_circle
		(center 36.412932 -58.278776)
		(end 37.301932 -58.278776)
		(stroke
			(width 0.2)
			(type default)
		)
		(fill no)
		(layer "In4.Cu")
	)
	(gr_circle
		(center 36.7284 -86.316312)
		(end 37.6174 -86.316312)
		(stroke
			(width 0.2)
			(type default)
		)
		(fill no)
		(layer "In4.Cu")
	)
	(gr_circle
		(center 36.7284 -85.6234)
		(end 37.6174 -85.6234)
		(stroke
			(width 0.2)
			(type default)
		)
		(fill no)
		(layer "In4.Cu")
	)
	(gr_circle
		(center 37.206428 -264.922)
		(end 38.095428 -264.922)
		(stroke
			(width 0.2)
			(type default)
		)
		(fill no)
		(layer "In4.Cu")
	)
	(gr_circle
		(center 37.206428 -80.321912)
		(end 38.095428 -80.321912)
		(stroke
			(width 0.2)
			(type default)
		)
		(fill no)
		(layer "In4.Cu")
	)
	(gr_circle
		(center 37.738304 -37.883846)
		(end 38.627304 -37.883846)
		(stroke
			(width 0.2)
			(type default)
		)
		(fill no)
		(layer "In4.Cu")
	)
	(gr_circle
		(center 37.738304 -37.248846)
		(end 38.627304 -37.248846)
		(stroke
			(width 0.2)
			(type default)
		)
		(fill no)
		(layer "In4.Cu")
	)
	(gr_circle
		(center 37.968428 -264.922)
		(end 38.857428 -264.922)
		(stroke
			(width 0.2)
			(type default)
		)
		(fill no)
		(layer "In4.Cu")
	)
	(gr_circle
		(center 37.968428 -80.321912)
		(end 38.857428 -80.321912)
		(stroke
			(width 0.2)
			(type default)
		)
		(fill no)
		(layer "In4.Cu")
	)
	(gr_circle
		(center 38.014656 -44.308522)
		(end 38.903656 -44.308522)
		(stroke
			(width 0.2)
			(type default)
		)
		(fill no)
		(layer "In4.Cu")
	)
	(gr_circle
		(center 38.014656 -43.546522)
		(end 38.903656 -43.546522)
		(stroke
			(width 0.2)
			(type default)
		)
		(fill no)
		(layer "In4.Cu")
	)
	(gr_circle
		(center 38.014656 -42.784522)
		(end 38.903656 -42.784522)
		(stroke
			(width 0.2)
			(type default)
		)
		(fill no)
		(layer "In4.Cu")
	)
	(gr_circle
		(center 38.014656 -42.022522)
		(end 38.903656 -42.022522)
		(stroke
			(width 0.2)
			(type default)
		)
		(fill no)
		(layer "In4.Cu")
	)
	(gr_circle
		(center 38.065456 -227.61321)
		(end 38.954456 -227.61321)
		(stroke
			(width 0.2)
			(type default)
		)
		(fill no)
		(layer "In4.Cu")
	)
	(gr_circle
		(center 38.065456 -226.85121)
		(end 38.954456 -226.85121)
		(stroke
			(width 0.2)
			(type default)
		)
		(fill no)
		(layer "In4.Cu")
	)
	(gr_circle
		(center 38.065456 -226.08921)
		(end 38.954456 -226.08921)
		(stroke
			(width 0.2)
			(type default)
		)
		(fill no)
		(layer "In4.Cu")
	)
	(gr_circle
		(center 38.0746 -94.0562)
		(end 38.9636 -94.0562)
		(stroke
			(width 0.2)
			(type default)
		)
		(fill no)
		(layer "In4.Cu")
	)
	(gr_circle
		(center 38.0746 -93.352112)
		(end 38.9636 -93.352112)
		(stroke
			(width 0.2)
			(type default)
		)
		(fill no)
		(layer "In4.Cu")
	)
	(gr_circle
		(center 38.0746 -92.5322)
		(end 38.9636 -92.5322)
		(stroke
			(width 0.2)
			(type default)
		)
		(fill no)
		(layer "In4.Cu")
	)
	(gr_circle
		(center 38.0746 -89.3572)
		(end 38.9636 -89.3572)
		(stroke
			(width 0.2)
			(type default)
		)
		(fill no)
		(layer "In4.Cu")
	)
	(gr_circle
		(center 38.0746 -88.653112)
		(end 38.9636 -88.653112)
		(stroke
			(width 0.2)
			(type default)
		)
		(fill no)
		(layer "In4.Cu")
	)
	(gr_circle
		(center 38.0746 -87.9602)
		(end 38.9636 -87.9602)
		(stroke
			(width 0.2)
			(type default)
		)
		(fill no)
		(layer "In4.Cu")
	)
	(gr_circle
		(center 38.222428 -59.713622)
		(end 39.111428 -59.713622)
		(stroke
			(width 0.2)
			(type default)
		)
		(fill no)
		(layer "In4.Cu")
	)
	(gr_circle
		(center 38.222428 -59.078622)
		(end 39.111428 -59.078622)
		(stroke
			(width 0.2)
			(type default)
		)
		(fill no)
		(layer "In4.Cu")
	)
	(gr_circle
		(center 38.374828 -245.113556)
		(end 39.263828 -245.113556)
		(stroke
			(width 0.2)
			(type default)
		)
		(fill no)
		(layer "In4.Cu")
	)
	(gr_circle
		(center 38.374828 -244.478556)
		(end 39.263828 -244.478556)
		(stroke
			(width 0.2)
			(type default)
		)
		(fill no)
		(layer "In4.Cu")
	)
	(gr_circle
		(center 38.500304 -37.883846)
		(end 39.389304 -37.883846)
		(stroke
			(width 0.2)
			(type default)
		)
		(fill no)
		(layer "In4.Cu")
	)
	(gr_circle
		(center 38.500304 -37.248846)
		(end 39.389304 -37.248846)
		(stroke
			(width 0.2)
			(type default)
		)
		(fill no)
		(layer "In4.Cu")
	)
	(gr_circle
		(center 38.700456 -227.61321)
		(end 39.589456 -227.61321)
		(stroke
			(width 0.2)
			(type default)
		)
		(fill no)
		(layer "In4.Cu")
	)
	(gr_circle
		(center 38.700456 -226.85121)
		(end 39.589456 -226.85121)
		(stroke
			(width 0.2)
			(type default)
		)
		(fill no)
		(layer "In4.Cu")
	)
	(gr_circle
		(center 38.700456 -226.08921)
		(end 39.589456 -226.08921)
		(stroke
			(width 0.2)
			(type default)
		)
		(fill no)
		(layer "In4.Cu")
	)
	(gr_circle
		(center 38.857428 -59.713622)
		(end 39.746428 -59.713622)
		(stroke
			(width 0.2)
			(type default)
		)
		(fill no)
		(layer "In4.Cu")
	)
	(gr_circle
		(center 38.867588 -59.078622)
		(end 39.756588 -59.078622)
		(stroke
			(width 0.2)
			(type default)
		)
		(fill no)
		(layer "In4.Cu")
	)
	(gr_circle
		(center 39.009828 -245.113556)
		(end 39.898828 -245.113556)
		(stroke
			(width 0.2)
			(type default)
		)
		(fill no)
		(layer "In4.Cu")
	)
	(gr_circle
		(center 39.019988 -244.478556)
		(end 39.908988 -244.478556)
		(stroke
			(width 0.2)
			(type default)
		)
		(fill no)
		(layer "In4.Cu")
	)
	(gr_circle
		(center 39.262304 -37.883846)
		(end 40.151304 -37.883846)
		(stroke
			(width 0.2)
			(type default)
		)
		(fill no)
		(layer "In4.Cu")
	)
	(gr_circle
		(center 39.262304 -37.248846)
		(end 40.151304 -37.248846)
		(stroke
			(width 0.2)
			(type default)
		)
		(fill no)
		(layer "In4.Cu")
	)
	(gr_circle
		(center 39.512748 -59.713622)
		(end 40.401748 -59.713622)
		(stroke
			(width 0.2)
			(type default)
		)
		(fill no)
		(layer "In4.Cu")
	)
	(gr_circle
		(center 39.512748 -59.078622)
		(end 40.401748 -59.078622)
		(stroke
			(width 0.2)
			(type default)
		)
		(fill no)
		(layer "In4.Cu")
	)
	(gr_circle
		(center 39.665148 -245.113556)
		(end 40.554148 -245.113556)
		(stroke
			(width 0.2)
			(type default)
		)
		(fill no)
		(layer "In4.Cu")
	)
	(gr_circle
		(center 39.665148 -244.478556)
		(end 40.554148 -244.478556)
		(stroke
			(width 0.2)
			(type default)
		)
		(fill no)
		(layer "In4.Cu")
	)
	(gr_circle
		(center 39.821612 -264.32129)
		(end 40.710612 -264.32129)
		(stroke
			(width 0.2)
			(type default)
		)
		(fill no)
		(layer "In4.Cu")
	)
	(gr_circle
		(center 39.821612 -263.68629)
		(end 40.710612 -263.68629)
		(stroke
			(width 0.2)
			(type default)
		)
		(fill no)
		(layer "In4.Cu")
	)
	(gr_circle
		(center 39.821612 -79.721202)
		(end 40.710612 -79.721202)
		(stroke
			(width 0.2)
			(type default)
		)
		(fill no)
		(layer "In4.Cu")
	)
	(gr_circle
		(center 39.821612 -79.086202)
		(end 40.710612 -79.086202)
		(stroke
			(width 0.2)
			(type default)
		)
		(fill no)
		(layer "In4.Cu")
	)
	(gr_circle
		(center 40.349932 -84.385912)
		(end 41.238932 -84.385912)
		(stroke
			(width 0.2)
			(type default)
		)
		(fill no)
		(layer "In4.Cu")
	)
	(gr_circle
		(center 40.349932 -83.623912)
		(end 41.238932 -83.623912)
		(stroke
			(width 0.2)
			(type default)
		)
		(fill no)
		(layer "In4.Cu")
	)
	(gr_circle
		(center 40.466772 -264.32129)
		(end 41.355772 -264.32129)
		(stroke
			(width 0.2)
			(type default)
		)
		(fill no)
		(layer "In4.Cu")
	)
	(gr_circle
		(center 40.466772 -79.721202)
		(end 41.355772 -79.721202)
		(stroke
			(width 0.2)
			(type default)
		)
		(fill no)
		(layer "In4.Cu")
	)
	(gr_circle
		(center 40.476932 -263.68629)
		(end 41.365932 -263.68629)
		(stroke
			(width 0.2)
			(type default)
		)
		(fill no)
		(layer "In4.Cu")
	)
	(gr_circle
		(center 40.476932 -79.086202)
		(end 41.365932 -79.086202)
		(stroke
			(width 0.2)
			(type default)
		)
		(fill no)
		(layer "In4.Cu")
	)
	(gr_circle
		(center 41.111932 -264.32129)
		(end 42.000932 -264.32129)
		(stroke
			(width 0.2)
			(type default)
		)
		(fill no)
		(layer "In4.Cu")
	)
	(gr_circle
		(center 41.111932 -263.68629)
		(end 42.000932 -263.68629)
		(stroke
			(width 0.2)
			(type default)
		)
		(fill no)
		(layer "In4.Cu")
	)
	(gr_circle
		(center 41.111932 -79.721202)
		(end 42.000932 -79.721202)
		(stroke
			(width 0.2)
			(type default)
		)
		(fill no)
		(layer "In4.Cu")
	)
	(gr_circle
		(center 41.111932 -79.086202)
		(end 42.000932 -79.086202)
		(stroke
			(width 0.2)
			(type default)
		)
		(fill no)
		(layer "In4.Cu")
	)
	(gr_circle
		(center 41.370758 -237.363)
		(end 42.259758 -237.363)
		(stroke
			(width 0.2)
			(type default)
		)
		(fill no)
		(layer "In4.Cu")
	)
	(gr_circle
		(center 41.370758 -236.601)
		(end 42.259758 -236.601)
		(stroke
			(width 0.2)
			(type default)
		)
		(fill no)
		(layer "In4.Cu")
	)
	(gr_circle
		(center 41.370758 -234.823)
		(end 42.259758 -234.823)
		(stroke
			(width 0.2)
			(type default)
		)
		(fill no)
		(layer "In4.Cu")
	)
	(gr_circle
		(center 41.370758 -234.061)
		(end 42.259758 -234.061)
		(stroke
			(width 0.2)
			(type default)
		)
		(fill no)
		(layer "In4.Cu")
	)
	(gr_circle
		(center 41.370758 -232.029)
		(end 42.259758 -232.029)
		(stroke
			(width 0.2)
			(type default)
		)
		(fill no)
		(layer "In4.Cu")
	)
	(gr_circle
		(center 41.370758 -231.267)
		(end 42.259758 -231.267)
		(stroke
			(width 0.2)
			(type default)
		)
		(fill no)
		(layer "In4.Cu")
	)
	(gr_circle
		(center 41.407588 -58.570622)
		(end 42.296588 -58.570622)
		(stroke
			(width 0.2)
			(type default)
		)
		(fill no)
		(layer "In4.Cu")
	)
	(gr_circle
		(center 41.873932 -244.2972)
		(end 42.762932 -244.2972)
		(stroke
			(width 0.2)
			(type default)
		)
		(fill no)
		(layer "In4.Cu")
	)
	(gr_circle
		(center 41.875456 -52.944522)
		(end 42.764456 -52.944522)
		(stroke
			(width 0.2)
			(type default)
		)
		(fill no)
		(layer "In4.Cu")
	)
	(gr_circle
		(center 41.875456 -52.182522)
		(end 42.764456 -52.182522)
		(stroke
			(width 0.2)
			(type default)
		)
		(fill no)
		(layer "In4.Cu")
	)
	(gr_circle
		(center 41.900856 -50.683922)
		(end 42.789856 -50.683922)
		(stroke
			(width 0.2)
			(type default)
		)
		(fill no)
		(layer "In4.Cu")
	)
	(gr_circle
		(center 41.900856 -49.921922)
		(end 42.789856 -49.921922)
		(stroke
			(width 0.2)
			(type default)
		)
		(fill no)
		(layer "In4.Cu")
	)
	(gr_circle
		(center 41.951656 -48.042322)
		(end 42.840656 -48.042322)
		(stroke
			(width 0.2)
			(type default)
		)
		(fill no)
		(layer "In4.Cu")
	)
	(gr_circle
		(center 41.951656 -47.280322)
		(end 42.840656 -47.280322)
		(stroke
			(width 0.2)
			(type default)
		)
		(fill no)
		(layer "In4.Cu")
	)
	(gr_circle
		(center 42.037 -312.3946)
		(end 42.926 -312.3946)
		(stroke
			(width 0.2)
			(type default)
		)
		(fill no)
		(layer "In4.Cu")
	)
	(gr_circle
		(center 42.052748 -58.570622)
		(end 42.941748 -58.570622)
		(stroke
			(width 0.2)
			(type default)
		)
		(fill no)
		(layer "In4.Cu")
	)
	(gr_circle
		(center 42.635932 -244.2972)
		(end 43.524932 -244.2972)
		(stroke
			(width 0.2)
			(type default)
		)
		(fill no)
		(layer "In4.Cu")
	)
	(gr_circle
		(center 42.716958 -239.5474)
		(end 43.605958 -239.5474)
		(stroke
			(width 0.2)
			(type default)
		)
		(fill no)
		(layer "In4.Cu")
	)
	(gr_circle
		(center 42.716958 -238.7854)
		(end 43.605958 -238.7854)
		(stroke
			(width 0.2)
			(type default)
		)
		(fill no)
		(layer "In4.Cu")
	)
	(gr_circle
		(center 42.815256 -55.255922)
		(end 43.704256 -55.255922)
		(stroke
			(width 0.2)
			(type default)
		)
		(fill no)
		(layer "In4.Cu")
	)
	(gr_circle
		(center 42.815256 -54.493922)
		(end 43.704256 -54.493922)
		(stroke
			(width 0.2)
			(type default)
		)
		(fill no)
		(layer "In4.Cu")
	)
	(gr_circle
		(center 42.921428 -265.121136)
		(end 43.810428 -265.121136)
		(stroke
			(width 0.2)
			(type default)
		)
		(fill no)
		(layer "In4.Cu")
	)
	(gr_circle
		(center 42.921428 -264.486136)
		(end 43.810428 -264.486136)
		(stroke
			(width 0.2)
			(type default)
		)
		(fill no)
		(layer "In4.Cu")
	)
	(gr_circle
		(center 42.921428 -80.521048)
		(end 43.810428 -80.521048)
		(stroke
			(width 0.2)
			(type default)
		)
		(fill no)
		(layer "In4.Cu")
	)
	(gr_circle
		(center 42.921428 -79.886048)
		(end 43.810428 -79.886048)
		(stroke
			(width 0.2)
			(type default)
		)
		(fill no)
		(layer "In4.Cu")
	)
	(gr_circle
		(center 42.999914 -295.310052)
		(end 44.320714 -295.310052)
		(stroke
			(width 0.2)
			(type default)
		)
		(fill no)
		(layer "In4.Cu")
	)
	(gr_circle
		(center 42.999914 -203.010008)
		(end 44.320714 -203.010008)
		(stroke
			(width 0.2)
			(type default)
		)
		(fill no)
		(layer "In4.Cu")
	)
	(gr_circle
		(center 42.999914 -110.709964)
		(end 44.320714 -110.709964)
		(stroke
			(width 0.2)
			(type default)
		)
		(fill no)
		(layer "In4.Cu")
	)
	(gr_circle
		(center 42.999914 -18.40992)
		(end 44.320714 -18.40992)
		(stroke
			(width 0.2)
			(type default)
		)
		(fill no)
		(layer "In4.Cu")
	)
	(gr_circle
		(center 43.566588 -265.121136)
		(end 44.455588 -265.121136)
		(stroke
			(width 0.2)
			(type default)
		)
		(fill no)
		(layer "In4.Cu")
	)
	(gr_circle
		(center 43.566588 -80.521048)
		(end 44.455588 -80.521048)
		(stroke
			(width 0.2)
			(type default)
		)
		(fill no)
		(layer "In4.Cu")
	)
	(gr_circle
		(center 43.576748 -264.486136)
		(end 44.465748 -264.486136)
		(stroke
			(width 0.2)
			(type default)
		)
		(fill no)
		(layer "In4.Cu")
	)
	(gr_circle
		(center 43.576748 -79.886048)
		(end 44.465748 -79.886048)
		(stroke
			(width 0.2)
			(type default)
		)
		(fill no)
		(layer "In4.Cu")
	)
	(gr_circle
		(center 44.211748 -265.121136)
		(end 45.100748 -265.121136)
		(stroke
			(width 0.2)
			(type default)
		)
		(fill no)
		(layer "In4.Cu")
	)
	(gr_circle
		(center 44.211748 -264.486136)
		(end 45.100748 -264.486136)
		(stroke
			(width 0.2)
			(type default)
		)
		(fill no)
		(layer "In4.Cu")
	)
	(gr_circle
		(center 44.211748 -80.521048)
		(end 45.100748 -80.521048)
		(stroke
			(width 0.2)
			(type default)
		)
		(fill no)
		(layer "In4.Cu")
	)
	(gr_circle
		(center 44.211748 -79.886048)
		(end 45.100748 -79.886048)
		(stroke
			(width 0.2)
			(type default)
		)
		(fill no)
		(layer "In4.Cu")
	)
	(gr_circle
		(center 44.921932 -92.02166)
		(end 45.810932 -92.02166)
		(stroke
			(width 0.2)
			(type default)
		)
		(fill no)
		(layer "In4.Cu")
	)
	(gr_circle
		(center 44.921932 -91.38666)
		(end 45.810932 -91.38666)
		(stroke
			(width 0.2)
			(type default)
		)
		(fill no)
		(layer "In4.Cu")
	)
	(gr_circle
		(center 44.99991 -293.310056)
		(end 46.32071 -293.310056)
		(stroke
			(width 0.2)
			(type default)
		)
		(fill no)
		(layer "In4.Cu")
	)
	(gr_circle
		(center 44.99991 -201.010012)
		(end 46.32071 -201.010012)
		(stroke
			(width 0.2)
			(type default)
		)
		(fill no)
		(layer "In4.Cu")
	)
	(gr_circle
		(center 44.99991 -108.709968)
		(end 46.32071 -108.709968)
		(stroke
			(width 0.2)
			(type default)
		)
		(fill no)
		(layer "In4.Cu")
	)
	(gr_circle
		(center 44.99991 -16.409924)
		(end 46.32071 -16.409924)
		(stroke
			(width 0.2)
			(type default)
		)
		(fill no)
		(layer "In4.Cu")
	)
	(gr_circle
		(center 45.556932 -58.503312)
		(end 46.445932 -58.503312)
		(stroke
			(width 0.2)
			(type default)
		)
		(fill no)
		(layer "In4.Cu")
	)
	(gr_circle
		(center 45.556932 -57.741312)
		(end 46.445932 -57.741312)
		(stroke
			(width 0.2)
			(type default)
		)
		(fill no)
		(layer "In4.Cu")
	)
	(gr_circle
		(center 45.633132 -61.856112)
		(end 46.522132 -61.856112)
		(stroke
			(width 0.2)
			(type default)
		)
		(fill no)
		(layer "In4.Cu")
	)
	(gr_circle
		(center 45.683932 -92.02166)
		(end 46.572932 -92.02166)
		(stroke
			(width 0.2)
			(type default)
		)
		(fill no)
		(layer "In4.Cu")
	)
	(gr_circle
		(center 45.683932 -91.38666)
		(end 46.572932 -91.38666)
		(stroke
			(width 0.2)
			(type default)
		)
		(fill no)
		(layer "In4.Cu")
	)
	(gr_circle
		(center 45.836332 -281.092148)
		(end 46.725332 -281.092148)
		(stroke
			(width 0.2)
			(type default)
		)
		(fill no)
		(layer "In4.Cu")
	)
	(gr_circle
		(center 45.836332 -280.330148)
		(end 46.725332 -280.330148)
		(stroke
			(width 0.2)
			(type default)
		)
		(fill no)
		(layer "In4.Cu")
	)
	(gr_circle
		(center 45.887132 -246.126)
		(end 46.776132 -246.126)
		(stroke
			(width 0.2)
			(type default)
		)
		(fill no)
		(layer "In4.Cu")
	)
	(gr_circle
		(center 45.887132 -242.8494)
		(end 46.776132 -242.8494)
		(stroke
			(width 0.2)
			(type default)
		)
		(fill no)
		(layer "In4.Cu")
	)
	(gr_circle
		(center 45.887132 -242.0366)
		(end 46.776132 -242.0366)
		(stroke
			(width 0.2)
			(type default)
		)
		(fill no)
		(layer "In4.Cu")
	)
	(gr_circle
		(center 46.318932 -58.503312)
		(end 47.207932 -58.503312)
		(stroke
			(width 0.2)
			(type default)
		)
		(fill no)
		(layer "In4.Cu")
	)
	(gr_circle
		(center 46.318932 -57.741312)
		(end 47.207932 -57.741312)
		(stroke
			(width 0.2)
			(type default)
		)
		(fill no)
		(layer "In4.Cu")
	)
	(gr_circle
		(center 46.395132 -61.856112)
		(end 47.284132 -61.856112)
		(stroke
			(width 0.2)
			(type default)
		)
		(fill no)
		(layer "In4.Cu")
	)
	(gr_circle
		(center 46.445932 -92.02166)
		(end 47.334932 -92.02166)
		(stroke
			(width 0.2)
			(type default)
		)
		(fill no)
		(layer "In4.Cu")
	)
	(gr_circle
		(center 46.445932 -91.38666)
		(end 47.334932 -91.38666)
		(stroke
			(width 0.2)
			(type default)
		)
		(fill no)
		(layer "In4.Cu")
	)
	(gr_circle
		(center 46.598332 -281.092148)
		(end 47.487332 -281.092148)
		(stroke
			(width 0.2)
			(type default)
		)
		(fill no)
		(layer "In4.Cu")
	)
	(gr_circle
		(center 46.598332 -280.330148)
		(end 47.487332 -280.330148)
		(stroke
			(width 0.2)
			(type default)
		)
		(fill no)
		(layer "In4.Cu")
	)
	(gr_circle
		(center 46.674532 -246.1514)
		(end 47.563532 -246.1514)
		(stroke
			(width 0.2)
			(type default)
		)
		(fill no)
		(layer "In4.Cu")
	)
	(gr_circle
		(center 46.674532 -242.8748)
		(end 47.563532 -242.8748)
		(stroke
			(width 0.2)
			(type default)
		)
		(fill no)
		(layer "In4.Cu")
	)
	(gr_circle
		(center 46.674532 -242.062)
		(end 47.563532 -242.062)
		(stroke
			(width 0.2)
			(type default)
		)
		(fill no)
		(layer "In4.Cu")
	)
	(gr_circle
		(center 47.080932 -58.503312)
		(end 47.969932 -58.503312)
		(stroke
			(width 0.2)
			(type default)
		)
		(fill no)
		(layer "In4.Cu")
	)
	(gr_circle
		(center 47.080932 -57.741312)
		(end 47.969932 -57.741312)
		(stroke
			(width 0.2)
			(type default)
		)
		(fill no)
		(layer "In4.Cu")
	)
	(gr_circle
		(center 47.157132 -61.856112)
		(end 48.046132 -61.856112)
		(stroke
			(width 0.2)
			(type default)
		)
		(fill no)
		(layer "In4.Cu")
	)
	(gr_circle
		(center 47.207932 -92.02166)
		(end 48.096932 -92.02166)
		(stroke
			(width 0.2)
			(type default)
		)
		(fill no)
		(layer "In4.Cu")
	)
	(gr_circle
		(center 47.207932 -91.38666)
		(end 48.096932 -91.38666)
		(stroke
			(width 0.2)
			(type default)
		)
		(fill no)
		(layer "In4.Cu")
	)
	(gr_circle
		(center 47.360332 -281.092148)
		(end 48.249332 -281.092148)
		(stroke
			(width 0.2)
			(type default)
		)
		(fill no)
		(layer "In4.Cu")
	)
	(gr_circle
		(center 47.360332 -280.330148)
		(end 48.249332 -280.330148)
		(stroke
			(width 0.2)
			(type default)
		)
		(fill no)
		(layer "In4.Cu")
	)
	(gr_circle
		(center 47.411132 -246.126)
		(end 48.300132 -246.126)
		(stroke
			(width 0.2)
			(type default)
		)
		(fill no)
		(layer "In4.Cu")
	)
	(gr_circle
		(center 47.411132 -242.8494)
		(end 48.300132 -242.8494)
		(stroke
			(width 0.2)
			(type default)
		)
		(fill no)
		(layer "In4.Cu")
	)
	(gr_circle
		(center 47.411132 -242.0366)
		(end 48.300132 -242.0366)
		(stroke
			(width 0.2)
			(type default)
		)
		(fill no)
		(layer "In4.Cu")
	)
	(gr_line
		(start 0 -333.000096)
		(end 0 -3.999992)
		(stroke
			(width 0.05)
			(type default)
		)
		(layer "Edge.Cuts")
	)
	(gr_arc
		(start 0 -333.000096)
		(mid 1.171571 -335.828517)
		(end 3.999992 -337.000088)
		(stroke
			(width 0.05)
			(type default)
		)
		(layer "Edge.Cuts")
	)
	(gr_arc
		(start 3.999992 0)
		(mid 1.171571 -1.171571)
		(end 0 -3.999992)
		(stroke
			(width 0.05)
			(type default)
		)
		(layer "Edge.Cuts")
	)
	(gr_line
		(start 3.999992 0)
		(end 14.960092 0)
		(stroke
			(width 0.05)
			(type default)
		)
		(layer "Edge.Cuts")
	)
	(gr_line
		(start 14.960092 0)
		(end 16.459962 -1.500124)
		(stroke
			(width 0.05)
			(type default)
		)
		(layer "Edge.Cuts")
	)
	(gr_arc
		(start 16.459962 -10.999978)
		(mid 17.660112 -12.200128)
		(end 18.860008 -10.999978)
		(stroke
			(width 0.05)
			(type default)
		)
		(layer "Edge.Cuts")
	)
	(gr_line
		(start 16.459962 -1.500124)
		(end 16.459962 -10.999978)
		(stroke
			(width 0.05)
			(type default)
		)
		(layer "Edge.Cuts")
	)
	(gr_line
		(start 18.860008 -10.999978)
		(end 18.860008 -1.849882)
		(stroke
			(width 0.05)
			(type default)
		)
		(layer "Edge.Cuts")
	)
	(gr_line
		(start 18.860008 -1.849882)
		(end 20.359878 -0.350012)
		(stroke
			(width 0.05)
			(type default)
		)
		(layer "Edge.Cuts")
	)
	(gr_line
		(start 20.359878 -0.350012)
		(end 25.269952 -0.350012)
		(stroke
			(width 0.05)
			(type default)
		)
		(layer "Edge.Cuts")
	)
	(gr_line
		(start 25.269952 -0.350012)
		(end 26.770076 -1.849882)
		(stroke
			(width 0.05)
			(type default)
		)
		(layer "Edge.Cuts")
	)
	(gr_arc
		(start 26.770076 -10.999978)
		(mid 27.120088 -11.34999)
		(end 27.4701 -10.999978)
		(stroke
			(width 0.05)
			(type default)
		)
		(layer "Edge.Cuts")
	)
	(gr_line
		(start 26.770076 -1.849882)
		(end 26.770076 -10.999978)
		(stroke
			(width 0.05)
			(type default)
		)
		(layer "Edge.Cuts")
	)
	(gr_line
		(start 27.4701 -10.999978)
		(end 27.4701 -1.849882)
		(stroke
			(width 0.05)
			(type default)
		)
		(layer "Edge.Cuts")
	)
	(gr_line
		(start 27.4701 -1.849882)
		(end 28.96997 -0.350012)
		(stroke
			(width 0.05)
			(type default)
		)
		(layer "Edge.Cuts")
	)
	(gr_line
		(start 28.96997 -0.350012)
		(end 31.340044 -0.350012)
		(stroke
			(width 0.05)
			(type default)
		)
		(layer "Edge.Cuts")
	)
	(gr_line
		(start 31.340044 -0.350012)
		(end 32.839914 -1.849882)
		(stroke
			(width 0.05)
			(type default)
		)
		(layer "Edge.Cuts")
	)
	(gr_arc
		(start 32.839914 -10.999978)
		(mid 34.040064 -12.200128)
		(end 35.23996 -10.999978)
		(stroke
			(width 0.05)
			(type default)
		)
		(layer "Edge.Cuts")
	)
	(gr_line
		(start 32.839914 -1.849882)
		(end 32.839914 -10.999978)
		(stroke
			(width 0.05)
			(type default)
		)
		(layer "Edge.Cuts")
	)
	(gr_line
		(start 35.23996 -10.999978)
		(end 35.23996 -1.500124)
		(stroke
			(width 0.05)
			(type default)
		)
		(layer "Edge.Cuts")
	)
	(gr_line
		(start 35.23996 -1.500124)
		(end 36.740084 0)
		(stroke
			(width 0.05)
			(type default)
		)
		(layer "Edge.Cuts")
	)
	(gr_line
		(start 36.740084 0)
		(end 47.69993 0)
		(stroke
			(width 0.05)
			(type default)
		)
		(layer "Edge.Cuts")
	)
	(gr_line
		(start 47.69993 -337.000088)
		(end 3.999992 -337.000088)
		(stroke
			(width 0.05)
			(type default)
		)
		(layer "Edge.Cuts")
	)
	(gr_arc
		(start 47.69993 -337.000088)
		(mid 50.528331 -335.828507)
		(end 51.699922 -333.000096)
		(stroke
			(width 0.05)
			(type default)
		)
		(layer "Edge.Cuts")
	)
	(gr_arc
		(start 51.699922 -3.999992)
		(mid 50.52835 -1.171565)
		(end 47.69993 0)
		(stroke
			(width 0.05)
			(type default)
		)
		(layer "Edge.Cuts")
	)
	(gr_line
		(start 51.699922 -3.999992)
		(end 51.699922 -333.000096)
		(stroke
			(width 0.05)
			(type default)
		)
		(layer "Edge.Cuts")
	)
	(segment
		(start 6.36905 -30.226)
		(end 6.36905 -31.496)
		(width 0.4572)
		(layer "F.Cu")
		(net "P12V_LED_R1_FAN4")
	)
	(segment
		(start 3.683 -27.53995)
		(end 3.683 -19.426936)
		(width 0.4572)
		(layer "F.Cu")
		(net "P12V_LED_R1_FAN4")
	)
	(segment
		(start 3.683 -19.426936)
		(end 6.700012 -16.409924)
		(width 0.4572)
		(layer "F.Cu")
		(net "P12V_LED_R1_FAN4")
	)
	(segment
		(start 6.36905 -30.226)
		(end 3.683 -27.53995)
		(width 0.4572)
		(layer "F.Cu")
		(net "P12V_LED_R1_FAN4")
	)
	(via
		(at 6.36905 -30.226)
		(size 0.762)
		(drill 0.381)
		(layers "F.Cu" "B.Cu")
		(net "P12V_LED_R1_FAN4")
	)
	(segment
		(start 3.8608 -111.54918)
		(end 3.8608 -119.5832)
		(width 0.4572)
		(layer "F.Cu")
		(net "P12V_LED_R1_FAN5")
	)
	(segment
		(start 7.00405 -123.698)
		(end 7.00405 -122.72645)
		(width 0.4572)
		(layer "F.Cu")
		(net "P12V_LED_R1_FAN5")
	)
	(segment
		(start 6.700012 -108.709968)
		(end 3.8608 -111.54918)
		(width 0.4572)
		(layer "F.Cu")
		(net "P12V_LED_R1_FAN5")
	)
	(segment
		(start 3.8608 -119.5832)
		(end 6.31952 -122.04192)
		(width 0.4572)
		(layer "F.Cu")
		(net "P12V_LED_R1_FAN5")
	)
	(segment
		(start 7.00405 -122.72645)
		(end 6.31952 -122.04192)
		(width 0.4572)
		(layer "F.Cu")
		(net "P12V_LED_R1_FAN5")
	)
	(via
		(at 6.31952 -122.04192)
		(size 0.762)
		(drill 0.381)
		(layers "F.Cu" "B.Cu")
		(net "P12V_LED_R1_FAN5")
	)
	(segment
		(start 10.09015 -203.47305)
		(end 12.192 -203.47305)
		(width 0.4572)
		(layer "F.Cu")
		(net "P12V_LED_R1_FAN6")
	)
	(segment
		(start 13.589 -203.47305)
		(end 12.192 -203.47305)
		(width 0.4572)
		(layer "F.Cu")
		(net "P12V_LED_R1_FAN6")
	)
	(segment
		(start 10.09015 -203.46035)
		(end 10.09015 -203.47305)
		(width 0.4572)
		(layer "F.Cu")
		(net "P12V_LED_R1_FAN6")
	)
	(segment
		(start 9.8806 -203.2508)
		(end 10.09015 -203.46035)
		(width 0.4572)
		(layer "F.Cu")
		(net "P12V_LED_R1_FAN6")
	)
	(via
		(at 12.192 -203.47305)
		(size 0.762)
		(drill 0.381)
		(layers "F.Cu" "B.Cu")
		(net "P12V_LED_R1_FAN6")
	)
	(via
		(at 9.8806 -203.2508)
		(size 0.508)
		(drill 0.254)
		(layers "F.Cu" "B.Cu")
		(net "P12V_LED_R1_FAN6")
	)
	(segment
		(start 7.703312 -202.013312)
		(end 6.700012 -201.010012)
		(width 0.4572)
		(layer "In2.Cu")
		(net "P12V_LED_R1_FAN6")
	)
	(segment
		(start 9.8806 -203.2508)
		(end 9.8806 -202.5904)
		(width 0.4572)
		(layer "In2.Cu")
		(net "P12V_LED_R1_FAN6")
	)
	(segment
		(start 9.8806 -202.5904)
		(end 9.303512 -202.013312)
		(width 0.4572)
		(layer "In2.Cu")
		(net "P12V_LED_R1_FAN6")
	)
	(segment
		(start 9.303512 -202.013312)
		(end 7.703312 -202.013312)
		(width 0.3556)
		(layer "In2.Cu")
		(net "P12V_LED_R1_FAN6")
	)
	(segment
		(start 13.95095 -294.64)
		(end 12.2428 -294.64)
		(width 0.4572)
		(layer "F.Cu")
		(net "P12V_LED_R1_FAN7")
	)
	(segment
		(start 10.338054 -294.64)
		(end 10.007854 -294.3098)
		(width 0.4572)
		(layer "F.Cu")
		(net "P12V_LED_R1_FAN7")
	)
	(segment
		(start 10.007854 -294.3098)
		(end 9.4742 -294.3098)
		(width 0.4572)
		(layer "F.Cu")
		(net "P12V_LED_R1_FAN7")
	)
	(segment
		(start 12.2428 -294.64)
		(end 10.338054 -294.64)
		(width 0.4572)
		(layer "F.Cu")
		(net "P12V_LED_R1_FAN7")
	)
	(segment
		(start 9.4742 -294.3098)
		(end 7.699756 -294.3098)
		(width 0.2794)
		(layer "F.Cu")
		(net "P12V_LED_R1_FAN7")
	)
	(segment
		(start 7.699756 -294.3098)
		(end 6.700012 -293.310056)
		(width 0.2794)
		(layer "F.Cu")
		(net "P12V_LED_R1_FAN7")
	)
	(via
		(at 12.2428 -294.64)
		(size 0.762)
		(drill 0.381)
		(layers "F.Cu" "B.Cu")
		(net "P12V_LED_R1_FAN7")
	)
	(segment
		(start 14.44625 -294.3352)
		(end 14.44625 -294.27551)
		(width 0.2794)
		(layer "F.Cu")
		(net "P12V_LED_R_FAN7")
	)
	(segment
		(start 14.44625 -294.27551)
		(end 13.95095 -293.78021)
		(width 0.2794)
		(layer "F.Cu")
		(net "P12V_LED_R_FAN7")
	)
	(segment
		(start 13.95095 -293.78021)
		(end 13.95095 -293.624)
		(width 0.2794)
		(layer "F.Cu")
		(net "P12V_LED_R_FAN7")
	)
	(segment
		(start 14.75105 -294.64)
		(end 14.44625 -294.3352)
		(width 0.2794)
		(layer "F.Cu")
		(net "P12V_LED_R_FAN7")
	)
	(segment
		(start 14.449044 -203.47305)
		(end 13.648944 -202.67295)
		(width 0.2794)
		(layer "F.Cu")
		(net "P12V_LED_R_FAN6")
	)
	(segment
		(start 14.605 -203.47305)
		(end 14.449044 -203.47305)
		(width 0.2794)
		(layer "F.Cu")
		(net "P12V_LED_R_FAN6")
	)
	(segment
		(start 13.648944 -202.67295)
		(end 13.589 -202.67295)
		(width 0.2794)
		(layer "F.Cu")
		(net "P12V_LED_R_FAN6")
	)
	(segment
		(start 5.0038 -123.698)
		(end 3.82905 -123.698)
		(width 0.2794)
		(layer "F.Cu")
		(net "P12V_LED_R_FAN5")
	)
	(segment
		(start 5.0038 -123.698)
		(end 6.20395 -123.698)
		(width 0.2794)
		(layer "F.Cu")
		(net "P12V_LED_R_FAN5")
	)
	(via
		(at 5.0038 -123.698)
		(size 0.762)
		(drill 0.381)
		(layers "F.Cu" "B.Cu")
		(net "P12V_LED_R_FAN5")
	)
	(segment
		(start 5.56895 -31.496)
		(end 4.3688 -31.496)
		(width 0.2794)
		(layer "F.Cu")
		(net "P12V_LED_R_FAN4")
	)
	(segment
		(start 4.3688 -31.496)
		(end 3.19405 -31.496)
		(width 0.2794)
		(layer "F.Cu")
		(net "P12V_LED_R_FAN4")
	)
	(via
		(at 4.3688 -31.496)
		(size 0.762)
		(drill 0.381)
		(layers "F.Cu" "B.Cu")
		(net "P12V_LED_R_FAN4")
	)
	(segment
		(start 45.19295 -30.65145)
		(end 45.19295 -31.623)
		(width 0.4572)
		(layer "F.Cu")
		(net "P12V_LED_R1_FAN3")
	)
	(segment
		(start 44.99991 -22.409912)
		(end 47.1678 -24.577802)
		(width 0.4572)
		(layer "F.Cu")
		(net "P12V_LED_R1_FAN3")
	)
	(segment
		(start 47.1678 -24.577802)
		(end 47.1678 -28.6766)
		(width 0.4572)
		(layer "F.Cu")
		(net "P12V_LED_R1_FAN3")
	)
	(segment
		(start 47.1678 -28.6766)
		(end 45.19295 -30.65145)
		(width 0.4572)
		(layer "F.Cu")
		(net "P12V_LED_R1_FAN3")
	)
	(via
		(at 47.1678 -28.6766)
		(size 0.762)
		(drill 0.381)
		(layers "F.Cu" "B.Cu")
		(net "P12V_LED_R1_FAN3")
	)
	(segment
		(start 48.36795 -31.623)
		(end 47.1678 -31.623)
		(width 0.2794)
		(layer "F.Cu")
		(net "P12V_LED_R_FAN3")
	)
	(segment
		(start 47.1678 -31.623)
		(end 45.99305 -31.623)
		(width 0.2794)
		(layer "F.Cu")
		(net "P12V_LED_R_FAN3")
	)
	(via
		(at 47.1678 -31.623)
		(size 0.762)
		(drill 0.381)
		(layers "F.Cu" "B.Cu")
		(net "P12V_LED_R_FAN3")
	)
	(segment
		(start 47.1678 -120.9548)
		(end 45.085 -123.0376)
		(width 0.4572)
		(layer "F.Cu")
		(net "P12V_LED_R1_FAN2")
	)
	(segment
		(start 44.99991 -114.709956)
		(end 47.1678 -116.877846)
		(width 0.4572)
		(layer "F.Cu")
		(net "P12V_LED_R1_FAN2")
	)
	(segment
		(start 47.1678 -116.877846)
		(end 47.1678 -120.9548)
		(width 0.4572)
		(layer "F.Cu")
		(net "P12V_LED_R1_FAN2")
	)
	(segment
		(start 45.085 -123.0376)
		(end 45.085 -123.67895)
		(width 0.4572)
		(layer "F.Cu")
		(net "P12V_LED_R1_FAN2")
	)
	(via
		(at 47.1678 -120.9548)
		(size 0.762)
		(drill 0.381)
		(layers "F.Cu" "B.Cu")
		(net "P12V_LED_R1_FAN2")
	)
	(segment
		(start 45.085 -124.47905)
		(end 46.101 -124.47905)
		(width 0.2794)
		(layer "F.Cu")
		(net "P12V_LED_R_FAN2")
	)
	(segment
		(start 39.5732 -197.4088)
		(end 41.1988 -195.7832)
		(width 0.4572)
		(layer "F.Cu")
		(net "P12V_LED_R1_FAN1")
	)
	(segment
		(start 39.5732 -197.97395)
		(end 37.846 -197.97395)
		(width 0.4572)
		(layer "F.Cu")
		(net "P12V_LED_R1_FAN1")
	)
	(segment
		(start 41.1988 -195.7832)
		(end 43.9928 -195.7832)
		(width 0.4572)
		(layer "F.Cu")
		(net "P12V_LED_R1_FAN1")
	)
	(segment
		(start 39.5732 -197.97395)
		(end 39.5732 -197.4088)
		(width 0.4572)
		(layer "F.Cu")
		(net "P12V_LED_R1_FAN1")
	)
	(via
		(at 39.5732 -197.97395)
		(size 0.762)
		(drill 0.381)
		(layers "F.Cu" "B.Cu")
		(net "P12V_LED_R1_FAN1")
	)
	(via
		(at 43.9928 -195.7832)
		(size 0.508)
		(drill 0.254)
		(layers "F.Cu" "B.Cu")
		(net "P12V_LED_R1_FAN1")
	)
	(segment
		(start 46.5709 -196.7611)
		(end 46.5709 -205.43901)
		(width 0.4572)
		(layer "In2.Cu")
		(net "P12V_LED_R1_FAN1")
	)
	(segment
		(start 46.5709 -205.43901)
		(end 44.99991 -207.01)
		(width 0.4572)
		(layer "In2.Cu")
		(net "P12V_LED_R1_FAN1")
	)
	(segment
		(start 43.9928 -195.7832)
		(end 45.593 -195.7832)
		(width 0.4572)
		(layer "In2.Cu")
		(net "P12V_LED_R1_FAN1")
	)
	(segment
		(start 45.593 -195.7832)
		(end 46.5709 -196.7611)
		(width 0.4572)
		(layer "In2.Cu")
		(net "P12V_LED_R1_FAN1")
	)
	(segment
		(start 36.83 -198.77405)
		(end 37.846 -198.77405)
		(width 0.2794)
		(layer "F.Cu")
		(net "P12V_LED_R_FAN1")
	)
	(segment
		(start 38.9128 -297.053)
		(end 37.73805 -297.053)
		(width 0.4572)
		(layer "F.Cu")
		(net "P12V_LED_R1_FAN0")
	)
	(segment
		(start 39.5986 -297.053)
		(end 38.9128 -297.053)
		(width 0.4572)
		(layer "F.Cu")
		(net "P12V_LED_R1_FAN0")
	)
	(segment
		(start 40.8686 -298.323)
		(end 39.5986 -297.053)
		(width 0.4572)
		(layer "F.Cu")
		(net "P12V_LED_R1_FAN0")
	)
	(segment
		(start 44.012866 -298.323)
		(end 42.2148 -298.323)
		(width 0.2794)
		(layer "F.Cu")
		(net "P12V_LED_R1_FAN0")
	)
	(segment
		(start 44.99991 -299.310044)
		(end 44.012866 -298.323)
		(width 0.2794)
		(layer "F.Cu")
		(net "P12V_LED_R1_FAN0")
	)
	(segment
		(start 42.2148 -298.323)
		(end 40.8686 -298.323)
		(width 0.4572)
		(layer "F.Cu")
		(net "P12V_LED_R1_FAN0")
	)
	(via
		(at 38.9128 -297.053)
		(size 0.762)
		(drill 0.381)
		(layers "F.Cu" "B.Cu")
		(net "P12V_LED_R1_FAN0")
	)
	(segment
		(start 36.93795 -296.99331)
		(end 36.93795 -297.053)
		(width 0.2794)
		(layer "F.Cu")
		(net "P12V_LED_R_FAN0")
	)
	(segment
		(start 37.73805 -295.91)
		(end 37.73805 -296.19321)
		(width 0.2794)
		(layer "F.Cu")
		(net "P12V_LED_R_FAN0")
	)
	(segment
		(start 37.73805 -296.19321)
		(end 36.93795 -296.99331)
		(width 0.2794)
		(layer "F.Cu")
		(net "P12V_LED_R_FAN0")
	)
	(segment
		(start 18.536158 -179.5399)
		(end 19.776186 -179.5399)
		(width 0.2794)
		(layer "F.Cu")
		(net "FM_BOARD_ID2")
	)
	(segment
		(start 18.01495 -180.061108)
		(end 18.536158 -179.5399)
		(width 0.2794)
		(layer "F.Cu")
		(net "FM_BOARD_ID2")
	)
	(segment
		(start 18.01495 -180.213)
		(end 18.01495 -180.061108)
		(width 0.2794)
		(layer "F.Cu")
		(net "FM_BOARD_ID2")
	)
	(segment
		(start 14.097 -180.28412)
		(end 14.64564 -180.83276)
		(width 0.2794)
		(layer "F.Cu")
		(net "FM_BOARD_ID2")
	)
	(segment
		(start 14.64564 -180.83276)
		(end 17.6149 -180.83276)
		(width 0.2794)
		(layer "F.Cu")
		(net "FM_BOARD_ID2")
	)
	(segment
		(start 19.776186 -179.5399)
		(end 20.42795 -180.191664)
		(width 0.2794)
		(layer "F.Cu")
		(net "FM_BOARD_ID2")
	)
	(segment
		(start 13.208 -180.28412)
		(end 14.097 -180.28412)
		(width 0.2794)
		(layer "F.Cu")
		(net "FM_BOARD_ID2")
	)
	(segment
		(start 18.01495 -180.43271)
		(end 18.01495 -180.213)
		(width 0.2794)
		(layer "F.Cu")
		(net "FM_BOARD_ID2")
	)
	(segment
		(start 20.42795 -180.191664)
		(end 20.42795 -180.213)
		(width 0.2794)
		(layer "F.Cu")
		(net "FM_BOARD_ID2")
	)
	(segment
		(start 17.6149 -180.83276)
		(end 18.01495 -180.43271)
		(width 0.2794)
		(layer "F.Cu")
		(net "FM_BOARD_ID2")
	)
	(via
		(at 17.6149 -180.83276)
		(size 0.508)
		(drill 0.254)
		(layers "F.Cu" "B.Cu")
		(net "FM_BOARD_ID2")
	)
	(segment
		(start 19.776186 -178.1429)
		(end 20.42795 -178.794664)
		(width 0.2794)
		(layer "F.Cu")
		(net "FM_BOARD_ID1")
	)
	(segment
		(start 16.93291 -179.89804)
		(end 18.01495 -178.816)
		(width 0.2794)
		(layer "F.Cu")
		(net "FM_BOARD_ID1")
	)
	(segment
		(start 16.74368 -179.89804)
		(end 14.6304 -179.89804)
		(width 0.2794)
		(layer "F.Cu")
		(net "FM_BOARD_ID1")
	)
	(segment
		(start 14.6304 -179.89804)
		(end 14.36624 -179.63388)
		(width 0.2794)
		(layer "F.Cu")
		(net "FM_BOARD_ID1")
	)
	(segment
		(start 14.36624 -179.63388)
		(end 13.208 -179.63388)
		(width 0.2794)
		(layer "F.Cu")
		(net "FM_BOARD_ID1")
	)
	(segment
		(start 16.74368 -179.89804)
		(end 16.93291 -179.89804)
		(width 0.2794)
		(layer "F.Cu")
		(net "FM_BOARD_ID1")
	)
	(segment
		(start 18.536158 -178.1429)
		(end 19.776186 -178.1429)
		(width 0.2794)
		(layer "F.Cu")
		(net "FM_BOARD_ID1")
	)
	(segment
		(start 20.42795 -178.794664)
		(end 20.42795 -178.816)
		(width 0.2794)
		(layer "F.Cu")
		(net "FM_BOARD_ID1")
	)
	(segment
		(start 18.01495 -178.816)
		(end 18.01495 -178.664108)
		(width 0.2794)
		(layer "F.Cu")
		(net "FM_BOARD_ID1")
	)
	(segment
		(start 18.01495 -178.664108)
		(end 18.536158 -178.1429)
		(width 0.2794)
		(layer "F.Cu")
		(net "FM_BOARD_ID1")
	)
	(via
		(at 16.74368 -179.89804)
		(size 0.762)
		(drill 0.381)
		(layers "F.Cu" "B.Cu")
		(net "FM_BOARD_ID1")
	)
	(segment
		(start 18.2753 -177.5587)
		(end 20.018248 -177.5587)
		(width 0.2794)
		(layer "F.Cu")
		(net "FM_BOARD_ID0")
	)
	(segment
		(start 20.018248 -177.5587)
		(end 20.259548 -177.8)
		(width 0.2794)
		(layer "F.Cu")
		(net "FM_BOARD_ID0")
	)
	(segment
		(start 20.42795 -176.784)
		(end 20.42795 -177.8)
		(width 0.2794)
		(layer "F.Cu")
		(net "FM_BOARD_ID0")
	)
	(segment
		(start 15.30604 -178.983894)
		(end 16.850106 -178.983894)
		(width 0.2794)
		(layer "F.Cu")
		(net "FM_BOARD_ID0")
	)
	(segment
		(start 20.259548 -177.8)
		(end 20.42795 -177.8)
		(width 0.2794)
		(layer "F.Cu")
		(net "FM_BOARD_ID0")
	)
	(segment
		(start 13.208 -178.983894)
		(end 15.30604 -178.983894)
		(width 0.2794)
		(layer "F.Cu")
		(net "FM_BOARD_ID0")
	)
	(segment
		(start 16.850106 -178.983894)
		(end 18.2753 -177.5587)
		(width 0.2794)
		(layer "F.Cu")
		(net "FM_BOARD_ID0")
	)
	(via
		(at 15.30604 -178.983894)
		(size 0.762)
		(drill 0.381)
		(layers "F.Cu" "B.Cu")
		(net "FM_BOARD_ID0")
	)
	(segment
		(start 20.42795 -175.768)
		(end 20.42795 -174.752)
		(width 0.2794)
		(layer "F.Cu")
		(net "FM_BOARD_SKU_ID2")
	)
	(segment
		(start 14.605 -177.8)
		(end 14.324838 -177.683922)
		(width 0.2794)
		(layer "F.Cu")
		(net "FM_BOARD_SKU_ID2")
	)
	(segment
		(start 16.66494 -177.8)
		(end 14.605 -177.8)
		(width 0.2794)
		(layer "F.Cu")
		(net "FM_BOARD_SKU_ID2")
	)
	(segment
		(start 17.1069 -177.8)
		(end 16.66494 -177.8)
		(width 0.2794)
		(layer "F.Cu")
		(net "FM_BOARD_SKU_ID2")
	)
	(segment
		(start 14.324838 -177.683922)
		(end 13.208 -177.683922)
		(width 0.2794)
		(layer "F.Cu")
		(net "FM_BOARD_SKU_ID2")
	)
	(segment
		(start 19.1389 -175.768)
		(end 17.1069 -177.8)
		(width 0.2794)
		(layer "F.Cu")
		(net "FM_BOARD_SKU_ID2")
	)
	(segment
		(start 20.42795 -175.768)
		(end 19.1389 -175.768)
		(width 0.2794)
		(layer "F.Cu")
		(net "FM_BOARD_SKU_ID2")
	)
	(via
		(at 16.66494 -177.8)
		(size 0.762)
		(drill 0.381)
		(layers "F.Cu" "B.Cu")
		(net "FM_BOARD_SKU_ID2")
	)
	(segment
		(start 15.24 -177.033936)
		(end 16.975328 -177.033936)
		(width 0.2794)
		(layer "F.Cu")
		(net "FM_BOARD_SKU_ID1")
	)
	(segment
		(start 20.273264 -173.736)
		(end 20.42795 -173.736)
		(width 0.2794)
		(layer "F.Cu")
		(net "FM_BOARD_SKU_ID1")
	)
	(segment
		(start 16.975328 -177.033936)
		(end 20.273264 -173.736)
		(width 0.2794)
		(layer "F.Cu")
		(net "FM_BOARD_SKU_ID1")
	)
	(segment
		(start 13.208 -177.033936)
		(end 15.24 -177.033936)
		(width 0.2794)
		(layer "F.Cu")
		(net "FM_BOARD_SKU_ID1")
	)
	(segment
		(start 20.42795 -173.736)
		(end 20.42795 -172.72)
		(width 0.2794)
		(layer "F.Cu")
		(net "FM_BOARD_SKU_ID1")
	)
	(via
		(at 15.24 -177.033936)
		(size 0.508)
		(drill 0.254)
		(layers "F.Cu" "B.Cu")
		(net "FM_BOARD_SKU_ID1")
	)
	(segment
		(start 14.062964 -176.38395)
		(end 13.208 -176.38395)
		(width 0.2794)
		(layer "F.Cu")
		(net "FM_BOARD_SKU_ID0")
	)
	(segment
		(start 15.27175 -176.264824)
		(end 14.062964 -176.38395)
		(width 0.2794)
		(layer "F.Cu")
		(net "FM_BOARD_SKU_ID0")
	)
	(segment
		(start 17.034002 -176.149)
		(end 19.05 -174.133002)
		(width 0.2794)
		(layer "F.Cu")
		(net "FM_BOARD_SKU_ID0")
	)
	(segment
		(start 15.367 -176.149)
		(end 17.034002 -176.149)
		(width 0.2794)
		(layer "F.Cu")
		(net "FM_BOARD_SKU_ID0")
	)
	(segment
		(start 15.367 -176.149)
		(end 15.27175 -176.264824)
		(width 0.2794)
		(layer "F.Cu")
		(net "FM_BOARD_SKU_ID0")
	)
	(segment
		(start 19.05 -174.133002)
		(end 19.05 -172.586396)
		(width 0.2794)
		(layer "F.Cu")
		(net "FM_BOARD_SKU_ID0")
	)
	(segment
		(start 19.05 -172.586396)
		(end 19.932396 -171.704)
		(width 0.2794)
		(layer "F.Cu")
		(net "FM_BOARD_SKU_ID0")
	)
	(segment
		(start 19.932396 -171.704)
		(end 20.42795 -171.704)
		(width 0.2794)
		(layer "F.Cu")
		(net "FM_BOARD_SKU_ID0")
	)
	(segment
		(start 20.42795 -171.704)
		(end 20.42795 -170.688)
		(width 0.2794)
		(layer "F.Cu")
		(net "FM_BOARD_SKU_ID0")
	)
	(via
		(at 15.367 -176.149)
		(size 0.762)
		(drill 0.381)
		(layers "F.Cu" "B.Cu")
		(net "FM_BOARD_SKU_ID0")
	)
	(segment
		(start 45.23105 -312.66765)
		(end 44.958 -312.3946)
		(width 0.2794)
		(layer "F.Cu")
		(net "U405_D1")
	)
	(segment
		(start 45.2247 -312.1279)
		(end 46.3804 -312.1279)
		(width 0.2794)
		(layer "F.Cu")
		(net "U405_D1")
	)
	(segment
		(start 44.958 -312.3946)
		(end 45.2247 -312.1279)
		(width 0.2794)
		(layer "F.Cu")
		(net "U405_D1")
	)
	(segment
		(start 46.3804 -312.1279)
		(end 47.752 -312.1279)
		(width 0.2794)
		(layer "F.Cu")
		(net "U405_D1")
	)
	(segment
		(start 45.23105 -314.071)
		(end 45.23105 -312.66765)
		(width 0.2794)
		(layer "F.Cu")
		(net "U405_D1")
	)
	(via
		(at 46.3804 -312.1279)
		(size 0.508)
		(drill 0.254)
		(layers "F.Cu" "B.Cu")
		(net "U405_D1")
	)
	(segment
		(start 45.8089 -312.6994)
		(end 46.3804 -312.1279)
		(width 0.2794)
		(layer "B.Cu")
		(net "U405_D1")
	)
	(segment
		(start 44.704 -312.6994)
		(end 45.8089 -312.6994)
		(width 0.2794)
		(layer "B.Cu")
		(net "U405_D1")
	)
	(segment
		(start 21.853144 -147.456144)
		(end 21.897594 -147.563332)
		(width 0.2794)
		(layer "F.Cu")
		(net "RST_SMB_PDB_R_N")
	)
	(segment
		(start 20.785328 -145.857976)
		(end 21.853144 -147.456144)
		(width 0.2794)
		(layer "F.Cu")
		(net "RST_SMB_PDB_R_N")
	)
	(segment
		(start 22.424136 -148.147024)
		(end 22.489922 -148.174202)
		(width 0.2794)
		(layer "F.Cu")
		(net "RST_SMB_PDB_R_N")
	)
	(segment
		(start 22.424136 -148.089874)
		(end 22.424136 -148.147024)
		(width 0.2794)
		(layer "F.Cu")
		(net "RST_SMB_PDB_R_N")
	)
	(segment
		(start 22.489922 -148.174202)
		(end 22.489922 -149.098)
		(width 0.2794)
		(layer "F.Cu")
		(net "RST_SMB_PDB_R_N")
	)
	(segment
		(start 20.32 -144.29105)
		(end 20.32 -144.734788)
		(width 0.2794)
		(layer "F.Cu")
		(net "RST_SMB_PDB_R_N")
	)
	(segment
		(start 21.897594 -147.563332)
		(end 22.424136 -148.089874)
		(width 0.2794)
		(layer "F.Cu")
		(net "RST_SMB_PDB_R_N")
	)
	(segment
		(start 20.686268 -145.618708)
		(end 20.785328 -145.857976)
		(width 0.2794)
		(layer "F.Cu")
		(net "RST_SMB_PDB_R_N")
	)
	(segment
		(start 20.32 -144.734788)
		(end 20.686268 -145.618708)
		(width 0.2794)
		(layer "F.Cu")
		(net "RST_SMB_PDB_R_N")
	)
	(via
		(at 20.686268 -145.618708)
		(size 0.762)
		(drill 0.381)
		(layers "F.Cu" "B.Cu")
		(net "RST_SMB_PDB_R_N")
	)
	(segment
		(start 22.4409 -31.369)
		(end 21.8313 -30.7594)
		(width 0.2794)
		(layer "F.Cu")
		(net "U409_D1")
	)
	(segment
		(start 22.4409 -31.966154)
		(end 22.4409 -31.369)
		(width 0.2794)
		(layer "F.Cu")
		(net "U409_D1")
	)
	(segment
		(start 20.56765 -33.76295)
		(end 20.4216 -33.909)
		(width 0.2794)
		(layer "F.Cu")
		(net "U409_D1")
	)
	(segment
		(start 23.701248 -33.226502)
		(end 22.4409 -31.966154)
		(width 0.2794)
		(layer "F.Cu")
		(net "U409_D1")
	)
	(segment
		(start 22.225 -33.76295)
		(end 20.56765 -33.76295)
		(width 0.2794)
		(layer "F.Cu")
		(net "U409_D1")
	)
	(segment
		(start 21.8313 -30.7594)
		(end 20.9042 -30.7594)
		(width 0.2794)
		(layer "F.Cu")
		(net "U409_D1")
	)
	(segment
		(start 23.701248 -33.76295)
		(end 22.225 -33.76295)
		(width 0.2794)
		(layer "F.Cu")
		(net "U409_D1")
	)
	(segment
		(start 23.701248 -33.76295)
		(end 23.701248 -33.226502)
		(width 0.2794)
		(layer "F.Cu")
		(net "U409_D1")
	)
	(via
		(at 23.701248 -33.76295)
		(size 0.762)
		(drill 0.381)
		(layers "F.Cu" "B.Cu")
		(net "U409_D1")
	)
	(segment
		(start 7.57428 -96.49714)
		(end 8.76554 -97.6884)
		(width 0.2794)
		(layer "F.Cu")
		(net "U410_D1")
	)
	(segment
		(start 7.34314 -96.266)
		(end 7.57428 -96.49714)
		(width 0.2794)
		(layer "F.Cu")
		(net "U410_D1")
	)
	(segment
		(start 4.826 -99.20605)
		(end 4.826 -96.647)
		(width 0.2794)
		(layer "F.Cu")
		(net "U410_D1")
	)
	(segment
		(start 10.2743 -97.6884)
		(end 9.398 -97.6884)
		(width 0.2794)
		(layer "F.Cu")
		(net "U410_D1")
	)
	(segment
		(start 4.21005 -99.822)
		(end 4.826 -99.20605)
		(width 0.2794)
		(layer "F.Cu")
		(net "U410_D1")
	)
	(segment
		(start 11.1379 -98.552)
		(end 10.2743 -97.6884)
		(width 0.2794)
		(layer "F.Cu")
		(net "U410_D1")
	)
	(segment
		(start 4.826 -96.647)
		(end 5.207 -96.266)
		(width 0.2794)
		(layer "F.Cu")
		(net "U410_D1")
	)
	(segment
		(start 8.76554 -97.6884)
		(end 9.398 -97.6884)
		(width 0.2794)
		(layer "F.Cu")
		(net "U410_D1")
	)
	(segment
		(start 3.7084 -98.425)
		(end 3.7084 -99.2124)
		(width 0.2794)
		(layer "F.Cu")
		(net "U410_D1")
	)
	(segment
		(start 5.207 -96.266)
		(end 7.34314 -96.266)
		(width 0.2794)
		(layer "F.Cu")
		(net "U410_D1")
	)
	(segment
		(start 3.7084 -99.2124)
		(end 4.21005 -99.71405)
		(width 0.2794)
		(layer "F.Cu")
		(net "U410_D1")
	)
	(segment
		(start 4.21005 -99.71405)
		(end 4.21005 -99.822)
		(width 0.2794)
		(layer "F.Cu")
		(net "U410_D1")
	)
	(via
		(at 7.57428 -96.49714)
		(size 0.762)
		(drill 0.381)
		(layers "F.Cu" "B.Cu")
		(net "U410_D1")
	)
	(segment
		(start 20.5359 -215.519)
		(end 20.00885 -214.99195)
		(width 0.2794)
		(layer "F.Cu")
		(net "U411_D1")
	)
	(segment
		(start 20.5359 -216.3191)
		(end 20.5359 -215.519)
		(width 0.2794)
		(layer "F.Cu")
		(net "U411_D1")
	)
	(segment
		(start 19.15795 -215.011)
		(end 18.13814 -215.011)
		(width 0.2794)
		(layer "F.Cu")
		(net "U411_D1")
	)
	(segment
		(start 19.177 -214.99195)
		(end 19.15795 -215.011)
		(width 0.2794)
		(layer "F.Cu")
		(net "U411_D1")
	)
	(segment
		(start 20.2184 -218.059)
		(end 20.2184 -216.6366)
		(width 0.2794)
		(layer "F.Cu")
		(net "U411_D1")
	)
	(segment
		(start 20.00885 -214.99195)
		(end 19.177 -214.99195)
		(width 0.2794)
		(layer "F.Cu")
		(net "U411_D1")
	)
	(segment
		(start 18.13814 -215.011)
		(end 16.3576 -215.011)
		(width 0.2794)
		(layer "F.Cu")
		(net "U411_D1")
	)
	(segment
		(start 20.2184 -216.6366)
		(end 20.5359 -216.3191)
		(width 0.2794)
		(layer "F.Cu")
		(net "U411_D1")
	)
	(via
		(at 18.13814 -215.011)
		(size 0.508)
		(drill 0.254)
		(layers "F.Cu" "B.Cu")
		(net "U411_D1")
	)
	(segment
		(start 10.795 -313.5376)
		(end 10.795 -312.674)
		(width 0.2794)
		(layer "F.Cu")
		(net "U412_D1")
	)
	(segment
		(start 3.937 -311.8739)
		(end 3.0861 -311.8739)
		(width 0.2794)
		(layer "F.Cu")
		(net "U412_D1")
	)
	(segment
		(start 10.5156 -313.817)
		(end 10.795 -313.5376)
		(width 0.2794)
		(layer "F.Cu")
		(net "U412_D1")
	)
	(segment
		(start 5.4991 -311.8739)
		(end 3.937 -311.8739)
		(width 0.2794)
		(layer "F.Cu")
		(net "U412_D1")
	)
	(segment
		(start 10.3124 -313.817)
		(end 10.3378 -313.8424)
		(width 0.2794)
		(layer "F.Cu")
		(net "U412_D1")
	)
	(segment
		(start 10.3886 -312.2676)
		(end 9.017 -312.2676)
		(width 0.2794)
		(layer "F.Cu")
		(net "U412_D1")
	)
	(segment
		(start 10.3632 -313.817)
		(end 10.5156 -313.817)
		(width 0.2794)
		(layer "F.Cu")
		(net "U412_D1")
	)
	(segment
		(start 9.16305 -313.817)
		(end 10.3124 -313.817)
		(width 0.2794)
		(layer "F.Cu")
		(net "U412_D1")
	)
	(segment
		(start 10.3378 -313.8424)
		(end 10.3632 -313.817)
		(width 0.2794)
		(layer "F.Cu")
		(net "U412_D1")
	)
	(segment
		(start 6.096 -311.277)
		(end 5.4991 -311.8739)
		(width 0.2794)
		(layer "F.Cu")
		(net "U412_D1")
	)
	(segment
		(start 8.0264 -311.277)
		(end 6.096 -311.277)
		(width 0.2794)
		(layer "F.Cu")
		(net "U412_D1")
	)
	(segment
		(start 10.795 -312.674)
		(end 10.3886 -312.2676)
		(width 0.2794)
		(layer "F.Cu")
		(net "U412_D1")
	)
	(segment
		(start 9.017 -312.2676)
		(end 8.0264 -311.277)
		(width 0.2794)
		(layer "F.Cu")
		(net "U412_D1")
	)
	(via
		(at 3.0861 -311.8739)
		(size 0.508)
		(drill 0.254)
		(layers "F.Cu" "B.Cu")
		(net "U412_D1")
	)
	(via
		(at 10.3378 -313.8424)
		(size 0.762)
		(drill 0.381)
		(layers "F.Cu" "B.Cu")
		(net "U412_D1")
	)
	(segment
		(start 4.3434 -313.1312)
		(end 3.0861 -311.8739)
		(width 0.2794)
		(layer "B.Cu")
		(net "U412_D1")
	)
	(segment
		(start 4.3434 -313.182)
		(end 4.3434 -313.1312)
		(width 0.2794)
		(layer "B.Cu")
		(net "U412_D1")
	)
	(segment
		(start 29.1211 -33.401)
		(end 29.1211 -35.21456)
		(width 0.2794)
		(layer "F.Cu")
		(net "U408_D1")
	)
	(segment
		(start 29.845 -31.579312)
		(end 28.999688 -30.734)
		(width 0.2794)
		(layer "F.Cu")
		(net "U408_D1")
	)
	(segment
		(start 31.0134 -35.306)
		(end 30.58795 -35.73145)
		(width 0.2794)
		(layer "F.Cu")
		(net "U408_D1")
	)
	(segment
		(start 28.999688 -30.734)
		(end 28.0416 -30.734)
		(width 0.2794)
		(layer "F.Cu")
		(net "U408_D1")
	)
	(segment
		(start 29.1211 -33.401)
		(end 29.845 -32.6771)
		(width 0.2794)
		(layer "F.Cu")
		(net "U408_D1")
	)
	(segment
		(start 29.1211 -35.21456)
		(end 29.38272 -35.47618)
		(width 0.2794)
		(layer "F.Cu")
		(net "U408_D1")
	)
	(segment
		(start 29.845 -32.6771)
		(end 29.845 -31.579312)
		(width 0.2794)
		(layer "F.Cu")
		(net "U408_D1")
	)
	(segment
		(start 30.58795 -35.73145)
		(end 30.58795 -36.703)
		(width 0.2794)
		(layer "F.Cu")
		(net "U408_D1")
	)
	(segment
		(start 29.38272 -35.49777)
		(end 29.38272 -35.47618)
		(width 0.2794)
		(layer "F.Cu")
		(net "U408_D1")
	)
	(segment
		(start 30.58795 -36.703)
		(end 29.38272 -35.49777)
		(width 0.2794)
		(layer "F.Cu")
		(net "U408_D1")
	)
	(via
		(at 29.38272 -35.47618)
		(size 0.762)
		(drill 0.381)
		(layers "F.Cu" "B.Cu")
		(net "U408_D1")
	)
	(segment
		(start 43.7896 -98.6536)
		(end 42.9641 -97.8281)
		(width 0.2794)
		(layer "F.Cu")
		(net "U407_D1")
	)
	(segment
		(start 45.466 -100.70592)
		(end 45.86478 -101.1047)
		(width 0.2794)
		(layer "F.Cu")
		(net "U407_D1")
	)
	(segment
		(start 41.62171 -97.8281)
		(end 40.6781 -98.77171)
		(width 0.2794)
		(layer "F.Cu")
		(net "U407_D1")
	)
	(segment
		(start 47.2694 -100.47224)
		(end 46.63694 -101.1047)
		(width 0.2794)
		(layer "F.Cu")
		(net "U407_D1")
	)
	(segment
		(start 45.86478 -101.1047)
		(end 46.63694 -101.1047)
		(width 0.2794)
		(layer "F.Cu")
		(net "U407_D1")
	)
	(segment
		(start 43.7896 -98.806)
		(end 43.7896 -98.6536)
		(width 0.2794)
		(layer "F.Cu")
		(net "U407_D1")
	)
	(segment
		(start 42.9641 -97.8281)
		(end 41.62171 -97.8281)
		(width 0.2794)
		(layer "F.Cu")
		(net "U407_D1")
	)
	(segment
		(start 47.2694 -99.568)
		(end 47.2694 -100.47224)
		(width 0.2794)
		(layer "F.Cu")
		(net "U407_D1")
	)
	(segment
		(start 43.7896 -98.806)
		(end 44.18965 -99.20605)
		(width 0.2794)
		(layer "F.Cu")
		(net "U407_D1")
	)
	(segment
		(start 45.466 -99.20605)
		(end 45.466 -100.70592)
		(width 0.2794)
		(layer "F.Cu")
		(net "U407_D1")
	)
	(segment
		(start 44.18965 -99.20605)
		(end 45.466 -99.20605)
		(width 0.2794)
		(layer "F.Cu")
		(net "U407_D1")
	)
	(segment
		(start 40.6781 -98.77171)
		(end 40.6781 -98.806)
		(width 0.2794)
		(layer "F.Cu")
		(net "U407_D1")
	)
	(via
		(at 46.63694 -101.1047)
		(size 0.762)
		(drill 0.381)
		(layers "F.Cu" "B.Cu")
		(net "U407_D1")
	)
	(segment
		(start 44.85005 -217.82405)
		(end 45.466 -217.82405)
		(width 0.2794)
		(layer "F.Cu")
		(net "U406_D1")
	)
	(segment
		(start 44.45 -217.424)
		(end 44.85005 -217.82405)
		(width 0.2794)
		(layer "F.Cu")
		(net "U406_D1")
	)
	(segment
		(start 47.1424 -219.1766)
		(end 47.1424 -218.44)
		(width 0.2794)
		(layer "F.Cu")
		(net "U406_D1")
	)
	(segment
		(start 46.08195 -218.44)
		(end 47.1424 -218.44)
		(width 0.2794)
		(layer "F.Cu")
		(net "U406_D1")
	)
	(segment
		(start 46.99 -219.329)
		(end 47.1424 -219.1766)
		(width 0.2794)
		(layer "F.Cu")
		(net "U406_D1")
	)
	(segment
		(start 46.99 -220.4974)
		(end 46.99 -219.329)
		(width 0.2794)
		(layer "F.Cu")
		(net "U406_D1")
	)
	(segment
		(start 45.466 -217.82405)
		(end 46.08195 -218.44)
		(width 0.2794)
		(layer "F.Cu")
		(net "U406_D1")
	)
	(segment
		(start 43.9801 -217.424)
		(end 44.45 -217.424)
		(width 0.2794)
		(layer "F.Cu")
		(net "U406_D1")
	)
	(segment
		(start 14.75105 -293.624)
		(end 16.764 -293.624)
		(width 0.4572)
		(layer "F.Cu")
		(net "P12V_LED_FAN7")
	)
	(segment
		(start 9.4488 -308.737)
		(end 13.97 -308.737)
		(width 0.4572)
		(layer "F.Cu")
		(net "P12V_LED_FAN7")
	)
	(segment
		(start 17.3101 -296.52595)
		(end 17.16405 -296.672)
		(width 0.4572)
		(layer "F.Cu")
		(net "P12V_LED_FAN7")
	)
	(segment
		(start 17.3101 -294.1701)
		(end 17.3101 -296.52595)
		(width 0.4572)
		(layer "F.Cu")
		(net "P12V_LED_FAN7")
	)
	(segment
		(start 15.912084 -301.587916)
		(end 16.70685 -301.587916)
		(width 0.4572)
		(layer "F.Cu")
		(net "P12V_LED_FAN7")
	)
	(segment
		(start 15.367 -307.34)
		(end 15.367 -302.133)
		(width 0.4572)
		(layer "F.Cu")
		(net "P12V_LED_FAN7")
	)
	(segment
		(start 17.2339 -298.25188)
		(end 17.2339 -299.974)
		(width 0.4572)
		(layer "F.Cu")
		(net "P12V_LED_FAN7")
	)
	(segment
		(start 17.16405 -296.672)
		(end 17.16405 -298.18203)
		(width 0.4572)
		(layer "F.Cu")
		(net "P12V_LED_FAN7")
	)
	(segment
		(start 17.16405 -301.130716)
		(end 17.16405 -300.736)
		(width 0.4572)
		(layer "F.Cu")
		(net "P12V_LED_FAN7")
	)
	(segment
		(start 17.2339 -299.974)
		(end 17.16405 -300.04385)
		(width 0.4572)
		(layer "F.Cu")
		(net "P12V_LED_FAN7")
	)
	(segment
		(start 15.367 -302.133)
		(end 15.912084 -301.587916)
		(width 0.4572)
		(layer "F.Cu")
		(net "P12V_LED_FAN7")
	)
	(segment
		(start 17.16405 -298.18203)
		(end 17.2339 -298.25188)
		(width 0.4572)
		(layer "F.Cu")
		(net "P12V_LED_FAN7")
	)
	(segment
		(start 17.16405 -300.04385)
		(end 17.16405 -300.736)
		(width 0.4572)
		(layer "F.Cu")
		(net "P12V_LED_FAN7")
	)
	(segment
		(start 13.97 -308.737)
		(end 15.367 -307.34)
		(width 0.4572)
		(layer "F.Cu")
		(net "P12V_LED_FAN7")
	)
	(segment
		(start 16.70685 -301.587916)
		(end 17.16405 -301.130716)
		(width 0.4572)
		(layer "F.Cu")
		(net "P12V_LED_FAN7")
	)
	(segment
		(start 8.128 -308.737)
		(end 9.4488 -308.737)
		(width 0.4572)
		(layer "F.Cu")
		(net "P12V_LED_FAN7")
	)
	(segment
		(start 16.764 -293.624)
		(end 17.3101 -294.1701)
		(width 0.4572)
		(layer "F.Cu")
		(net "P12V_LED_FAN7")
	)
	(via
		(at 6.36524 -308.74716)
		(size 0.762)
		(drill 0.381)
		(layers "F.Cu" "B.Cu")
		(net "P12V_LED_FAN7")
	)
	(via
		(at 9.4488 -308.737)
		(size 0.762)
		(drill 0.381)
		(layers "F.Cu" "B.Cu")
		(net "P12V_LED_FAN7")
	)
	(segment
		(start 17.272 -205.08595)
		(end 17.272 -204.369924)
		(width 0.4572)
		(layer "F.Cu")
		(net "P12V_LED_FAN6")
	)
	(segment
		(start 17.29105 -205.105)
		(end 17.272 -205.08595)
		(width 0.4572)
		(layer "F.Cu")
		(net "P12V_LED_FAN6")
	)
	(segment
		(start 14.605 -202.67295)
		(end 15.24 -202.67295)
		(width 0.4572)
		(layer "F.Cu")
		(net "P12V_LED_FAN6")
	)
	(segment
		(start 18.94205 -209.169)
		(end 19.558 -209.169)
		(width 0.4572)
		(layer "F.Cu")
		(net "P12V_LED_FAN6")
	)
	(via
		(at 19.558 -209.169)
		(size 0.508)
		(drill 0.254)
		(layers "F.Cu" "B.Cu")
		(net "P12V_LED_FAN6")
	)
	(via
		(at 3.429 -219.075)
		(size 0.508)
		(drill 0.254)
		(layers "F.Cu" "B.Cu")
		(net "P12V_LED_FAN6")
	)
	(via
		(at 17.272 -204.369924)
		(size 0.508)
		(drill 0.254)
		(layers "F.Cu" "B.Cu")
		(net "P12V_LED_FAN6")
	)
	(via
		(at 17.61236 -192.659)
		(size 0.6604)
		(drill 0.3302)
		(layers "F.Cu" "B.Cu")
		(net "P12V_LED_FAN6")
	)
	(via
		(at 15.24 -202.67295)
		(size 0.508)
		(drill 0.254)
		(layers "F.Cu" "B.Cu")
		(net "P12V_LED_FAN6")
	)
	(via
		(at 5.842 -193.04)
		(size 0.508)
		(drill 0.254)
		(layers "F.Cu" "B.Cu")
		(net "P12V_LED_FAN6")
	)
	(segment
		(start 18.72615 -202.67295)
		(end 15.24 -202.67295)
		(width 0.4572)
		(layer "B.Cu")
		(net "P12V_LED_FAN6")
	)
	(segment
		(start 17.7927 -205.3209)
		(end 18.6055 -205.3209)
		(width 0.4572)
		(layer "B.Cu")
		(net "P12V_LED_FAN6")
	)
	(segment
		(start 5.842 -193.04)
		(end 10.922 -193.04)
		(width 0.4572)
		(layer "B.Cu")
		(net "P12V_LED_FAN6")
	)
	(segment
		(start 19.0754 -201.4982)
		(end 21.082 -199.4916)
		(width 0.4572)
		(layer "B.Cu")
		(net "P12V_LED_FAN6")
	)
	(segment
		(start 17.272 -204.369924)
		(end 17.272 -204.8002)
		(width 0.4572)
		(layer "B.Cu")
		(net "P12V_LED_FAN6")
	)
	(segment
		(start 15.24 -202.67295)
		(end 15.24 -201.9554)
		(width 0.4572)
		(layer "B.Cu")
		(net "P12V_LED_FAN6")
	)
	(segment
		(start 10.922 -193.04)
		(end 11.303 -192.659)
		(width 0.4572)
		(layer "B.Cu")
		(net "P12V_LED_FAN6")
	)
	(segment
		(start 19.2024 -203.1492)
		(end 18.72615 -202.67295)
		(width 0.4572)
		(layer "B.Cu")
		(net "P12V_LED_FAN6")
	)
	(segment
		(start 15.6972 -201.4982)
		(end 19.0754 -201.4982)
		(width 0.4572)
		(layer "B.Cu")
		(net "P12V_LED_FAN6")
	)
	(segment
		(start 21.082 -193.802)
		(end 19.939 -192.659)
		(width 0.4572)
		(layer "B.Cu")
		(net "P12V_LED_FAN6")
	)
	(segment
		(start 19.939 -192.659)
		(end 17.61236 -192.659)
		(width 0.4572)
		(layer "B.Cu")
		(net "P12V_LED_FAN6")
	)
	(segment
		(start 16.330676 -204.827124)
		(end 16.330676 -205.767432)
		(width 0.4572)
		(layer "B.Cu")
		(net "P12V_LED_FAN6")
	)
	(segment
		(start 15.24 -201.9554)
		(end 15.6972 -201.4982)
		(width 0.4572)
		(layer "B.Cu")
		(net "P12V_LED_FAN6")
	)
	(segment
		(start 17.272 -204.8002)
		(end 17.7927 -205.3209)
		(width 0.4572)
		(layer "B.Cu")
		(net "P12V_LED_FAN6")
	)
	(segment
		(start 17.272 -204.369924)
		(end 16.787876 -204.369924)
		(width 0.4572)
		(layer "B.Cu")
		(net "P12V_LED_FAN6")
	)
	(segment
		(start 19.2024 -204.724)
		(end 19.2024 -203.1492)
		(width 0.4572)
		(layer "B.Cu")
		(net "P12V_LED_FAN6")
	)
	(segment
		(start 16.330676 -205.767432)
		(end 19.558 -208.994756)
		(width 0.4572)
		(layer "B.Cu")
		(net "P12V_LED_FAN6")
	)
	(segment
		(start 18.6055 -205.3209)
		(end 19.2024 -204.724)
		(width 0.4572)
		(layer "B.Cu")
		(net "P12V_LED_FAN6")
	)
	(segment
		(start 16.787876 -204.369924)
		(end 16.330676 -204.827124)
		(width 0.4572)
		(layer "B.Cu")
		(net "P12V_LED_FAN6")
	)
	(segment
		(start 11.303 -192.659)
		(end 17.61236 -192.659)
		(width 0.4572)
		(layer "B.Cu")
		(net "P12V_LED_FAN6")
	)
	(segment
		(start 21.082 -199.4916)
		(end 21.082 -193.802)
		(width 0.4572)
		(layer "B.Cu")
		(net "P12V_LED_FAN6")
	)
	(segment
		(start 19.558 -208.994756)
		(end 19.558 -209.169)
		(width 0.4572)
		(layer "B.Cu")
		(net "P12V_LED_FAN6")
	)
	(segment
		(start 3.429 -195.453)
		(end 5.842 -193.04)
		(width 0.4572)
		(layer "In2.Cu")
		(net "P12V_LED_FAN6")
	)
	(segment
		(start 3.429 -219.075)
		(end 3.429 -195.453)
		(width 0.4572)
		(layer "In2.Cu")
		(net "P12V_LED_FAN6")
	)
	(segment
		(start 49.492916 -35.904424)
		(end 48.800766 -35.212274)
		(width 0.4572)
		(layer "F.Cu")
		(net "P12V_LED_FAN3")
	)
	(segment
		(start 48.019716 -34.149284)
		(end 49.16805 -33.00095)
		(width 0.4572)
		(layer "F.Cu")
		(net "P12V_LED_FAN3")
	)
	(segment
		(start 48.800766 -35.212274)
		(end 48.019716 -35.212274)
		(width 0.4572)
		(layer "F.Cu")
		(net "P12V_LED_FAN3")
	)
	(segment
		(start 32.385 -33.4264)
		(end 32.385 -32.893)
		(width 0.4572)
		(layer "F.Cu")
		(net "P12V_LED_FAN3")
	)
	(segment
		(start 33.2486 -34.29)
		(end 33.909 -34.29)
		(width 0.4572)
		(layer "F.Cu")
		(net "P12V_LED_FAN3")
	)
	(segment
		(start 49.16805 -33.00095)
		(end 49.16805 -31.623)
		(width 0.4572)
		(layer "F.Cu")
		(net "P12V_LED_FAN3")
	)
	(segment
		(start 48.019716 -35.212274)
		(end 48.019716 -34.149284)
		(width 0.4572)
		(layer "F.Cu")
		(net "P12V_LED_FAN3")
	)
	(segment
		(start 48.019716 -35.212274)
		(end 47.290482 -34.48304)
		(width 0.4572)
		(layer "F.Cu")
		(net "P12V_LED_FAN3")
	)
	(segment
		(start 33.2486 -34.29)
		(end 32.385 -33.4264)
		(width 0.4572)
		(layer "F.Cu")
		(net "P12V_LED_FAN3")
	)
	(segment
		(start 35.24504 -34.48304)
		(end 34.4805 -33.7185)
		(width 0.4572)
		(layer "F.Cu")
		(net "P12V_LED_FAN3")
	)
	(segment
		(start 33.909 -34.29)
		(end 34.4805 -33.7185)
		(width 0.4572)
		(layer "F.Cu")
		(net "P12V_LED_FAN3")
	)
	(segment
		(start 34.39795 -24.638)
		(end 34.163 -24.638)
		(width 0.4572)
		(layer "F.Cu")
		(net "P12V_LED_FAN3")
	)
	(segment
		(start 34.39795 -20.574)
		(end 34.39795 -24.638)
		(width 0.4572)
		(layer "F.Cu")
		(net "P12V_LED_FAN3")
	)
	(segment
		(start 47.290482 -34.48304)
		(end 35.24504 -34.48304)
		(width 0.4572)
		(layer "F.Cu")
		(net "P12V_LED_FAN3")
	)
	(segment
		(start 34.163 -24.638)
		(end 33.655 -25.146)
		(width 0.4572)
		(layer "F.Cu")
		(net "P12V_LED_FAN3")
	)
	(via
		(at 32.385 -32.893)
		(size 0.508)
		(drill 0.254)
		(layers "F.Cu" "B.Cu")
		(net "P12V_LED_FAN3")
	)
	(via
		(at 33.655 -25.146)
		(size 0.508)
		(drill 0.254)
		(layers "F.Cu" "B.Cu")
		(net "P12V_LED_FAN3")
	)
	(via
		(at 34.4805 -33.7185)
		(size 0.508)
		(drill 0.254)
		(layers "F.Cu" "B.Cu")
		(net "P12V_LED_FAN3")
	)
	(via
		(at 49.16805 -33.00095)
		(size 0.762)
		(drill 0.381)
		(layers "F.Cu" "B.Cu")
		(net "P12V_LED_FAN3")
	)
	(segment
		(start 33.655 -25.146)
		(end 33.401 -25.4)
		(width 0.4572)
		(layer "B.Cu")
		(net "P12V_LED_FAN3")
	)
	(segment
		(start 33.401 -25.4)
		(end 33.401 -31.877)
		(width 0.4572)
		(layer "B.Cu")
		(net "P12V_LED_FAN3")
	)
	(segment
		(start 33.401 -31.877)
		(end 32.385 -32.893)
		(width 0.4572)
		(layer "B.Cu")
		(net "P12V_LED_FAN3")
	)
	(segment
		(start 18.178526 -34.932874)
		(end 18.1864 -34.925)
		(width 0.4572)
		(layer "F.Cu")
		(net "P12V_LED_FAN4")
	)
	(segment
		(start 16.368268 -31.354268)
		(end 16.891 -31.877)
		(width 0.4572)
		(layer "F.Cu")
		(net "P12V_LED_FAN4")
	)
	(segment
		(start 15.494 -29.464)
		(end 15.494 -30.804866)
		(width 0.4572)
		(layer "F.Cu")
		(net "P12V_LED_FAN4")
	)
	(segment
		(start 16.043402 -31.354268)
		(end 16.368268 -31.354268)
		(width 0.4572)
		(layer "F.Cu")
		(net "P12V_LED_FAN4")
	)
	(segment
		(start 3.7338 -34.10585)
		(end 3.7338 -34.932874)
		(width 0.4572)
		(layer "F.Cu")
		(net "P12V_LED_FAN4")
	)
	(segment
		(start 17.41805 -27.53995)
		(end 15.494 -29.464)
		(width 0.4572)
		(layer "F.Cu")
		(net "P12V_LED_FAN4")
	)
	(segment
		(start 16.891 -33.6296)
		(end 18.1864 -34.925)
		(width 0.4572)
		(layer "F.Cu")
		(net "P12V_LED_FAN4")
	)
	(segment
		(start 2.2606 -35.396424)
		(end 2.72415 -34.932874)
		(width 0.4572)
		(layer "F.Cu")
		(net "P12V_LED_FAN4")
	)
	(segment
		(start 15.494 -30.804866)
		(end 16.043402 -31.354268)
		(width 0.4572)
		(layer "F.Cu")
		(net "P12V_LED_FAN4")
	)
	(segment
		(start 2.72415 -34.932874)
		(end 3.7338 -34.932874)
		(width 0.4572)
		(layer "F.Cu")
		(net "P12V_LED_FAN4")
	)
	(segment
		(start 3.7338 -34.932874)
		(end 18.178526 -34.932874)
		(width 0.4572)
		(layer "F.Cu")
		(net "P12V_LED_FAN4")
	)
	(segment
		(start 16.891 -31.877)
		(end 16.891 -33.6296)
		(width 0.4572)
		(layer "F.Cu")
		(net "P12V_LED_FAN4")
	)
	(segment
		(start 17.41805 -20.574)
		(end 17.41805 -24.892)
		(width 0.4572)
		(layer "F.Cu")
		(net "P12V_LED_FAN4")
	)
	(segment
		(start 17.41805 -24.892)
		(end 17.41805 -27.53995)
		(width 0.4572)
		(layer "F.Cu")
		(net "P12V_LED_FAN4")
	)
	(segment
		(start 2.39395 -31.496)
		(end 2.39395 -32.766)
		(width 0.4572)
		(layer "F.Cu")
		(net "P12V_LED_FAN4")
	)
	(segment
		(start 2.39395 -32.766)
		(end 3.7338 -34.10585)
		(width 0.4572)
		(layer "F.Cu")
		(net "P12V_LED_FAN4")
	)
	(via
		(at 2.39395 -32.766)
		(size 0.762)
		(drill 0.381)
		(layers "F.Cu" "B.Cu")
		(net "P12V_LED_FAN4")
	)
	(segment
		(start 17.29105 -108.458)
		(end 18.034 -108.458)
		(width 0.4572)
		(layer "F.Cu")
		(net "P12V_LED_FAN5")
	)
	(segment
		(start 3.02895 -124.714)
		(end 3.02895 -123.698)
		(width 0.4572)
		(layer "F.Cu")
		(net "P12V_LED_FAN5")
	)
	(segment
		(start 5.6642 -100.965)
		(end 3.02895 -103.60025)
		(width 0.4572)
		(layer "F.Cu")
		(net "P12V_LED_FAN5")
	)
	(segment
		(start 17.907 -112.649)
		(end 17.29105 -112.649)
		(width 0.4572)
		(layer "F.Cu")
		(net "P12V_LED_FAN5")
	)
	(segment
		(start 20.955 -101.092)
		(end 19.431 -99.568)
		(width 0.4572)
		(layer "F.Cu")
		(net "P12V_LED_FAN5")
	)
	(segment
		(start 5.6642 -100.965)
		(end 5.9436 -100.6856)
		(width 0.4572)
		(layer "F.Cu")
		(net "P12V_LED_FAN5")
	)
	(segment
		(start 16.002 -99.568)
		(end 14.605 -100.965)
		(width 0.4572)
		(layer "F.Cu")
		(net "P12V_LED_FAN5")
	)
	(segment
		(start 19.431 -99.568)
		(end 16.002 -99.568)
		(width 0.4572)
		(layer "F.Cu")
		(net "P12V_LED_FAN5")
	)
	(segment
		(start 14.605 -100.965)
		(end 5.6642 -100.965)
		(width 0.4572)
		(layer "F.Cu")
		(net "P12V_LED_FAN5")
	)
	(segment
		(start 5.9436 -100.6856)
		(end 5.9436 -97.409)
		(width 0.4572)
		(layer "F.Cu")
		(net "P12V_LED_FAN5")
	)
	(segment
		(start 2.54 -126.111)
		(end 2.54 -125.20295)
		(width 0.4572)
		(layer "F.Cu")
		(net "P12V_LED_FAN5")
	)
	(segment
		(start 3.02895 -103.60025)
		(end 3.02895 -123.698)
		(width 0.4572)
		(layer "F.Cu")
		(net "P12V_LED_FAN5")
	)
	(segment
		(start 2.54 -125.20295)
		(end 3.02895 -124.714)
		(width 0.4572)
		(layer "F.Cu")
		(net "P12V_LED_FAN5")
	)
	(via
		(at 18.034 -108.458)
		(size 0.508)
		(drill 0.254)
		(layers "F.Cu" "B.Cu")
		(net "P12V_LED_FAN5")
	)
	(via
		(at 20.955 -101.092)
		(size 0.508)
		(drill 0.254)
		(layers "F.Cu" "B.Cu")
		(net "P12V_LED_FAN5")
	)
	(via
		(at 17.907 -112.649)
		(size 0.508)
		(drill 0.254)
		(layers "F.Cu" "B.Cu")
		(net "P12V_LED_FAN5")
	)
	(segment
		(start 20.199604 -100.983542)
		(end 18.403062 -102.780084)
		(width 0.4572)
		(layer "In2.Cu")
		(net "P12V_LED_FAN5")
	)
	(segment
		(start 18.403062 -102.780084)
		(end 18.403062 -108.088938)
		(width 0.4572)
		(layer "In2.Cu")
		(net "P12V_LED_FAN5")
	)
	(segment
		(start 17.907 -112.649)
		(end 17.78 -112.522)
		(width 0.4572)
		(layer "In2.Cu")
		(net "P12V_LED_FAN5")
	)
	(segment
		(start 20.955 -101.092)
		(end 20.846542 -100.983542)
		(width 0.4572)
		(layer "In2.Cu")
		(net "P12V_LED_FAN5")
	)
	(segment
		(start 18.403062 -108.088938)
		(end 18.034 -108.458)
		(width 0.4572)
		(layer "In2.Cu")
		(net "P12V_LED_FAN5")
	)
	(segment
		(start 17.78 -108.712)
		(end 18.034 -108.458)
		(width 0.4572)
		(layer "In2.Cu")
		(net "P12V_LED_FAN5")
	)
	(segment
		(start 20.846542 -100.983542)
		(end 20.199604 -100.983542)
		(width 0.4572)
		(layer "In2.Cu")
		(net "P12V_LED_FAN5")
	)
	(segment
		(start 17.78 -112.522)
		(end 17.78 -108.712)
		(width 0.4572)
		(layer "In2.Cu")
		(net "P12V_LED_FAN5")
	)
	(segment
		(start 46.863 -125.07595)
		(end 46.863 -125.984)
		(width 0.4572)
		(layer "F.Cu")
		(net "P12V_LED_FAN2")
	)
	(segment
		(start 46.101 -123.67895)
		(end 46.6979 -123.67895)
		(width 0.4572)
		(layer "F.Cu")
		(net "P12V_LED_FAN2")
	)
	(segment
		(start 40.84828 -102.489)
		(end 40.003984 -101.644704)
		(width 0.4572)
		(layer "F.Cu")
		(net "P12V_LED_FAN2")
	)
	(segment
		(start 49.5046 -98.552)
		(end 49.5046 -99.7204)
		(width 0.4572)
		(layer "F.Cu")
		(net "P12V_LED_FAN2")
	)
	(segment
		(start 34.5821 -105.33888)
		(end 34.5821 -107.75315)
		(width 0.4572)
		(layer "F.Cu")
		(net "P12V_LED_FAN2")
	)
	(segment
		(start 38.017704 -101.644704)
		(end 36.703 -100.33)
		(width 0.4572)
		(layer "F.Cu")
		(net "P12V_LED_FAN2")
	)
	(segment
		(start 47.47895 -124.46)
		(end 46.863 -125.07595)
		(width 0.4572)
		(layer "F.Cu")
		(net "P12V_LED_FAN2")
	)
	(segment
		(start 35.052 -100.6602)
		(end 35.052 -102.108)
		(width 0.4572)
		(layer "F.Cu")
		(net "P12V_LED_FAN2")
	)
	(segment
		(start 36.322 -103.186992)
		(end 36.322 -104.190546)
		(width 0.4572)
		(layer "F.Cu")
		(net "P12V_LED_FAN2")
	)
	(segment
		(start 35.592512 -102.648512)
		(end 35.78352 -102.648512)
		(width 0.4572)
		(layer "F.Cu")
		(net "P12V_LED_FAN2")
	)
	(segment
		(start 31.60395 -108.35005)
		(end 31.60395 -108.966)
		(width 0.4572)
		(layer "F.Cu")
		(net "P12V_LED_FAN2")
	)
	(segment
		(start 49.5046 -99.7204)
		(end 46.736 -102.489)
		(width 0.4572)
		(layer "F.Cu")
		(net "P12V_LED_FAN2")
	)
	(segment
		(start 40.003984 -101.644704)
		(end 38.017704 -101.644704)
		(width 0.4572)
		(layer "F.Cu")
		(net "P12V_LED_FAN2")
	)
	(segment
		(start 35.052 -102.108)
		(end 35.592512 -102.648512)
		(width 0.4572)
		(layer "F.Cu")
		(net "P12V_LED_FAN2")
	)
	(segment
		(start 36.322 -104.190546)
		(end 35.864546 -104.648)
		(width 0.4572)
		(layer "F.Cu")
		(net "P12V_LED_FAN2")
	)
	(segment
		(start 35.3822 -100.33)
		(end 35.052 -100.6602)
		(width 0.4572)
		(layer "F.Cu")
		(net "P12V_LED_FAN2")
	)
	(segment
		(start 46.101 -123.1646)
		(end 47.9552 -121.3104)
		(width 0.4572)
		(layer "F.Cu")
		(net "P12V_LED_FAN2")
	)
	(segment
		(start 34.65195 -107.823)
		(end 32.131 -107.823)
		(width 0.4572)
		(layer "F.Cu")
		(net "P12V_LED_FAN2")
	)
	(segment
		(start 47.9552 -121.3104)
		(end 47.9552 -103.7082)
		(width 0.4572)
		(layer "F.Cu")
		(net "P12V_LED_FAN2")
	)
	(segment
		(start 35.78352 -102.648512)
		(end 36.322 -103.186992)
		(width 0.4572)
		(layer "F.Cu")
		(net "P12V_LED_FAN2")
	)
	(segment
		(start 32.131 -107.823)
		(end 31.60395 -108.35005)
		(width 0.4572)
		(layer "F.Cu")
		(net "P12V_LED_FAN2")
	)
	(segment
		(start 47.9552 -103.7082)
		(end 46.736 -102.489)
		(width 0.4572)
		(layer "F.Cu")
		(net "P12V_LED_FAN2")
	)
	(segment
		(start 34.5821 -107.75315)
		(end 34.65195 -107.823)
		(width 0.4572)
		(layer "F.Cu")
		(net "P12V_LED_FAN2")
	)
	(segment
		(start 36.703 -100.33)
		(end 35.3822 -100.33)
		(width 0.4572)
		(layer "F.Cu")
		(net "P12V_LED_FAN2")
	)
	(segment
		(start 35.27298 -104.648)
		(end 34.5821 -105.33888)
		(width 0.4572)
		(layer "F.Cu")
		(net "P12V_LED_FAN2")
	)
	(segment
		(start 35.864546 -104.648)
		(end 35.27298 -104.648)
		(width 0.4572)
		(layer "F.Cu")
		(net "P12V_LED_FAN2")
	)
	(segment
		(start 46.101 -123.67895)
		(end 46.101 -123.1646)
		(width 0.4572)
		(layer "F.Cu")
		(net "P12V_LED_FAN2")
	)
	(segment
		(start 46.6979 -123.67895)
		(end 47.47895 -124.46)
		(width 0.4572)
		(layer "F.Cu")
		(net "P12V_LED_FAN2")
	)
	(segment
		(start 46.736 -102.489)
		(end 40.84828 -102.489)
		(width 0.4572)
		(layer "F.Cu")
		(net "P12V_LED_FAN2")
	)
	(via
		(at 40.003984 -101.644704)
		(size 0.762)
		(drill 0.381)
		(layers "F.Cu" "B.Cu")
		(net "P12V_LED_FAN2")
	)
	(via
		(at 47.9552 -103.7082)
		(size 0.762)
		(drill 0.381)
		(layers "F.Cu" "B.Cu")
		(net "P12V_LED_FAN2")
	)
	(segment
		(start 36.83 -197.459854)
		(end 36.83 -197.97395)
		(width 0.4572)
		(layer "F.Cu")
		(net "P12V_LED_FAN1")
	)
	(segment
		(start 32.495744 -203.56195)
		(end 33.06318 -204.129386)
		(width 0.4572)
		(layer "F.Cu")
		(net "P12V_LED_FAN1")
	)
	(segment
		(start 34.52495 -200.298304)
		(end 34.671 -200.152254)
		(width 0.4572)
		(layer "F.Cu")
		(net "P12V_LED_FAN1")
	)
	(segment
		(start 36.74237 -192.899284)
		(end 35.946842 -193.694812)
		(width 0.4572)
		(layer "F.Cu")
		(net "P12V_LED_FAN1")
	)
	(segment
		(start 34.431732 -203.868274)
		(end 34.431732 -200.956418)
		(width 0.4572)
		(layer "F.Cu")
		(net "P12V_LED_FAN1")
	)
	(segment
		(start 49.100232 -196.659246)
		(end 45.34027 -192.899284)
		(width 0.4572)
		(layer "F.Cu")
		(net "P12V_LED_FAN1")
	)
	(segment
		(start 35.946842 -196.576696)
		(end 36.83 -197.459854)
		(width 0.4572)
		(layer "F.Cu")
		(net "P12V_LED_FAN1")
	)
	(segment
		(start 33.06318 -204.129386)
		(end 34.17062 -204.129386)
		(width 0.4572)
		(layer "F.Cu")
		(net "P12V_LED_FAN1")
	)
	(segment
		(start 32.258 -203.56195)
		(end 32.495744 -203.56195)
		(width 0.4572)
		(layer "F.Cu")
		(net "P12V_LED_FAN1")
	)
	(segment
		(start 34.671 -198.30288)
		(end 34.99993 -197.97395)
		(width 0.4572)
		(layer "F.Cu")
		(net "P12V_LED_FAN1")
	)
	(segment
		(start 34.52495 -200.8632)
		(end 34.52495 -200.298304)
		(width 0.4572)
		(layer "F.Cu")
		(net "P12V_LED_FAN1")
	)
	(segment
		(start 49.100232 -213.260432)
		(end 49.3776 -213.5378)
		(width 0.4572)
		(layer "F.Cu")
		(net "P12V_LED_FAN1")
	)
	(segment
		(start 49.3776 -213.5378)
		(end 49.3776 -217.424)
		(width 0.4572)
		(layer "F.Cu")
		(net "P12V_LED_FAN1")
	)
	(segment
		(start 44.1452 -192.899284)
		(end 36.74237 -192.899284)
		(width 0.4572)
		(layer "F.Cu")
		(net "P12V_LED_FAN1")
	)
	(segment
		(start 35.946842 -193.694812)
		(end 35.946842 -196.576696)
		(width 0.4572)
		(layer "F.Cu")
		(net "P12V_LED_FAN1")
	)
	(segment
		(start 49.100232 -213.260432)
		(end 49.100232 -196.659246)
		(width 0.4572)
		(layer "F.Cu")
		(net "P12V_LED_FAN1")
	)
	(segment
		(start 34.671 -200.152254)
		(end 34.671 -198.30288)
		(width 0.4572)
		(layer "F.Cu")
		(net "P12V_LED_FAN1")
	)
	(segment
		(start 34.99993 -197.97395)
		(end 36.83 -197.97395)
		(width 0.4572)
		(layer "F.Cu")
		(net "P12V_LED_FAN1")
	)
	(segment
		(start 34.431732 -200.956418)
		(end 34.52495 -200.8632)
		(width 0.4572)
		(layer "F.Cu")
		(net "P12V_LED_FAN1")
	)
	(segment
		(start 45.34027 -192.899284)
		(end 44.1452 -192.899284)
		(width 0.4572)
		(layer "F.Cu")
		(net "P12V_LED_FAN1")
	)
	(segment
		(start 34.17062 -204.129386)
		(end 34.431732 -203.868274)
		(width 0.4572)
		(layer "F.Cu")
		(net "P12V_LED_FAN1")
	)
	(via
		(at 49.100232 -213.260432)
		(size 0.762)
		(drill 0.381)
		(layers "F.Cu" "B.Cu")
		(net "P12V_LED_FAN1")
	)
	(via
		(at 44.1452 -192.899284)
		(size 0.762)
		(drill 0.381)
		(layers "F.Cu" "B.Cu")
		(net "P12V_LED_FAN1")
	)
	(segment
		(start 25.705308 -299.287692)
		(end 25.705308 -305.409854)
		(width 0.4572)
		(layer "F.Cu")
		(net "P12V_LED_FAN0")
	)
	(segment
		(start 36.195 -296.40403)
		(end 36.68903 -295.91)
		(width 0.4572)
		(layer "F.Cu")
		(net "P12V_LED_FAN0")
	)
	(segment
		(start 34.52495 -297.18)
		(end 34.52495 -297.54195)
		(width 0.4572)
		(layer "F.Cu")
		(net "P12V_LED_FAN0")
	)
	(segment
		(start 43.688 -308.61)
		(end 43.617642 -308.680358)
		(width 0.4572)
		(layer "F.Cu")
		(net "P12V_LED_FAN0")
	)
	(segment
		(start 25.705308 -305.409854)
		(end 28.975812 -308.680358)
		(width 0.4572)
		(layer "F.Cu")
		(net "P12V_LED_FAN0")
	)
	(segment
		(start 29.651198 -295.341802)
		(end 25.705308 -299.287692)
		(width 0.4572)
		(layer "F.Cu")
		(net "P12V_LED_FAN0")
	)
	(segment
		(start 34.78022 -297.79722)
		(end 35.705034 -297.79722)
		(width 0.4572)
		(layer "F.Cu")
		(net "P12V_LED_FAN0")
	)
	(segment
		(start 34.52495 -297.54195)
		(end 34.78022 -297.79722)
		(width 0.4572)
		(layer "F.Cu")
		(net "P12V_LED_FAN0")
	)
	(segment
		(start 28.975812 -308.680358)
		(end 41.3512 -308.680358)
		(width 0.4572)
		(layer "F.Cu")
		(net "P12V_LED_FAN0")
	)
	(segment
		(start 41.3512 -308.680358)
		(end 43.617642 -308.680358)
		(width 0.4572)
		(layer "F.Cu")
		(net "P12V_LED_FAN0")
	)
	(segment
		(start 34.4551 -293.18585)
		(end 34.52495 -293.116)
		(width 0.4572)
		(layer "F.Cu")
		(net "P12V_LED_FAN0")
	)
	(segment
		(start 34.52495 -293.116)
		(end 31.877 -293.116)
		(width 0.4572)
		(layer "F.Cu")
		(net "P12V_LED_FAN0")
	)
	(segment
		(start 34.52495 -297.18)
		(end 34.4551 -297.11015)
		(width 0.4572)
		(layer "F.Cu")
		(net "P12V_LED_FAN0")
	)
	(segment
		(start 34.4551 -297.11015)
		(end 34.4551 -293.18585)
		(width 0.4572)
		(layer "F.Cu")
		(net "P12V_LED_FAN0")
	)
	(segment
		(start 36.68903 -295.91)
		(end 36.93795 -295.91)
		(width 0.4572)
		(layer "F.Cu")
		(net "P12V_LED_FAN0")
	)
	(segment
		(start 31.877 -293.116)
		(end 29.651198 -295.341802)
		(width 0.4572)
		(layer "F.Cu")
		(net "P12V_LED_FAN0")
	)
	(segment
		(start 36.195 -297.307254)
		(end 36.195 -296.40403)
		(width 0.4572)
		(layer "F.Cu")
		(net "P12V_LED_FAN0")
	)
	(segment
		(start 35.705034 -297.79722)
		(end 36.195 -297.307254)
		(width 0.4572)
		(layer "F.Cu")
		(net "P12V_LED_FAN0")
	)
	(via
		(at 41.3512 -308.680358)
		(size 0.762)
		(drill 0.381)
		(layers "F.Cu" "B.Cu")
		(net "P12V_LED_FAN0")
	)
	(via
		(at 29.651198 -295.341802)
		(size 0.762)
		(drill 0.381)
		(layers "F.Cu" "B.Cu")
		(net "P12V_LED_FAN0")
	)
	(segment
		(start 47.244254 -132.334)
		(end 47.85995 -132.334)
		(width 0.2794)
		(layer "F.Cu")
		(net "U403_ADD0")
	)
	(segment
		(start 47.883064 -132.310886)
		(end 47.883064 -131.65074)
		(width 0.2794)
		(layer "F.Cu")
		(net "U403_ADD0")
	)
	(segment
		(start 47.883064 -131.65074)
		(end 47.883064 -131.087114)
		(width 0.2794)
		(layer "F.Cu")
		(net "U403_ADD0")
	)
	(segment
		(start 46.75632 -132.821934)
		(end 47.244254 -132.334)
		(width 0.2794)
		(layer "F.Cu")
		(net "U403_ADD0")
	)
	(segment
		(start 47.85995 -132.334)
		(end 47.883064 -132.310886)
		(width 0.2794)
		(layer "F.Cu")
		(net "U403_ADD0")
	)
	(segment
		(start 47.85995 -131.064)
		(end 47.85995 -130.937)
		(width 0.2794)
		(layer "F.Cu")
		(net "U403_ADD0")
	)
	(segment
		(start 47.883064 -131.087114)
		(end 47.85995 -131.064)
		(width 0.2794)
		(layer "F.Cu")
		(net "U403_ADD0")
	)
	(segment
		(start 45.992034 -132.821934)
		(end 46.75632 -132.821934)
		(width 0.2794)
		(layer "F.Cu")
		(net "U403_ADD0")
	)
	(via
		(at 47.883064 -131.65074)
		(size 0.508)
		(drill 0.254)
		(layers "F.Cu" "B.Cu")
		(net "U403_ADD0")
	)
	(segment
		(start 43.191938 -134.739888)
		(end 43.561 -135.10895)
		(width 0.2794)
		(layer "F.Cu")
		(net "U403_ADD1")
	)
	(segment
		(start 44.2341 -135.630158)
		(end 43.712892 -135.10895)
		(width 0.2794)
		(layer "F.Cu")
		(net "U403_ADD1")
	)
	(segment
		(start 44.16044 -137.23112)
		(end 43.81627 -136.88695)
		(width 0.2794)
		(layer "F.Cu")
		(net "U403_ADD1")
	)
	(segment
		(start 43.191938 -133.622034)
		(end 43.191938 -134.739888)
		(width 0.2794)
		(layer "F.Cu")
		(net "U403_ADD1")
	)
	(segment
		(start 43.712892 -135.10895)
		(end 43.561 -135.10895)
		(width 0.2794)
		(layer "F.Cu")
		(net "U403_ADD1")
	)
	(segment
		(start 44.7929 -136.77265)
		(end 44.2341 -136.21385)
		(width 0.2794)
		(layer "F.Cu")
		(net "U403_ADD1")
	)
	(segment
		(start 43.81627 -136.88695)
		(end 43.561 -136.88695)
		(width 0.2794)
		(layer "F.Cu")
		(net "U403_ADD1")
	)
	(segment
		(start 44.2341 -136.21385)
		(end 44.2341 -135.630158)
		(width 0.2794)
		(layer "F.Cu")
		(net "U403_ADD1")
	)
	(segment
		(start 44.7929 -137.19048)
		(end 44.75226 -137.23112)
		(width 0.2794)
		(layer "F.Cu")
		(net "U403_ADD1")
	)
	(segment
		(start 44.7929 -137.19048)
		(end 44.7929 -136.77265)
		(width 0.2794)
		(layer "F.Cu")
		(net "U403_ADD1")
	)
	(segment
		(start 44.75226 -137.23112)
		(end 44.16044 -137.23112)
		(width 0.2794)
		(layer "F.Cu")
		(net "U403_ADD1")
	)
	(via
		(at 44.7929 -137.19048)
		(size 0.762)
		(drill 0.381)
		(layers "F.Cu" "B.Cu")
		(net "U403_ADD1")
	)
	(segment
		(start 42.46626 -134.53872)
		(end 42.46626 -134.49554)
		(width 0.2794)
		(layer "F.Cu")
		(net "U403_ADD2")
	)
	(segment
		(start 41.6179 -135.630158)
		(end 42.139108 -135.10895)
		(width 0.2794)
		(layer "F.Cu")
		(net "U403_ADD2")
	)
	(segment
		(start 42.291 -134.71398)
		(end 42.46626 -134.53872)
		(width 0.2794)
		(layer "F.Cu")
		(net "U403_ADD2")
	)
	(segment
		(start 42.291 -136.88695)
		(end 41.6179 -136.21385)
		(width 0.2794)
		(layer "F.Cu")
		(net "U403_ADD2")
	)
	(segment
		(start 42.46626 -134.49554)
		(end 42.692066 -134.269734)
		(width 0.2794)
		(layer "F.Cu")
		(net "U403_ADD2")
	)
	(segment
		(start 41.6179 -136.21385)
		(end 41.6179 -135.630158)
		(width 0.2794)
		(layer "F.Cu")
		(net "U403_ADD2")
	)
	(segment
		(start 42.139108 -135.10895)
		(end 42.291 -135.10895)
		(width 0.2794)
		(layer "F.Cu")
		(net "U403_ADD2")
	)
	(segment
		(start 42.291 -135.10895)
		(end 42.291 -134.71398)
		(width 0.2794)
		(layer "F.Cu")
		(net "U403_ADD2")
	)
	(segment
		(start 42.692066 -134.269734)
		(end 42.692066 -133.622034)
		(width 0.2794)
		(layer "F.Cu")
		(net "U403_ADD2")
	)
	(via
		(at 42.46626 -134.49554)
		(size 0.508)
		(drill 0.254)
		(layers "F.Cu" "B.Cu")
		(net "U403_ADD2")
	)
	(segment
		(start 37.44595 -127.508)
		(end 36.879022 -128.074928)
		(width 0.2794)
		(layer "F.Cu")
		(net "FAN_3_TACH_IL_R1")
	)
	(segment
		(start 35.54095 -129.413)
		(end 35.3949 -129.55905)
		(width 0.1016)
		(layer "F.Cu")
		(net "FAN_3_TACH_IL_R1")
	)
	(segment
		(start 36.879022 -128.074928)
		(end 35.54095 -129.413)
		(width 0.2794)
		(layer "F.Cu")
		(net "FAN_3_TACH_IL_R1")
	)
	(segment
		(start 35.3949 -129.55905)
		(end 33.495996 -129.55905)
		(width 0.1016)
		(layer "F.Cu")
		(net "FAN_3_TACH_IL_R1")
	)
	(via
		(at 36.879022 -128.074928)
		(size 0.508)
		(drill 0.254)
		(layers "F.Cu" "B.Cu")
		(net "FAN_3_TACH_IL_R1")
	)
	(segment
		(start 34.919666 -128.31318)
		(end 36.658296 -126.57455)
		(width 0.2794)
		(layer "F.Cu")
		(net "FAN_3_PWM_R1")
	)
	(segment
		(start 34.473896 -128.75895)
		(end 34.919666 -128.31318)
		(width 0.1016)
		(layer "F.Cu")
		(net "FAN_3_PWM_R1")
	)
	(segment
		(start 33.495996 -128.75895)
		(end 34.473896 -128.75895)
		(width 0.1016)
		(layer "F.Cu")
		(net "FAN_3_PWM_R1")
	)
	(segment
		(start 36.658296 -125.755654)
		(end 37.44595 -124.968)
		(width 0.2794)
		(layer "F.Cu")
		(net "FAN_3_PWM_R1")
	)
	(segment
		(start 36.658296 -126.57455)
		(end 36.658296 -125.755654)
		(width 0.2794)
		(layer "F.Cu")
		(net "FAN_3_PWM_R1")
	)
	(via
		(at 36.658296 -126.57455)
		(size 0.508)
		(drill 0.254)
		(layers "F.Cu" "B.Cu")
		(net "FAN_3_PWM_R1")
	)
	(segment
		(start 37.4269 -123.698)
		(end 37.286946 -123.698)
		(width 0.2794)
		(layer "F.Cu")
		(net "FAN_3_TACH_OL_R1")
	)
	(segment
		(start 36.024566 -124.96038)
		(end 36.024566 -125.961394)
		(width 0.2794)
		(layer "F.Cu")
		(net "FAN_3_TACH_OL_R1")
	)
	(segment
		(start 35.91306 -126.456948)
		(end 34.831782 -127.538226)
		(width 0.2794)
		(layer "F.Cu")
		(net "FAN_3_TACH_OL_R1")
	)
	(segment
		(start 36.024566 -125.961394)
		(end 35.91306 -126.0729)
		(width 0.2794)
		(layer "F.Cu")
		(net "FAN_3_TACH_OL_R1")
	)
	(segment
		(start 37.286946 -123.698)
		(end 36.024566 -124.96038)
		(width 0.2794)
		(layer "F.Cu")
		(net "FAN_3_TACH_OL_R1")
	)
	(segment
		(start 35.91306 -126.0729)
		(end 35.91306 -126.456948)
		(width 0.2794)
		(layer "F.Cu")
		(net "FAN_3_TACH_OL_R1")
	)
	(segment
		(start 34.011108 -128.3589)
		(end 33.495996 -128.3589)
		(width 0.1016)
		(layer "F.Cu")
		(net "FAN_3_TACH_OL_R1")
	)
	(segment
		(start 34.831782 -127.538226)
		(end 34.011108 -128.3589)
		(width 0.1016)
		(layer "F.Cu")
		(net "FAN_3_TACH_OL_R1")
	)
	(via
		(at 35.91306 -126.0729)
		(size 0.762)
		(drill 0.381)
		(layers "F.Cu" "B.Cu")
		(net "FAN_3_TACH_OL_R1")
	)
	(segment
		(start 31.404052 -132.902198)
		(end 31.404052 -132.605272)
		(width 0.1016)
		(layer "F.Cu")
		(net "FAN_1_TACH_IL_R1")
	)
	(segment
		(start 33.055052 -135.128)
		(end 31.404052 -133.477)
		(width 0.2794)
		(layer "F.Cu")
		(net "FAN_1_TACH_IL_R1")
	)
	(segment
		(start 36.15182 -135.128)
		(end 33.055052 -135.128)
		(width 0.2794)
		(layer "F.Cu")
		(net "FAN_1_TACH_IL_R1")
	)
	(segment
		(start 31.496 -132.513324)
		(end 31.496 -131.158996)
		(width 0.1016)
		(layer "F.Cu")
		(net "FAN_1_TACH_IL_R1")
	)
	(segment
		(start 37.44595 -135.128)
		(end 36.15182 -135.128)
		(width 0.2794)
		(layer "F.Cu")
		(net "FAN_1_TACH_IL_R1")
	)
	(segment
		(start 31.404052 -133.477)
		(end 31.404052 -132.902198)
		(width 0.2794)
		(layer "F.Cu")
		(net "FAN_1_TACH_IL_R1")
	)
	(segment
		(start 31.404052 -132.605272)
		(end 31.496 -132.513324)
		(width 0.1016)
		(layer "F.Cu")
		(net "FAN_1_TACH_IL_R1")
	)
	(via
		(at 36.15182 -135.128)
		(size 0.762)
		(drill 0.381)
		(layers "F.Cu" "B.Cu")
		(net "FAN_1_TACH_IL_R1")
	)
	(segment
		(start 35.187128 -128.905)
		(end 37.44595 -126.646178)
		(width 0.2794)
		(layer "F.Cu")
		(net "FAN_2_TACH_OL_R1")
	)
	(segment
		(start 33.495996 -129.159)
		(end 34.933128 -129.159)
		(width 0.1016)
		(layer "F.Cu")
		(net "FAN_2_TACH_OL_R1")
	)
	(segment
		(start 34.933128 -129.159)
		(end 35.187128 -128.905)
		(width 0.1016)
		(layer "F.Cu")
		(net "FAN_2_TACH_OL_R1")
	)
	(segment
		(start 37.44595 -126.646178)
		(end 37.44595 -126.238)
		(width 0.2794)
		(layer "F.Cu")
		(net "FAN_2_TACH_OL_R1")
	)
	(via
		(at 35.187128 -128.905)
		(size 0.508)
		(drill 0.254)
		(layers "F.Cu" "B.Cu")
		(net "FAN_2_TACH_OL_R1")
	)
	(segment
		(start 19.47164 -131.158996)
		(end 19.755104 -131.158996)
		(width 0.1016)
		(layer "F.Cu")
		(net "TP_U330_XTAL1")
	)
	(segment
		(start 19.2151 -131.415536)
		(end 19.47164 -131.158996)
		(width 0.2794)
		(layer "F.Cu")
		(net "TP_U330_XTAL1")
	)
	(segment
		(start 19.2151 -131.51358)
		(end 19.2151 -131.415536)
		(width 0.2794)
		(layer "F.Cu")
		(net "TP_U330_XTAL1")
	)
	(via
		(at 19.2151 -131.51358)
		(size 0.508)
		(drill 0.254)
		(layers "F.Cu" "B.Cu")
		(net "TP_U330_XTAL1")
	)
	(segment
		(start 33.04032 -131.91744)
		(end 32.695896 -131.573016)
		(width 0.1016)
		(layer "F.Cu")
		(net "FAN_1_TACH_OL_R1")
	)
	(segment
		(start 34.68624 -131.91744)
		(end 33.04032 -131.91744)
		(width 0.2794)
		(layer "F.Cu")
		(net "FAN_1_TACH_OL_R1")
	)
	(segment
		(start 32.695896 -131.573016)
		(end 32.695896 -131.158996)
		(width 0.1016)
		(layer "F.Cu")
		(net "FAN_1_TACH_OL_R1")
	)
	(segment
		(start 37.44595 -131.318)
		(end 36.84651 -131.91744)
		(width 0.2794)
		(layer "F.Cu")
		(net "FAN_1_TACH_OL_R1")
	)
	(segment
		(start 36.84651 -131.91744)
		(end 34.68624 -131.91744)
		(width 0.2794)
		(layer "F.Cu")
		(net "FAN_1_TACH_OL_R1")
	)
	(via
		(at 34.68624 -131.91744)
		(size 0.762)
		(drill 0.381)
		(layers "F.Cu" "B.Cu")
		(net "FAN_1_TACH_OL_R1")
	)
	(segment
		(start 18.669 -132.334)
		(end 18.875248 -132.334)
		(width 0.1016)
		(layer "F.Cu")
		(net "TP_U330_XTAL2")
	)
	(segment
		(start 19.852894 -131.929124)
		(end 20.1549 -131.627118)
		(width 0.1016)
		(layer "F.Cu")
		(net "TP_U330_XTAL2")
	)
	(segment
		(start 20.1549 -131.627118)
		(end 20.1549 -131.158996)
		(width 0.1016)
		(layer "F.Cu")
		(net "TP_U330_XTAL2")
	)
	(segment
		(start 18.875248 -132.334)
		(end 19.852894 -131.929124)
		(width 0.1016)
		(layer "F.Cu")
		(net "TP_U330_XTAL2")
	)
	(via
		(at 18.669 -132.334)
		(size 0.762)
		(drill 0.381)
		(layers "F.Cu" "B.Cu")
		(net "TP_U330_XTAL2")
	)
	(segment
		(start 35.53206 -137.668)
		(end 33.655 -137.668)
		(width 0.2794)
		(layer "F.Cu")
		(net "FAN_0_PWM_R1")
	)
	(segment
		(start 30.235652 -132.624068)
		(end 30.6959 -132.16382)
		(width 0.1016)
		(layer "F.Cu")
		(net "FAN_0_PWM_R1")
	)
	(segment
		(start 30.235652 -134.248652)
		(end 30.235652 -132.902198)
		(width 0.2794)
		(layer "F.Cu")
		(net "FAN_0_PWM_R1")
	)
	(segment
		(start 33.655 -137.668)
		(end 30.235652 -134.248652)
		(width 0.2794)
		(layer "F.Cu")
		(net "FAN_0_PWM_R1")
	)
	(segment
		(start 30.6959 -132.16382)
		(end 30.6959 -131.158996)
		(width 0.1016)
		(layer "F.Cu")
		(net "FAN_0_PWM_R1")
	)
	(segment
		(start 37.4269 -137.668)
		(end 35.53206 -137.668)
		(width 0.2794)
		(layer "F.Cu")
		(net "FAN_0_PWM_R1")
	)
	(segment
		(start 30.235652 -132.902198)
		(end 30.235652 -132.624068)
		(width 0.1016)
		(layer "F.Cu")
		(net "FAN_0_PWM_R1")
	)
	(via
		(at 35.53206 -137.668)
		(size 0.762)
		(drill 0.381)
		(layers "F.Cu" "B.Cu")
		(net "FAN_0_PWM_R1")
	)
	(segment
		(start 33.841944 -126.619)
		(end 33.30194 -127.159004)
		(width 0.2794)
		(layer "F.Cu")
		(net "TP_U317_XTAL1")
	)
	(segment
		(start 33.30194 -127.159004)
		(end 32.695896 -127.159004)
		(width 0.1016)
		(layer "F.Cu")
		(net "TP_U317_XTAL1")
	)
	(segment
		(start 34.544 -126.619)
		(end 33.841944 -126.619)
		(width 0.2794)
		(layer "F.Cu")
		(net "TP_U317_XTAL1")
	)
	(via
		(at 34.544 -126.619)
		(size 0.762)
		(drill 0.381)
		(layers "F.Cu" "B.Cu")
		(net "TP_U317_XTAL1")
	)
	(segment
		(start 30.819852 -132.902198)
		(end 30.819852 -132.61467)
		(width 0.1016)
		(layer "F.Cu")
		(net "FAN_0_TACH_IL_R1")
	)
	(segment
		(start 34.39668 -136.398)
		(end 33.401 -136.398)
		(width 0.2794)
		(layer "F.Cu")
		(net "FAN_0_TACH_IL_R1")
	)
	(segment
		(start 33.401 -136.398)
		(end 30.819852 -133.816852)
		(width 0.2794)
		(layer "F.Cu")
		(net "FAN_0_TACH_IL_R1")
	)
	(segment
		(start 37.44595 -136.398)
		(end 34.39668 -136.398)
		(width 0.2794)
		(layer "F.Cu")
		(net "FAN_0_TACH_IL_R1")
	)
	(segment
		(start 30.819852 -133.816852)
		(end 30.819852 -132.902198)
		(width 0.2794)
		(layer "F.Cu")
		(net "FAN_0_TACH_IL_R1")
	)
	(segment
		(start 30.819852 -132.61467)
		(end 31.09595 -132.338572)
		(width 0.1016)
		(layer "F.Cu")
		(net "FAN_0_TACH_IL_R1")
	)
	(segment
		(start 31.09595 -132.338572)
		(end 31.09595 -131.158996)
		(width 0.1016)
		(layer "F.Cu")
		(net "FAN_0_TACH_IL_R1")
	)
	(via
		(at 34.39668 -136.398)
		(size 0.762)
		(drill 0.381)
		(layers "F.Cu" "B.Cu")
		(net "FAN_0_TACH_IL_R1")
	)
	(segment
		(start 33.24352 -126.38024)
		(end 33.76676 -125.857)
		(width 0.2794)
		(layer "F.Cu")
		(net "TP_U317_XTAL2")
	)
	(segment
		(start 33.76676 -125.857)
		(end 34.29 -125.857)
		(width 0.2794)
		(layer "F.Cu")
		(net "TP_U317_XTAL2")
	)
	(segment
		(start 32.2961 -126.73838)
		(end 32.65424 -126.38024)
		(width 0.1016)
		(layer "F.Cu")
		(net "TP_U317_XTAL2")
	)
	(segment
		(start 32.2961 -127.159004)
		(end 32.2961 -126.73838)
		(width 0.1016)
		(layer "F.Cu")
		(net "TP_U317_XTAL2")
	)
	(segment
		(start 32.65424 -126.38024)
		(end 33.24352 -126.38024)
		(width 0.1016)
		(layer "F.Cu")
		(net "TP_U317_XTAL2")
	)
	(segment
		(start 35.941 -124.206)
		(end 35.941 -123.825)
		(width 0.2794)
		(layer "F.Cu")
		(net "TP_U317_XTAL2")
	)
	(segment
		(start 34.29 -125.857)
		(end 35.941 -124.206)
		(width 0.2794)
		(layer "F.Cu")
		(net "TP_U317_XTAL2")
	)
	(via
		(at 35.941 -123.825)
		(size 0.762)
		(drill 0.381)
		(layers "F.Cu" "B.Cu")
		(net "TP_U317_XTAL2")
	)
	(segment
		(start 33.495996 -130.358896)
		(end 34.190178 -130.358896)
		(width 0.1016)
		(layer "F.Cu")
		(net "FAN_2_PWM_R1")
	)
	(segment
		(start 34.190178 -130.358896)
		(end 34.435796 -130.604514)
		(width 0.1016)
		(layer "F.Cu")
		(net "FAN_2_PWM_R1")
	)
	(segment
		(start 36.830254 -130.048)
		(end 36.27374 -130.604514)
		(width 0.2794)
		(layer "F.Cu")
		(net "FAN_2_PWM_R1")
	)
	(segment
		(start 35.237674 -130.604514)
		(end 35.31108 -130.67792)
		(width 0.2794)
		(layer "F.Cu")
		(net "FAN_2_PWM_R1")
	)
	(segment
		(start 35.384486 -130.604514)
		(end 35.31108 -130.67792)
		(width 0.2794)
		(layer "F.Cu")
		(net "FAN_2_PWM_R1")
	)
	(segment
		(start 36.27374 -130.604514)
		(end 35.384486 -130.604514)
		(width 0.2794)
		(layer "F.Cu")
		(net "FAN_2_PWM_R1")
	)
	(segment
		(start 37.44595 -130.048)
		(end 36.830254 -130.048)
		(width 0.2794)
		(layer "F.Cu")
		(net "FAN_2_PWM_R1")
	)
	(segment
		(start 34.435796 -130.604514)
		(end 35.237674 -130.604514)
		(width 0.2794)
		(layer "F.Cu")
		(net "FAN_2_PWM_R1")
	)
	(via
		(at 35.31108 -130.67792)
		(size 0.762)
		(drill 0.381)
		(layers "F.Cu" "B.Cu")
		(net "FAN_2_PWM_R1")
	)
	(segment
		(start 32.638746 -133.858)
		(end 31.988252 -133.207506)
		(width 0.2794)
		(layer "F.Cu")
		(net "FAN_0_TACH_OL_R1")
	)
	(segment
		(start 31.89605 -132.51307)
		(end 31.89605 -131.158996)
		(width 0.1016)
		(layer "F.Cu")
		(net "FAN_0_TACH_OL_R1")
	)
	(segment
		(start 37.44595 -133.858)
		(end 33.90138 -133.858)
		(width 0.2794)
		(layer "F.Cu")
		(net "FAN_0_TACH_OL_R1")
	)
	(segment
		(start 31.988252 -133.207506)
		(end 31.988252 -132.902198)
		(width 0.2794)
		(layer "F.Cu")
		(net "FAN_0_TACH_OL_R1")
	)
	(segment
		(start 31.988252 -132.605272)
		(end 31.89605 -132.51307)
		(width 0.1016)
		(layer "F.Cu")
		(net "FAN_0_TACH_OL_R1")
	)
	(segment
		(start 33.90138 -133.858)
		(end 32.638746 -133.858)
		(width 0.2794)
		(layer "F.Cu")
		(net "FAN_0_TACH_OL_R1")
	)
	(segment
		(start 31.988252 -132.902198)
		(end 31.988252 -132.605272)
		(width 0.1016)
		(layer "F.Cu")
		(net "FAN_0_TACH_OL_R1")
	)
	(via
		(at 33.90138 -133.858)
		(size 0.762)
		(drill 0.381)
		(layers "F.Cu" "B.Cu")
		(net "FAN_0_TACH_OL_R1")
	)
	(segment
		(start 37.44595 -128.778)
		(end 37.211254 -128.778)
		(width 0.2794)
		(layer "F.Cu")
		(net "FAN_2_TACH_IL_R1")
	)
	(segment
		(start 34.386012 -129.9591)
		(end 36.030154 -129.9591)
		(width 0.2794)
		(layer "F.Cu")
		(net "FAN_2_TACH_IL_R1")
	)
	(segment
		(start 37.211254 -128.778)
		(end 36.66109 -129.328164)
		(width 0.2794)
		(layer "F.Cu")
		(net "FAN_2_TACH_IL_R1")
	)
	(segment
		(start 33.495996 -129.9591)
		(end 34.386012 -129.9591)
		(width 0.1016)
		(layer "F.Cu")
		(net "FAN_2_TACH_IL_R1")
	)
	(segment
		(start 36.030154 -129.9591)
		(end 36.66109 -129.328164)
		(width 0.2794)
		(layer "F.Cu")
		(net "FAN_2_TACH_IL_R1")
	)
	(via
		(at 36.66109 -129.328164)
		(size 0.508)
		(drill 0.254)
		(layers "F.Cu" "B.Cu")
		(net "FAN_2_TACH_IL_R1")
	)
	(segment
		(start 47.151544 -134.439406)
		(end 47.85995 -133.731)
		(width 0.2794)
		(layer "F.Cu")
		(net "SMB_PDBV_FAN_R_U403_SCL")
	)
	(segment
		(start 45.191934 -133.622034)
		(end 45.712634 -133.622034)
		(width 0.2794)
		(layer "F.Cu")
		(net "SMB_PDBV_FAN_R_U403_SCL")
	)
	(segment
		(start 46.530006 -134.439406)
		(end 46.66488 -134.439406)
		(width 0.2794)
		(layer "F.Cu")
		(net "SMB_PDBV_FAN_R_U403_SCL")
	)
	(segment
		(start 45.712634 -133.622034)
		(end 46.530006 -134.439406)
		(width 0.2794)
		(layer "F.Cu")
		(net "SMB_PDBV_FAN_R_U403_SCL")
	)
	(segment
		(start 46.66488 -134.439406)
		(end 47.151544 -134.439406)
		(width 0.2794)
		(layer "F.Cu")
		(net "SMB_PDBV_FAN_R_U403_SCL")
	)
	(via
		(at 46.66488 -134.439406)
		(size 0.762)
		(drill 0.381)
		(layers "F.Cu" "B.Cu")
		(net "SMB_PDBV_FAN_R_U403_SCL")
	)
	(segment
		(start 37.44595 -132.588)
		(end 37.20211 -132.83184)
		(width 0.2794)
		(layer "F.Cu")
		(net "FAN_1_PWM_R1")
	)
	(segment
		(start 32.2961 -132.023358)
		(end 32.2961 -131.158996)
		(width 0.1016)
		(layer "F.Cu")
		(net "FAN_1_PWM_R1")
	)
	(segment
		(start 32.729932 -132.45719)
		(end 32.2961 -132.023358)
		(width 0.1016)
		(layer "F.Cu")
		(net "FAN_1_PWM_R1")
	)
	(segment
		(start 37.20211 -132.83184)
		(end 36.08324 -132.83184)
		(width 0.2794)
		(layer "F.Cu")
		(net "FAN_1_PWM_R1")
	)
	(segment
		(start 33.104582 -132.83184)
		(end 32.729932 -132.45719)
		(width 0.2794)
		(layer "F.Cu")
		(net "FAN_1_PWM_R1")
	)
	(segment
		(start 36.08324 -132.83184)
		(end 33.104582 -132.83184)
		(width 0.2794)
		(layer "F.Cu")
		(net "FAN_1_PWM_R1")
	)
	(via
		(at 36.08324 -132.83184)
		(size 0.762)
		(drill 0.381)
		(layers "F.Cu" "B.Cu")
		(net "FAN_1_PWM_R1")
	)
	(segment
		(start 46.02988 -135.63346)
		(end 46.02988 -134.80034)
		(width 0.2794)
		(layer "F.Cu")
		(net "SMB_PDBV_FAN_R_U403_SDA")
	)
	(segment
		(start 46.02988 -134.80034)
		(end 45.66539 -134.43585)
		(width 0.2794)
		(layer "F.Cu")
		(net "SMB_PDBV_FAN_R_U403_SDA")
	)
	(segment
		(start 47.4345 -135.128)
		(end 46.64964 -135.91286)
		(width 0.2794)
		(layer "F.Cu")
		(net "SMB_PDBV_FAN_R_U403_SDA")
	)
	(segment
		(start 47.85995 -135.128)
		(end 47.4345 -135.128)
		(width 0.2794)
		(layer "F.Cu")
		(net "SMB_PDBV_FAN_R_U403_SDA")
	)
	(segment
		(start 46.64964 -135.91286)
		(end 46.41342 -135.91286)
		(width 0.2794)
		(layer "F.Cu")
		(net "SMB_PDBV_FAN_R_U403_SDA")
	)
	(segment
		(start 45.66539 -134.43585)
		(end 45.03166 -134.43585)
		(width 0.2794)
		(layer "F.Cu")
		(net "SMB_PDBV_FAN_R_U403_SDA")
	)
	(segment
		(start 46.41342 -135.91286)
		(end 46.30928 -135.91286)
		(width 0.2794)
		(layer "F.Cu")
		(net "SMB_PDBV_FAN_R_U403_SDA")
	)
	(segment
		(start 45.03166 -134.43585)
		(end 44.692062 -134.096252)
		(width 0.2794)
		(layer "F.Cu")
		(net "SMB_PDBV_FAN_R_U403_SDA")
	)
	(segment
		(start 44.692062 -134.096252)
		(end 44.692062 -133.622034)
		(width 0.2794)
		(layer "F.Cu")
		(net "SMB_PDBV_FAN_R_U403_SDA")
	)
	(segment
		(start 46.30928 -135.91286)
		(end 46.02988 -135.63346)
		(width 0.2794)
		(layer "F.Cu")
		(net "SMB_PDBV_FAN_R_U403_SDA")
	)
	(via
		(at 46.41342 -135.91286)
		(size 0.762)
		(drill 0.381)
		(layers "F.Cu" "B.Cu")
		(net "SMB_PDBV_FAN_R_U403_SDA")
	)
	(segment
		(start 18.1102 -116.84)
		(end 18.288 -117.0178)
		(width 0.4572)
		(layer "F.Cu")
		(net "P52V_FAN_5")
	)
	(segment
		(start 19.9136 -105.41)
		(end 20.828 -105.41)
		(width 0.4572)
		(layer "F.Cu")
		(net "P52V_FAN_5")
	)
	(segment
		(start 18.288 -117.0178)
		(end 18.288 -117.6274)
		(width 0.4572)
		(layer "F.Cu")
		(net "P52V_FAN_5")
	)
	(via
		(at 13.462 -88.518238)
		(size 0.508)
		(drill 0.254)
		(layers "F.Cu" "B.Cu")
		(net "P52V_FAN_5")
	)
	(via
		(at 4.445 -91.116912)
		(size 0.508)
		(drill 0.254)
		(layers "F.Cu" "B.Cu")
		(net "P52V_FAN_5")
	)
	(via
		(at 15.15999 -80.521048)
		(size 0.508)
		(drill 0.254)
		(layers "F.Cu" "B.Cu")
		(net "P52V_FAN_5")
	)
	(via
		(at 10.16 -85.0138)
		(size 0.6604)
		(drill 0.3302)
		(layers "F.Cu" "B.Cu")
		(net "P52V_FAN_5")
	)
	(via
		(at 13.462 -93.344238)
		(size 0.508)
		(drill 0.254)
		(layers "F.Cu" "B.Cu")
		(net "P52V_FAN_5")
	)
	(via
		(at 13.462 -93.979238)
		(size 0.508)
		(drill 0.254)
		(layers "F.Cu" "B.Cu")
		(net "P52V_FAN_5")
	)
	(via
		(at 15.81531 -79.886048)
		(size 0.508)
		(drill 0.254)
		(layers "F.Cu" "B.Cu")
		(net "P52V_FAN_5")
	)
	(via
		(at 5.969 -91.116912)
		(size 0.508)
		(drill 0.254)
		(layers "F.Cu" "B.Cu")
		(net "P52V_FAN_5")
	)
	(via
		(at 13.462 -92.709238)
		(size 0.508)
		(drill 0.254)
		(layers "F.Cu" "B.Cu")
		(net "P52V_FAN_5")
	)
	(via
		(at 4.445 -91.878912)
		(size 0.762)
		(drill 0.254)
		(layers "F.Cu" "B.Cu")
		(net "P52V_FAN_5")
	)
	(via
		(at 5.207 -91.116912)
		(size 0.508)
		(drill 0.254)
		(layers "F.Cu" "B.Cu")
		(net "P52V_FAN_5")
	)
	(via
		(at 5.207 -91.878912)
		(size 0.508)
		(drill 0.254)
		(layers "F.Cu" "B.Cu")
		(net "P52V_FAN_5")
	)
	(via
		(at 16.45031 -79.886048)
		(size 0.508)
		(drill 0.254)
		(layers "F.Cu" "B.Cu")
		(net "P52V_FAN_5")
	)
	(via
		(at 13.462 -87.883238)
		(size 0.508)
		(drill 0.254)
		(layers "F.Cu" "B.Cu")
		(net "P52V_FAN_5")
	)
	(via
		(at 15.80515 -80.521048)
		(size 0.508)
		(drill 0.254)
		(layers "F.Cu" "B.Cu")
		(net "P52V_FAN_5")
	)
	(via
		(at 16.45031 -80.521048)
		(size 0.508)
		(drill 0.254)
		(layers "F.Cu" "B.Cu")
		(net "P52V_FAN_5")
	)
	(via
		(at 18.1102 -116.84)
		(size 0.508)
		(drill 0.254)
		(layers "F.Cu" "B.Cu")
		(net "P52V_FAN_5")
	)
	(via
		(at 15.15999 -79.886048)
		(size 0.508)
		(drill 0.254)
		(layers "F.Cu" "B.Cu")
		(net "P52V_FAN_5")
	)
	(via
		(at 14.1478 -86.995)
		(size 0.508)
		(drill 0.254)
		(layers "F.Cu" "B.Cu")
		(net "P52V_FAN_5")
	)
	(via
		(at 5.969 -91.878912)
		(size 0.508)
		(drill 0.254)
		(layers "F.Cu" "B.Cu")
		(net "P52V_FAN_5")
	)
	(via
		(at 6.731 -91.878912)
		(size 0.762)
		(drill 0.254)
		(layers "F.Cu" "B.Cu")
		(net "P52V_FAN_5")
	)
	(via
		(at 6.731 -91.116912)
		(size 0.508)
		(drill 0.254)
		(layers "F.Cu" "B.Cu")
		(net "P52V_FAN_5")
	)
	(via
		(at 13.462 -89.153238)
		(size 0.508)
		(drill 0.254)
		(layers "F.Cu" "B.Cu")
		(net "P52V_FAN_5")
	)
	(via
		(at 20.828 -105.41)
		(size 0.508)
		(drill 0.254)
		(layers "F.Cu" "B.Cu")
		(net "P52V_FAN_5")
	)
	(segment
		(start 20.828 -105.41)
		(end 19.304 -105.41)
		(width 0.4572)
		(layer "B.Cu")
		(net "P52V_FAN_5")
	)
	(segment
		(start 3.859276 -114.709956)
		(end 6.700012 -114.709956)
		(width 1.3716)
		(layer "B.Cu")
		(net "P52V_FAN_5")
	)
	(segment
		(start 13.54328 -117.602)
		(end 12.37996 -116.43868)
		(width 0.4572)
		(layer "B.Cu")
		(net "P52V_FAN_5")
	)
	(segment
		(start 17.114012 -103.220012)
		(end 12.705588 -103.220012)
		(width 0.4572)
		(layer "B.Cu")
		(net "P52V_FAN_5")
	)
	(segment
		(start 11.66114 -112.70996)
		(end 8.700008 -112.70996)
		(width 1.3716)
		(layer "B.Cu")
		(net "P52V_FAN_5")
	)
	(segment
		(start 18.1102 -116.84)
		(end 17.8562 -116.586)
		(width 0.4572)
		(layer "B.Cu")
		(net "P52V_FAN_5")
	)
	(segment
		(start 15.494 -117.602)
		(end 13.54328 -117.602)
		(width 0.4572)
		(layer "B.Cu")
		(net "P52V_FAN_5")
	)
	(segment
		(start 3.8227 -114.67338)
		(end 3.859276 -114.709956)
		(width 1.3716)
		(layer "B.Cu")
		(net "P52V_FAN_5")
	)
	(segment
		(start 11.66622 -112.70488)
		(end 11.66114 -112.70996)
		(width 1.3716)
		(layer "B.Cu")
		(net "P52V_FAN_5")
	)
	(segment
		(start 16.51 -116.586)
		(end 15.494 -117.602)
		(width 0.4572)
		(layer "B.Cu")
		(net "P52V_FAN_5")
	)
	(segment
		(start 19.304 -105.41)
		(end 17.114012 -103.220012)
		(width 0.4572)
		(layer "B.Cu")
		(net "P52V_FAN_5")
	)
	(segment
		(start 17.8562 -116.586)
		(end 16.51 -116.586)
		(width 0.4572)
		(layer "B.Cu")
		(net "P52V_FAN_5")
	)
	(segment
		(start 19.4056 -288.036)
		(end 20.193 -288.036)
		(width 0.4572)
		(layer "F.Cu")
		(net "P52V_FAN_7")
	)
	(segment
		(start 19.4056 -302.514)
		(end 19.4056 -301.7774)
		(width 0.4572)
		(layer "F.Cu")
		(net "P52V_FAN_7")
	)
	(via
		(at 14.1478 -273.273012)
		(size 0.508)
		(drill 0.254)
		(layers "F.Cu" "B.Cu")
		(net "P52V_FAN_7")
	)
	(via
		(at 15.94231 -264.486136)
		(size 0.508)
		(drill 0.254)
		(layers "F.Cu" "B.Cu")
		(net "P52V_FAN_7")
	)
	(via
		(at 16.57731 -264.486136)
		(size 0.508)
		(drill 0.254)
		(layers "F.Cu" "B.Cu")
		(net "P52V_FAN_7")
	)
	(via
		(at 5.588 -281.2542)
		(size 0.508)
		(drill 0.254)
		(layers "F.Cu" "B.Cu")
		(net "P52V_FAN_7")
	)
	(via
		(at 16.57731 -265.121136)
		(size 0.508)
		(drill 0.254)
		(layers "F.Cu" "B.Cu")
		(net "P52V_FAN_7")
	)
	(via
		(at 15.28699 -265.121136)
		(size 0.508)
		(drill 0.254)
		(layers "F.Cu" "B.Cu")
		(net "P52V_FAN_7")
	)
	(via
		(at 14.148054 -271.386046)
		(size 0.508)
		(drill 0.254)
		(layers "F.Cu" "B.Cu")
		(net "P52V_FAN_7")
	)
	(via
		(at 14.13129 -277.895304)
		(size 0.508)
		(drill 0.254)
		(layers "F.Cu" "B.Cu")
		(net "P52V_FAN_7")
	)
	(via
		(at 15.501366 -269.428468)
		(size 0.508)
		(drill 0.254)
		(layers "F.Cu" "B.Cu")
		(net "P52V_FAN_7")
	)
	(via
		(at 4.826 -280.4922)
		(size 0.508)
		(drill 0.254)
		(layers "F.Cu" "B.Cu")
		(net "P52V_FAN_7")
	)
	(via
		(at 4.826 -281.2542)
		(size 0.508)
		(drill 0.254)
		(layers "F.Cu" "B.Cu")
		(net "P52V_FAN_7")
	)
	(via
		(at 14.1478 -274.139406)
		(size 0.508)
		(drill 0.254)
		(layers "F.Cu" "B.Cu")
		(net "P52V_FAN_7")
	)
	(via
		(at 5.588 -280.4922)
		(size 0.508)
		(drill 0.254)
		(layers "F.Cu" "B.Cu")
		(net "P52V_FAN_7")
	)
	(via
		(at 14.148054 -272.25244)
		(size 0.508)
		(drill 0.254)
		(layers "F.Cu" "B.Cu")
		(net "P52V_FAN_7")
	)
	(via
		(at 15.93215 -265.121136)
		(size 0.508)
		(drill 0.254)
		(layers "F.Cu" "B.Cu")
		(net "P52V_FAN_7")
	)
	(via
		(at 15.501366 -270.294862)
		(size 0.508)
		(drill 0.254)
		(layers "F.Cu" "B.Cu")
		(net "P52V_FAN_7")
	)
	(via
		(at 19.4056 -301.7774)
		(size 0.508)
		(drill 0.254)
		(layers "F.Cu" "B.Cu")
		(net "P52V_FAN_7")
	)
	(via
		(at 14.13129 -277.02891)
		(size 0.508)
		(drill 0.254)
		(layers "F.Cu" "B.Cu")
		(net "P52V_FAN_7")
	)
	(via
		(at 6.35 -281.2542)
		(size 0.508)
		(drill 0.254)
		(layers "F.Cu" "B.Cu")
		(net "P52V_FAN_7")
	)
	(via
		(at 15.28699 -264.486136)
		(size 0.508)
		(drill 0.254)
		(layers "F.Cu" "B.Cu")
		(net "P52V_FAN_7")
	)
	(via
		(at 6.35 -280.4922)
		(size 0.762)
		(drill 0.254)
		(layers "F.Cu" "B.Cu")
		(net "P52V_FAN_7")
	)
	(via
		(at 20.193 -288.036)
		(size 0.508)
		(drill 0.254)
		(layers "F.Cu" "B.Cu")
		(net "P52V_FAN_7")
	)
	(segment
		(start 3.786124 -299.310044)
		(end 6.700012 -299.310044)
		(width 1.3716)
		(layer "B.Cu")
		(net "P52V_FAN_7")
	)
	(segment
		(start 8.700008 -297.310048)
		(end 12.372848 -297.310048)
		(width 1.3716)
		(layer "B.Cu")
		(net "P52V_FAN_7")
	)
	(segment
		(start 12.6238 -288.036)
		(end 20.193 -288.036)
		(width 0.4572)
		(layer "B.Cu")
		(net "P52V_FAN_7")
	)
	(segment
		(start 19.4056 -301.7774)
		(end 12.74318 -301.7774)
		(width 0.4572)
		(layer "B.Cu")
		(net "P52V_FAN_7")
	)
	(segment
		(start 19.5326 -210.439)
		(end 20.32 -210.439)
		(width 0.4572)
		(layer "F.Cu")
		(net "P52V_FAN_6")
	)
	(segment
		(start 19.6596 -196.85)
		(end 19.6596 -197.612)
		(width 0.4572)
		(layer "F.Cu")
		(net "P52V_FAN_6")
	)
	(via
		(at 4.340098 -243.513864)
		(size 0.508)
		(drill 0.254)
		(layers "F.Cu" "B.Cu")
		(net "P52V_FAN_6")
	)
	(via
		(at 3.705098 -243.513864)
		(size 0.508)
		(drill 0.254)
		(layers "F.Cu" "B.Cu")
		(net "P52V_FAN_6")
	)
	(via
		(at 4.350258 -242.878864)
		(size 0.508)
		(drill 0.254)
		(layers "F.Cu" "B.Cu")
		(net "P52V_FAN_6")
	)
	(via
		(at 12.905232 -223.62541)
		(size 0.508)
		(drill 0.254)
		(layers "F.Cu" "B.Cu")
		(net "P52V_FAN_6")
	)
	(via
		(at 7.007098 -238.20501)
		(size 0.762)
		(drill 0.254)
		(layers "F.Cu" "B.Cu")
		(net "P52V_FAN_6")
	)
	(via
		(at 8.28675 -235.773214)
		(size 0.508)
		(drill 0.254)
		(layers "F.Cu" "B.Cu")
		(net "P52V_FAN_6")
	)
	(via
		(at 12.905232 -224.38741)
		(size 0.508)
		(drill 0.254)
		(layers "F.Cu" "B.Cu")
		(net "P52V_FAN_6")
	)
	(via
		(at 12.270232 -224.38741)
		(size 0.508)
		(drill 0.254)
		(layers "F.Cu" "B.Cu")
		(net "P52V_FAN_6")
	)
	(via
		(at 7.007098 -237.44301)
		(size 0.508)
		(drill 0.254)
		(layers "F.Cu" "B.Cu")
		(net "P52V_FAN_6")
	)
	(via
		(at 12.270232 -223.62541)
		(size 0.508)
		(drill 0.254)
		(layers "F.Cu" "B.Cu")
		(net "P52V_FAN_6")
	)
	(via
		(at 3.705098 -242.878864)
		(size 0.508)
		(drill 0.254)
		(layers "F.Cu" "B.Cu")
		(net "P52V_FAN_6")
	)
	(via
		(at 8.33755 -233.131614)
		(size 0.508)
		(drill 0.254)
		(layers "F.Cu" "B.Cu")
		(net "P52V_FAN_6")
	)
	(via
		(at 8.33755 -232.369614)
		(size 0.508)
		(drill 0.254)
		(layers "F.Cu" "B.Cu")
		(net "P52V_FAN_6")
	)
	(via
		(at 19.6596 -196.85)
		(size 0.508)
		(drill 0.254)
		(layers "F.Cu" "B.Cu")
		(net "P52V_FAN_6")
	)
	(via
		(at 8.28675 -235.011214)
		(size 0.508)
		(drill 0.254)
		(layers "F.Cu" "B.Cu")
		(net "P52V_FAN_6")
	)
	(via
		(at 4.995418 -242.878864)
		(size 0.508)
		(drill 0.254)
		(layers "F.Cu" "B.Cu")
		(net "P52V_FAN_6")
	)
	(via
		(at 12.905232 -222.86341)
		(size 0.508)
		(drill 0.254)
		(layers "F.Cu" "B.Cu")
		(net "P52V_FAN_6")
	)
	(via
		(at 4.995418 -243.513864)
		(size 0.508)
		(drill 0.254)
		(layers "F.Cu" "B.Cu")
		(net "P52V_FAN_6")
	)
	(via
		(at 16.383 -239.649)
		(size 0.6604)
		(drill 0.3302)
		(layers "F.Cu" "B.Cu")
		(net "P52V_FAN_6")
	)
	(via
		(at 20.32 -210.439)
		(size 0.508)
		(drill 0.254)
		(layers "F.Cu" "B.Cu")
		(net "P52V_FAN_6")
	)
	(via
		(at 8.26135 -230.439214)
		(size 0.508)
		(drill 0.254)
		(layers "F.Cu" "B.Cu")
		(net "P52V_FAN_6")
	)
	(via
		(at 8.26135 -229.677214)
		(size 0.508)
		(drill 0.254)
		(layers "F.Cu" "B.Cu")
		(net "P52V_FAN_6")
	)
	(via
		(at 12.270232 -222.86341)
		(size 0.508)
		(drill 0.254)
		(layers "F.Cu" "B.Cu")
		(net "P52V_FAN_6")
	)
	(segment
		(start 11.57732 -205.572868)
		(end 12.4968 -204.653388)
		(width 1.3716)
		(layer "B.Cu")
		(net "P52V_FAN_6")
	)
	(segment
		(start 19.375628 -210.439)
		(end 20.32 -210.439)
		(width 0.4572)
		(layer "B.Cu")
		(net "P52V_FAN_6")
	)
	(segment
		(start 13.344144 -200.142856)
		(end 17.972532 -200.142856)
		(width 0.4572)
		(layer "B.Cu")
		(net "P52V_FAN_6")
	)
	(segment
		(start 6.700012 -207.01)
		(end 3.99288 -207.01)
		(width 1.3716)
		(layer "B.Cu")
		(net "P52V_FAN_6")
	)
	(segment
		(start 11.014456 -205.010004)
		(end 11.57732 -205.572868)
		(width 1.3716)
		(layer "B.Cu")
		(net "P52V_FAN_6")
	)
	(segment
		(start 18.669 -199.446388)
		(end 18.669 -197.8406)
		(width 0.4572)
		(layer "B.Cu")
		(net "P52V_FAN_6")
	)
	(segment
		(start 12.4968 -202.3872)
		(end 12.4968 -200.9902)
		(width 0.4572)
		(layer "B.Cu")
		(net "P52V_FAN_6")
	)
	(segment
		(start 17.972532 -200.142856)
		(end 18.669 -199.446388)
		(width 0.4572)
		(layer "B.Cu")
		(net "P52V_FAN_6")
	)
	(segment
		(start 12.4968 -204.653388)
		(end 12.4968 -202.3872)
		(width 1.3716)
		(layer "B.Cu")
		(net "P52V_FAN_6")
	)
	(segment
		(start 11.57732 -205.572868)
		(end 11.57732 -207.95488)
		(width 1.3716)
		(layer "B.Cu")
		(net "P52V_FAN_6")
	)
	(segment
		(start 11.66241 -218.152218)
		(end 19.375628 -210.439)
		(width 0.4572)
		(layer "B.Cu")
		(net "P52V_FAN_6")
	)
	(segment
		(start 11.66241 -218.152218)
		(end 11.59891 -218.215718)
		(width 0.4572)
		(layer "B.Cu")
		(net "P52V_FAN_6")
	)
	(segment
		(start 14.30782 -210.68538)
		(end 14.30782 -214.33282)
		(width 1.3716)
		(layer "B.Cu")
		(net "P52V_FAN_6")
	)
	(segment
		(start 18.669 -197.8406)
		(end 19.6596 -196.85)
		(width 0.4572)
		(layer "B.Cu")
		(net "P52V_FAN_6")
	)
	(segment
		(start 12.4968 -200.9902)
		(end 13.344144 -200.142856)
		(width 0.4572)
		(layer "B.Cu")
		(net "P52V_FAN_6")
	)
	(segment
		(start 8.700008 -205.010004)
		(end 11.014456 -205.010004)
		(width 1.3716)
		(layer "B.Cu")
		(net "P52V_FAN_6")
	)
	(segment
		(start 11.57732 -207.95488)
		(end 14.30782 -210.68538)
		(width 1.3716)
		(layer "B.Cu")
		(net "P52V_FAN_6")
	)
	(segment
		(start 20.447 -18.796)
		(end 20.447 -16.6624)
		(width 0.4572)
		(layer "F.Cu")
		(net "P52V_FAN_4")
	)
	(segment
		(start 19.492722 -30.353)
		(end 19.492722 -29.591)
		(width 0.4572)
		(layer "F.Cu")
		(net "P52V_FAN_4")
	)
	(segment
		(start 20.447 -16.6624)
		(end 19.7866 -16.002)
		(width 0.4572)
		(layer "F.Cu")
		(net "P52V_FAN_4")
	)
	(via
		(at 12.039346 -38.649656)
		(size 0.508)
		(drill 0.254)
		(layers "F.Cu" "B.Cu")
		(net "P52V_FAN_4")
	)
	(via
		(at 4.350258 -58.278776)
		(size 0.508)
		(drill 0.254)
		(layers "F.Cu" "B.Cu")
		(net "P52V_FAN_4")
	)
	(via
		(at 11.299698 -44.263056)
		(size 0.508)
		(drill 0.254)
		(layers "F.Cu" "B.Cu")
		(net "P52V_FAN_4")
	)
	(via
		(at 7.414514 -53.448712)
		(size 0.762)
		(drill 0.254)
		(layers "F.Cu" "B.Cu")
		(net "P52V_FAN_4")
	)
	(via
		(at 11.277346 -38.014656)
		(size 0.508)
		(drill 0.254)
		(layers "F.Cu" "B.Cu")
		(net "P52V_FAN_4")
	)
	(via
		(at 4.995418 -58.913776)
		(size 0.508)
		(drill 0.254)
		(layers "F.Cu" "B.Cu")
		(net "P52V_FAN_4")
	)
	(via
		(at 8.774176 -48.90516)
		(size 0.762)
		(drill 0.254)
		(layers "F.Cu" "B.Cu")
		(net "P52V_FAN_4")
	)
	(via
		(at 8.73252 -45.629322)
		(size 0.508)
		(drill 0.254)
		(layers "F.Cu" "B.Cu")
		(net "P52V_FAN_4")
	)
	(via
		(at 8.75792 -51.369722)
		(size 0.762)
		(drill 0.254)
		(layers "F.Cu" "B.Cu")
		(net "P52V_FAN_4")
	)
	(via
		(at 12.061698 -43.501056)
		(size 0.508)
		(drill 0.254)
		(layers "F.Cu" "B.Cu")
		(net "P52V_FAN_4")
	)
	(via
		(at 19.492722 -29.591)
		(size 0.508)
		(drill 0.254)
		(layers "F.Cu" "B.Cu")
		(net "P52V_FAN_4")
	)
	(via
		(at 11.277346 -37.303456)
		(size 0.508)
		(drill 0.254)
		(layers "F.Cu" "B.Cu")
		(net "P52V_FAN_4")
	)
	(via
		(at 8.774176 -48.14316)
		(size 0.508)
		(drill 0.254)
		(layers "F.Cu" "B.Cu")
		(net "P52V_FAN_4")
	)
	(via
		(at 7.414514 -52.686712)
		(size 0.508)
		(drill 0.254)
		(layers "F.Cu" "B.Cu")
		(net "P52V_FAN_4")
	)
	(via
		(at 12.061698 -44.263056)
		(size 0.508)
		(drill 0.254)
		(layers "F.Cu" "B.Cu")
		(net "P52V_FAN_4")
	)
	(via
		(at 8.73252 -46.391322)
		(size 0.508)
		(drill 0.254)
		(layers "F.Cu" "B.Cu")
		(net "P52V_FAN_4")
	)
	(via
		(at 4.340098 -58.913776)
		(size 0.508)
		(drill 0.254)
		(layers "F.Cu" "B.Cu")
		(net "P52V_FAN_4")
	)
	(via
		(at 12.039346 -38.014656)
		(size 0.508)
		(drill 0.254)
		(layers "F.Cu" "B.Cu")
		(net "P52V_FAN_4")
	)
	(via
		(at 8.75792 -50.607722)
		(size 0.508)
		(drill 0.254)
		(layers "F.Cu" "B.Cu")
		(net "P52V_FAN_4")
	)
	(via
		(at 16.764 -55.0672)
		(size 0.6604)
		(drill 0.3302)
		(layers "F.Cu" "B.Cu")
		(net "P52V_FAN_4")
	)
	(via
		(at 3.705098 -58.913776)
		(size 0.508)
		(drill 0.254)
		(layers "F.Cu" "B.Cu")
		(net "P52V_FAN_4")
	)
	(via
		(at 20.447 -18.796)
		(size 0.508)
		(drill 0.254)
		(layers "F.Cu" "B.Cu")
		(net "P52V_FAN_4")
	)
	(via
		(at 11.277346 -38.649656)
		(size 0.508)
		(drill 0.254)
		(layers "F.Cu" "B.Cu")
		(net "P52V_FAN_4")
	)
	(via
		(at 11.299698 -43.501056)
		(size 0.508)
		(drill 0.254)
		(layers "F.Cu" "B.Cu")
		(net "P52V_FAN_4")
	)
	(via
		(at 3.705098 -58.278776)
		(size 0.508)
		(drill 0.254)
		(layers "F.Cu" "B.Cu")
		(net "P52V_FAN_4")
	)
	(via
		(at 4.995418 -58.278776)
		(size 0.508)
		(drill 0.254)
		(layers "F.Cu" "B.Cu")
		(net "P52V_FAN_4")
	)
	(via
		(at 12.039346 -37.303456)
		(size 0.508)
		(drill 0.254)
		(layers "F.Cu" "B.Cu")
		(net "P52V_FAN_4")
	)
	(segment
		(start 12.97686 -19.1135)
		(end 15.6845 -19.1135)
		(width 0.4572)
		(layer "B.Cu")
		(net "P52V_FAN_4")
	)
	(segment
		(start 19.111722 -29.972)
		(end 12.954 -29.972)
		(width 0.4572)
		(layer "B.Cu")
		(net "P52V_FAN_4")
	)
	(segment
		(start 19.304 -21.336)
		(end 20.447 -20.193)
		(width 0.4572)
		(layer "B.Cu")
		(net "P52V_FAN_4")
	)
	(segment
		(start 17.907 -21.336)
		(end 19.304 -21.336)
		(width 0.4572)
		(layer "B.Cu")
		(net "P52V_FAN_4")
	)
	(segment
		(start 20.447 -20.193)
		(end 20.447 -18.796)
		(width 0.4572)
		(layer "B.Cu")
		(net "P52V_FAN_4")
	)
	(segment
		(start 11.69162 -20.39874)
		(end 11.680444 -20.409916)
		(width 1.3716)
		(layer "B.Cu")
		(net "P52V_FAN_4")
	)
	(segment
		(start 3.8227 -22.4155)
		(end 3.828288 -22.409912)
		(width 1.3716)
		(layer "B.Cu")
		(net "P52V_FAN_4")
	)
	(segment
		(start 3.828288 -22.409912)
		(end 6.700012 -22.409912)
		(width 1.3716)
		(layer "B.Cu")
		(net "P52V_FAN_4")
	)
	(segment
		(start 15.6845 -19.1135)
		(end 17.907 -21.336)
		(width 0.4572)
		(layer "B.Cu")
		(net "P52V_FAN_4")
	)
	(segment
		(start 11.680444 -20.409916)
		(end 8.700008 -20.409916)
		(width 1.3716)
		(layer "B.Cu")
		(net "P52V_FAN_4")
	)
	(segment
		(start 19.492722 -29.591)
		(end 19.111722 -29.972)
		(width 0.4572)
		(layer "B.Cu")
		(net "P52V_FAN_4")
	)
	(segment
		(start 31.115 -26.6954)
		(end 31.115 -25.908)
		(width 0.4572)
		(layer "F.Cu")
		(net "P52V_FAN_3")
	)
	(segment
		(start 31.369 -15.113)
		(end 32.1564 -15.113)
		(width 0.4572)
		(layer "F.Cu")
		(net "P52V_FAN_3")
	)
	(via
		(at 31.369 -15.113)
		(size 0.508)
		(drill 0.254)
		(layers "F.Cu" "B.Cu")
		(net "P52V_FAN_3")
	)
	(via
		(at 38.014656 -43.546522)
		(size 0.508)
		(drill 0.254)
		(layers "F.Cu" "B.Cu")
		(net "P52V_FAN_3")
	)
	(via
		(at 42.815256 -54.493922)
		(size 0.508)
		(drill 0.254)
		(layers "F.Cu" "B.Cu")
		(net "P52V_FAN_3")
	)
	(via
		(at 38.014656 -44.308522)
		(size 0.508)
		(drill 0.254)
		(layers "F.Cu" "B.Cu")
		(net "P52V_FAN_3")
	)
	(via
		(at 36.412932 -58.278776)
		(size 0.508)
		(drill 0.254)
		(layers "F.Cu" "B.Cu")
		(net "P52V_FAN_3")
	)
	(via
		(at 35.767772 -58.278776)
		(size 0.508)
		(drill 0.254)
		(layers "F.Cu" "B.Cu")
		(net "P52V_FAN_3")
	)
	(via
		(at 40.9194 -54.991)
		(size 0.6604)
		(drill 0.3302)
		(layers "F.Cu" "B.Cu")
		(net "P52V_FAN_3")
	)
	(via
		(at 42.815256 -55.255922)
		(size 0.508)
		(drill 0.254)
		(layers "F.Cu" "B.Cu")
		(net "P52V_FAN_3")
	)
	(via
		(at 38.500304 -37.883846)
		(size 0.508)
		(drill 0.254)
		(layers "F.Cu" "B.Cu")
		(net "P52V_FAN_3")
	)
	(via
		(at 38.500304 -37.248846)
		(size 0.508)
		(drill 0.254)
		(layers "F.Cu" "B.Cu")
		(net "P52V_FAN_3")
	)
	(via
		(at 38.014656 -42.784522)
		(size 0.508)
		(drill 0.254)
		(layers "F.Cu" "B.Cu")
		(net "P52V_FAN_3")
	)
	(via
		(at 41.951656 -47.280322)
		(size 0.508)
		(drill 0.254)
		(layers "F.Cu" "B.Cu")
		(net "P52V_FAN_3")
	)
	(via
		(at 35.102292 -58.913776)
		(size 0.508)
		(drill 0.254)
		(layers "F.Cu" "B.Cu")
		(net "P52V_FAN_3")
	)
	(via
		(at 37.738304 -37.883846)
		(size 0.508)
		(drill 0.254)
		(layers "F.Cu" "B.Cu")
		(net "P52V_FAN_3")
	)
	(via
		(at 35.757612 -58.913776)
		(size 0.508)
		(drill 0.254)
		(layers "F.Cu" "B.Cu")
		(net "P52V_FAN_3")
	)
	(via
		(at 41.875456 -52.182522)
		(size 0.508)
		(drill 0.254)
		(layers "F.Cu" "B.Cu")
		(net "P52V_FAN_3")
	)
	(via
		(at 39.262304 -37.248846)
		(size 0.508)
		(drill 0.254)
		(layers "F.Cu" "B.Cu")
		(net "P52V_FAN_3")
	)
	(via
		(at 39.262304 -37.883846)
		(size 0.508)
		(drill 0.254)
		(layers "F.Cu" "B.Cu")
		(net "P52V_FAN_3")
	)
	(via
		(at 41.900856 -49.921922)
		(size 0.508)
		(drill 0.254)
		(layers "F.Cu" "B.Cu")
		(net "P52V_FAN_3")
	)
	(via
		(at 38.014656 -42.022522)
		(size 0.508)
		(drill 0.254)
		(layers "F.Cu" "B.Cu")
		(net "P52V_FAN_3")
	)
	(via
		(at 41.951656 -48.042322)
		(size 0.762)
		(drill 0.254)
		(layers "F.Cu" "B.Cu")
		(net "P52V_FAN_3")
	)
	(via
		(at 35.112452 -58.278776)
		(size 0.508)
		(drill 0.254)
		(layers "F.Cu" "B.Cu")
		(net "P52V_FAN_3")
	)
	(via
		(at 41.875456 -52.944522)
		(size 0.762)
		(drill 0.254)
		(layers "F.Cu" "B.Cu")
		(net "P52V_FAN_3")
	)
	(via
		(at 31.115 -25.908)
		(size 0.508)
		(drill 0.254)
		(layers "F.Cu" "B.Cu")
		(net "P52V_FAN_3")
	)
	(via
		(at 36.412932 -58.913776)
		(size 0.508)
		(drill 0.254)
		(layers "F.Cu" "B.Cu")
		(net "P52V_FAN_3")
	)
	(via
		(at 37.738304 -37.248846)
		(size 0.508)
		(drill 0.254)
		(layers "F.Cu" "B.Cu")
		(net "P52V_FAN_3")
	)
	(via
		(at 41.900856 -50.683922)
		(size 0.762)
		(drill 0.254)
		(layers "F.Cu" "B.Cu")
		(net "P52V_FAN_3")
	)
	(segment
		(start 32.385 -22.225)
		(end 38.989 -22.225)
		(width 0.4572)
		(layer "B.Cu")
		(net "P52V_FAN_3")
	)
	(segment
		(start 31.369 -15.113)
		(end 32.512 -16.256)
		(width 0.4572)
		(layer "B.Cu")
		(net "P52V_FAN_3")
	)
	(segment
		(start 40.27932 -18.40992)
		(end 42.999914 -18.40992)
		(width 1.3716)
		(layer "B.Cu")
		(net "P52V_FAN_3")
	)
	(segment
		(start 38.1254 -16.256)
		(end 40.27932 -18.40992)
		(width 0.4572)
		(layer "B.Cu")
		(net "P52V_FAN_3")
	)
	(segment
		(start 47.81296 -16.56588)
		(end 47.657004 -16.409924)
		(width 1.3716)
		(layer "B.Cu")
		(net "P52V_FAN_3")
	)
	(segment
		(start 32.512 -16.256)
		(end 38.1254 -16.256)
		(width 0.4572)
		(layer "B.Cu")
		(net "P52V_FAN_3")
	)
	(segment
		(start 31.115 -23.495)
		(end 32.385 -22.225)
		(width 0.4572)
		(layer "B.Cu")
		(net "P52V_FAN_3")
	)
	(segment
		(start 47.657004 -16.409924)
		(end 44.99991 -16.409924)
		(width 1.3716)
		(layer "B.Cu")
		(net "P52V_FAN_3")
	)
	(segment
		(start 31.115 -25.908)
		(end 31.115 -23.495)
		(width 0.4572)
		(layer "B.Cu")
		(net "P52V_FAN_3")
	)
	(segment
		(start 32.1564 -288.925)
		(end 31.369 -288.925)
		(width 0.4572)
		(layer "F.Cu")
		(net "P52V_FAN_0")
	)
	(segment
		(start 31.7754 -302.895)
		(end 30.861 -301.9806)
		(width 0.4572)
		(layer "F.Cu")
		(net "P52V_FAN_0")
	)
	(segment
		(start 30.861 -300.355)
		(end 31.242 -299.974)
		(width 0.4572)
		(layer "F.Cu")
		(net "P52V_FAN_0")
	)
	(segment
		(start 30.861 -301.9806)
		(end 30.861 -300.355)
		(width 0.4572)
		(layer "F.Cu")
		(net "P52V_FAN_0")
	)
	(via
		(at 44.211748 -264.486136)
		(size 0.508)
		(drill 0.254)
		(layers "F.Cu" "B.Cu")
		(net "P52V_FAN_0")
	)
	(via
		(at 35.959288 -271.2466)
		(size 0.508)
		(drill 0.254)
		(layers "F.Cu" "B.Cu")
		(net "P52V_FAN_0")
	)
	(via
		(at 47.360332 -281.092148)
		(size 0.508)
		(drill 0.254)
		(layers "F.Cu" "B.Cu")
		(net "P52V_FAN_0")
	)
	(via
		(at 36.340288 -273.812)
		(size 0.508)
		(drill 0.254)
		(layers "F.Cu" "B.Cu")
		(net "P52V_FAN_0")
	)
	(via
		(at 31.242 -299.974)
		(size 0.508)
		(drill 0.254)
		(layers "F.Cu" "B.Cu")
		(net "P52V_FAN_0")
	)
	(via
		(at 45.836332 -281.092148)
		(size 0.508)
		(drill 0.254)
		(layers "F.Cu" "B.Cu")
		(net "P52V_FAN_0")
	)
	(via
		(at 45.836332 -280.330148)
		(size 0.508)
		(drill 0.254)
		(layers "F.Cu" "B.Cu")
		(net "P52V_FAN_0")
	)
	(via
		(at 46.598332 -280.330148)
		(size 0.508)
		(drill 0.254)
		(layers "F.Cu" "B.Cu")
		(net "P52V_FAN_0")
	)
	(via
		(at 43.576748 -264.486136)
		(size 0.508)
		(drill 0.254)
		(layers "F.Cu" "B.Cu")
		(net "P52V_FAN_0")
	)
	(via
		(at 36.340288 -272.542)
		(size 0.508)
		(drill 0.254)
		(layers "F.Cu" "B.Cu")
		(net "P52V_FAN_0")
	)
	(via
		(at 47.360332 -280.330148)
		(size 0.508)
		(drill 0.254)
		(layers "F.Cu" "B.Cu")
		(net "P52V_FAN_0")
	)
	(via
		(at 42.921428 -264.486136)
		(size 0.508)
		(drill 0.254)
		(layers "F.Cu" "B.Cu")
		(net "P52V_FAN_0")
	)
	(via
		(at 31.369 -288.925)
		(size 0.508)
		(drill 0.254)
		(layers "F.Cu" "B.Cu")
		(net "P52V_FAN_0")
	)
	(via
		(at 44.211748 -265.121136)
		(size 0.508)
		(drill 0.254)
		(layers "F.Cu" "B.Cu")
		(net "P52V_FAN_0")
	)
	(via
		(at 42.921428 -265.121136)
		(size 0.508)
		(drill 0.254)
		(layers "F.Cu" "B.Cu")
		(net "P52V_FAN_0")
	)
	(via
		(at 36.340288 -278.13)
		(size 0.508)
		(drill 0.254)
		(layers "F.Cu" "B.Cu")
		(net "P52V_FAN_0")
	)
	(via
		(at 46.598332 -281.092148)
		(size 0.508)
		(drill 0.254)
		(layers "F.Cu" "B.Cu")
		(net "P52V_FAN_0")
	)
	(via
		(at 43.566588 -265.121136)
		(size 0.508)
		(drill 0.254)
		(layers "F.Cu" "B.Cu")
		(net "P52V_FAN_0")
	)
	(via
		(at 35.959288 -271.8816)
		(size 0.508)
		(drill 0.254)
		(layers "F.Cu" "B.Cu")
		(net "P52V_FAN_0")
	)
	(via
		(at 36.340288 -277.495)
		(size 0.508)
		(drill 0.254)
		(layers "F.Cu" "B.Cu")
		(net "P52V_FAN_0")
	)
	(via
		(at 36.340288 -278.765)
		(size 0.508)
		(drill 0.254)
		(layers "F.Cu" "B.Cu")
		(net "P52V_FAN_0")
	)
	(via
		(at 36.340288 -273.177)
		(size 0.508)
		(drill 0.254)
		(layers "F.Cu" "B.Cu")
		(net "P52V_FAN_0")
	)
	(segment
		(start 32.258 -288.925)
		(end 37.592 -283.591)
		(width 0.4572)
		(layer "B.Cu")
		(net "P52V_FAN_0")
	)
	(segment
		(start 31.369 -288.925)
		(end 32.258 -288.925)
		(width 0.4572)
		(layer "B.Cu")
		(net "P52V_FAN_0")
	)
	(segment
		(start 32.639 -299.974)
		(end 31.242 -299.974)
		(width 0.4572)
		(layer "B.Cu")
		(net "P52V_FAN_0")
	)
	(segment
		(start 35.179 -297.434)
		(end 32.639 -299.974)
		(width 0.4572)
		(layer "B.Cu")
		(net "P52V_FAN_0")
	)
	(segment
		(start 44.99991 -293.310056)
		(end 47.768256 -293.310056)
		(width 1.3716)
		(layer "B.Cu")
		(net "P52V_FAN_0")
	)
	(segment
		(start 38.862 -297.434)
		(end 35.179 -297.434)
		(width 0.4572)
		(layer "B.Cu")
		(net "P52V_FAN_0")
	)
	(segment
		(start 42.999914 -295.310052)
		(end 40.096948 -295.310052)
		(width 1.3716)
		(layer "B.Cu")
		(net "P52V_FAN_0")
	)
	(segment
		(start 29.845 -101.219)
		(end 31.97225 -101.219)
		(width 0.4572)
		(layer "F.Cu")
		(net "P52V_FAN_2")
	)
	(segment
		(start 31.97225 -101.219)
		(end 32.22625 -101.473)
		(width 0.4572)
		(layer "F.Cu")
		(net "P52V_FAN_2")
	)
	(segment
		(start 31.496 -117.094)
		(end 30.988 -117.602)
		(width 0.4572)
		(layer "F.Cu")
		(net "P52V_FAN_2")
	)
	(segment
		(start 31.7754 -117.094)
		(end 31.496 -117.094)
		(width 0.4572)
		(layer "F.Cu")
		(net "P52V_FAN_2")
	)
	(via
		(at 40.349932 -84.385912)
		(size 0.508)
		(drill 0.254)
		(layers "F.Cu" "B.Cu")
		(net "P52V_FAN_2")
	)
	(via
		(at 46.445932 -91.38666)
		(size 0.508)
		(drill 0.254)
		(layers "F.Cu" "B.Cu")
		(net "P52V_FAN_2")
	)
	(via
		(at 47.207932 -91.38666)
		(size 0.508)
		(drill 0.254)
		(layers "F.Cu" "B.Cu")
		(net "P52V_FAN_2")
	)
	(via
		(at 38.0746 -93.352112)
		(size 0.508)
		(drill 0.254)
		(layers "F.Cu" "B.Cu")
		(net "P52V_FAN_2")
	)
	(via
		(at 38.0746 -87.9602)
		(size 0.508)
		(drill 0.254)
		(layers "F.Cu" "B.Cu")
		(net "P52V_FAN_2")
	)
	(via
		(at 48.2092 -96.5962)
		(size 0.6604)
		(drill 0.3302)
		(layers "F.Cu" "B.Cu")
		(net "P52V_FAN_2")
	)
	(via
		(at 46.445932 -92.02166)
		(size 0.508)
		(drill 0.254)
		(layers "F.Cu" "B.Cu")
		(net "P52V_FAN_2")
	)
	(via
		(at 36.7284 -85.6234)
		(size 0.508)
		(drill 0.254)
		(layers "F.Cu" "B.Cu")
		(net "P52V_FAN_2")
	)
	(via
		(at 45.683932 -92.02166)
		(size 0.508)
		(drill 0.254)
		(layers "F.Cu" "B.Cu")
		(net "P52V_FAN_2")
	)
	(via
		(at 43.566588 -80.521048)
		(size 0.508)
		(drill 0.254)
		(layers "F.Cu" "B.Cu")
		(net "P52V_FAN_2")
	)
	(via
		(at 38.0746 -88.653112)
		(size 0.508)
		(drill 0.254)
		(layers "F.Cu" "B.Cu")
		(net "P52V_FAN_2")
	)
	(via
		(at 47.207932 -92.02166)
		(size 0.508)
		(drill 0.254)
		(layers "F.Cu" "B.Cu")
		(net "P52V_FAN_2")
	)
	(via
		(at 36.7284 -86.316312)
		(size 0.508)
		(drill 0.254)
		(layers "F.Cu" "B.Cu")
		(net "P52V_FAN_2")
	)
	(via
		(at 38.0746 -94.0562)
		(size 0.508)
		(drill 0.254)
		(layers "F.Cu" "B.Cu")
		(net "P52V_FAN_2")
	)
	(via
		(at 40.349932 -83.623912)
		(size 0.508)
		(drill 0.254)
		(layers "F.Cu" "B.Cu")
		(net "P52V_FAN_2")
	)
	(via
		(at 42.921428 -80.521048)
		(size 0.508)
		(drill 0.254)
		(layers "F.Cu" "B.Cu")
		(net "P52V_FAN_2")
	)
	(via
		(at 42.921428 -79.886048)
		(size 0.508)
		(drill 0.254)
		(layers "F.Cu" "B.Cu")
		(net "P52V_FAN_2")
	)
	(via
		(at 38.0746 -89.3572)
		(size 0.508)
		(drill 0.254)
		(layers "F.Cu" "B.Cu")
		(net "P52V_FAN_2")
	)
	(via
		(at 30.988 -117.602)
		(size 0.508)
		(drill 0.254)
		(layers "F.Cu" "B.Cu")
		(net "P52V_FAN_2")
	)
	(via
		(at 44.211748 -80.521048)
		(size 0.508)
		(drill 0.254)
		(layers "F.Cu" "B.Cu")
		(net "P52V_FAN_2")
	)
	(via
		(at 44.921932 -92.02166)
		(size 0.508)
		(drill 0.254)
		(layers "F.Cu" "B.Cu")
		(net "P52V_FAN_2")
	)
	(via
		(at 43.576748 -79.886048)
		(size 0.508)
		(drill 0.254)
		(layers "F.Cu" "B.Cu")
		(net "P52V_FAN_2")
	)
	(via
		(at 45.683932 -91.38666)
		(size 0.508)
		(drill 0.254)
		(layers "F.Cu" "B.Cu")
		(net "P52V_FAN_2")
	)
	(via
		(at 29.845 -101.219)
		(size 0.508)
		(drill 0.254)
		(layers "F.Cu" "B.Cu")
		(net "P52V_FAN_2")
	)
	(via
		(at 44.921932 -91.38666)
		(size 0.508)
		(drill 0.254)
		(layers "F.Cu" "B.Cu")
		(net "P52V_FAN_2")
	)
	(via
		(at 38.0746 -92.5322)
		(size 0.508)
		(drill 0.254)
		(layers "F.Cu" "B.Cu")
		(net "P52V_FAN_2")
	)
	(via
		(at 44.211748 -79.886048)
		(size 0.508)
		(drill 0.254)
		(layers "F.Cu" "B.Cu")
		(net "P52V_FAN_2")
	)
	(segment
		(start 47.90186 -108.69422)
		(end 47.886112 -108.709968)
		(width 1.3716)
		(layer "B.Cu")
		(net "P52V_FAN_2")
	)
	(segment
		(start 30.988 -117.602)
		(end 35.2552 -113.3348)
		(width 0.4572)
		(layer "B.Cu")
		(net "P52V_FAN_2")
	)
	(segment
		(start 35.2552 -113.3348)
		(end 38.8874 -113.3348)
		(width 0.4572)
		(layer "B.Cu")
		(net "P52V_FAN_2")
	)
	(segment
		(start 40.08374 -110.70082)
		(end 40.092884 -110.709964)
		(width 1.3716)
		(layer "B.Cu")
		(net "P52V_FAN_2")
	)
	(segment
		(start 33.147 -101.219)
		(end 29.845 -101.219)
		(width 0.4572)
		(layer "B.Cu")
		(net "P52V_FAN_2")
	)
	(segment
		(start 47.886112 -108.709968)
		(end 44.99991 -108.709968)
		(width 1.3716)
		(layer "B.Cu")
		(net "P52V_FAN_2")
	)
	(segment
		(start 40.092884 -110.709964)
		(end 42.999914 -110.709964)
		(width 1.3716)
		(layer "B.Cu")
		(net "P52V_FAN_2")
	)
	(segment
		(start 36.322 -98.044)
		(end 33.147 -101.219)
		(width 0.4572)
		(layer "B.Cu")
		(net "P52V_FAN_2")
	)
	(segment
		(start 32.0294 -210.594956)
		(end 31.242 -210.594956)
		(width 0.4572)
		(layer "F.Cu")
		(net "P52V_FAN_1")
	)
	(segment
		(start 34.0106 -197.104)
		(end 33.5534 -196.6468)
		(width 0.4572)
		(layer "F.Cu")
		(net "P52V_FAN_1")
	)
	(segment
		(start 33.5534 -196.6468)
		(end 33.5534 -194.691)
		(width 0.4572)
		(layer "F.Cu")
		(net "P52V_FAN_1")
	)
	(via
		(at 36.412932 -244.31371)
		(size 0.508)
		(drill 0.254)
		(layers "F.Cu" "B.Cu")
		(net "P52V_FAN_1")
	)
	(via
		(at 41.370758 -234.823)
		(size 0.508)
		(drill 0.254)
		(layers "F.Cu" "B.Cu")
		(net "P52V_FAN_1")
	)
	(via
		(at 38.700456 -226.85121)
		(size 0.508)
		(drill 0.254)
		(layers "F.Cu" "B.Cu")
		(net "P52V_FAN_1")
	)
	(via
		(at 36.412932 -243.67871)
		(size 0.508)
		(drill 0.254)
		(layers "F.Cu" "B.Cu")
		(net "P52V_FAN_1")
	)
	(via
		(at 42.716958 -238.7854)
		(size 0.508)
		(drill 0.254)
		(layers "F.Cu" "B.Cu")
		(net "P52V_FAN_1")
	)
	(via
		(at 41.370758 -237.363)
		(size 0.508)
		(drill 0.254)
		(layers "F.Cu" "B.Cu")
		(net "P52V_FAN_1")
	)
	(via
		(at 35.122612 -243.67871)
		(size 0.508)
		(drill 0.254)
		(layers "F.Cu" "B.Cu")
		(net "P52V_FAN_1")
	)
	(via
		(at 38.065456 -226.08921)
		(size 0.508)
		(drill 0.254)
		(layers "F.Cu" "B.Cu")
		(net "P52V_FAN_1")
	)
	(via
		(at 35.767772 -243.67871)
		(size 0.508)
		(drill 0.254)
		(layers "F.Cu" "B.Cu")
		(net "P52V_FAN_1")
	)
	(via
		(at 41.370758 -232.029)
		(size 0.508)
		(drill 0.254)
		(layers "F.Cu" "B.Cu")
		(net "P52V_FAN_1")
	)
	(via
		(at 38.700456 -226.08921)
		(size 0.508)
		(drill 0.254)
		(layers "F.Cu" "B.Cu")
		(net "P52V_FAN_1")
	)
	(via
		(at 35.122612 -244.31371)
		(size 0.508)
		(drill 0.254)
		(layers "F.Cu" "B.Cu")
		(net "P52V_FAN_1")
	)
	(via
		(at 31.242 -210.594956)
		(size 0.508)
		(drill 0.254)
		(layers "F.Cu" "B.Cu")
		(net "P52V_FAN_1")
	)
	(via
		(at 41.370758 -231.267)
		(size 0.508)
		(drill 0.254)
		(layers "F.Cu" "B.Cu")
		(net "P52V_FAN_1")
	)
	(via
		(at 34.0106 -197.104)
		(size 0.508)
		(drill 0.254)
		(layers "F.Cu" "B.Cu")
		(net "P52V_FAN_1")
	)
	(via
		(at 38.065456 -227.61321)
		(size 0.508)
		(drill 0.254)
		(layers "F.Cu" "B.Cu")
		(net "P52V_FAN_1")
	)
	(via
		(at 41.370758 -236.601)
		(size 0.508)
		(drill 0.254)
		(layers "F.Cu" "B.Cu")
		(net "P52V_FAN_1")
	)
	(via
		(at 38.065456 -226.85121)
		(size 0.508)
		(drill 0.254)
		(layers "F.Cu" "B.Cu")
		(net "P52V_FAN_1")
	)
	(via
		(at 42.716958 -239.5474)
		(size 0.508)
		(drill 0.254)
		(layers "F.Cu" "B.Cu")
		(net "P52V_FAN_1")
	)
	(via
		(at 35.757612 -244.31371)
		(size 0.508)
		(drill 0.254)
		(layers "F.Cu" "B.Cu")
		(net "P52V_FAN_1")
	)
	(via
		(at 41.370758 -234.061)
		(size 0.508)
		(drill 0.254)
		(layers "F.Cu" "B.Cu")
		(net "P52V_FAN_1")
	)
	(via
		(at 38.700456 -227.61321)
		(size 0.508)
		(drill 0.254)
		(layers "F.Cu" "B.Cu")
		(net "P52V_FAN_1")
	)
	(segment
		(start 31.242 -210.594956)
		(end 32.540702 -210.594956)
		(width 0.4572)
		(layer "B.Cu")
		(net "P52V_FAN_1")
	)
	(segment
		(start 42.999914 -203.010008)
		(end 40.086788 -203.010008)
		(width 1.3716)
		(layer "B.Cu")
		(net "P52V_FAN_1")
	)
	(segment
		(start 34.0106 -197.104)
		(end 38.989 -197.104)
		(width 0.4572)
		(layer "B.Cu")
		(net "P52V_FAN_1")
	)
	(segment
		(start 32.540702 -210.594956)
		(end 33.248346 -211.3026)
		(width 0.4572)
		(layer "B.Cu")
		(net "P52V_FAN_1")
	)
	(segment
		(start 44.99991 -201.010012)
		(end 47.710852 -201.010012)
		(width 1.3716)
		(layer "B.Cu")
		(net "P52V_FAN_1")
	)
	(segment
		(start 33.248346 -211.3026)
		(end 40.005 -211.3026)
		(width 0.4572)
		(layer "B.Cu")
		(net "P52V_FAN_1")
	)
	(segment
		(start 11.4935 -135.78332)
		(end 12.15771 -135.78332)
		(width 0.2794)
		(layer "F.Cu")
		(net "FAN_7_TACH_OL_R2")
	)
	(segment
		(start 9.758934 -133.241034)
		(end 9.758934 -134.048754)
		(width 0.2794)
		(layer "F.Cu")
		(net "FAN_7_TACH_OL_R2")
	)
	(segment
		(start 9.758934 -134.048754)
		(end 11.4935 -135.78332)
		(width 0.2794)
		(layer "F.Cu")
		(net "FAN_7_TACH_OL_R2")
	)
	(segment
		(start 13.6779 -136.144)
		(end 13.31722 -135.78332)
		(width 0.2794)
		(layer "F.Cu")
		(net "FAN_7_TACH_OL_R2")
	)
	(segment
		(start 13.31722 -135.78332)
		(end 12.15771 -135.78332)
		(width 0.2794)
		(layer "F.Cu")
		(net "FAN_7_TACH_OL_R2")
	)
	(via
		(at 12.15771 -135.78332)
		(size 0.762)
		(drill 0.381)
		(layers "F.Cu" "B.Cu")
		(net "FAN_7_TACH_OL_R2")
	)
	(segment
		(start 11.0363 -134.15518)
		(end 10.559034 -133.677914)
		(width 0.2794)
		(layer "F.Cu")
		(net "FAN_7_PWM_R2")
	)
	(segment
		(start 13.65885 -134.874)
		(end 11.75512 -134.874)
		(width 0.2794)
		(layer "F.Cu")
		(net "FAN_7_PWM_R2")
	)
	(segment
		(start 11.75512 -134.874)
		(end 11.0363 -134.15518)
		(width 0.2794)
		(layer "F.Cu")
		(net "FAN_7_PWM_R2")
	)
	(segment
		(start 10.559034 -133.677914)
		(end 10.559034 -132.440934)
		(width 0.2794)
		(layer "F.Cu")
		(net "FAN_7_PWM_R2")
	)
	(via
		(at 11.0363 -134.15518)
		(size 0.762)
		(drill 0.381)
		(layers "F.Cu" "B.Cu")
		(net "FAN_7_PWM_R2")
	)
	(segment
		(start 12.47648 -133.36524)
		(end 11.052302 -131.941062)
		(width 0.2794)
		(layer "F.Cu")
		(net "FAN_6_TACH_OL_R2")
	)
	(segment
		(start 11.052302 -131.941062)
		(end 10.559034 -131.941062)
		(width 0.2794)
		(layer "F.Cu")
		(net "FAN_6_TACH_OL_R2")
	)
	(segment
		(start 12.47648 -133.604)
		(end 12.47648 -133.36524)
		(width 0.2794)
		(layer "F.Cu")
		(net "FAN_6_TACH_OL_R2")
	)
	(segment
		(start 13.65885 -133.604)
		(end 12.47648 -133.604)
		(width 0.2794)
		(layer "F.Cu")
		(net "FAN_6_TACH_OL_R2")
	)
	(via
		(at 12.47648 -133.604)
		(size 0.762)
		(drill 0.381)
		(layers "F.Cu" "B.Cu")
		(net "FAN_6_TACH_OL_R2")
	)
	(segment
		(start 12.319 -132.0419)
		(end 11.718036 -131.440936)
		(width 0.2794)
		(layer "F.Cu")
		(net "FAN_7_TACH_IL_R2")
	)
	(segment
		(start 13.65885 -132.334)
		(end 12.6111 -132.334)
		(width 0.2794)
		(layer "F.Cu")
		(net "FAN_7_TACH_IL_R2")
	)
	(segment
		(start 11.718036 -131.440936)
		(end 10.559034 -131.440936)
		(width 0.2794)
		(layer "F.Cu")
		(net "FAN_7_TACH_IL_R2")
	)
	(segment
		(start 12.6111 -132.334)
		(end 12.319 -132.0419)
		(width 0.2794)
		(layer "F.Cu")
		(net "FAN_7_TACH_IL_R2")
	)
	(via
		(at 12.319 -132.0419)
		(size 0.762)
		(drill 0.381)
		(layers "F.Cu" "B.Cu")
		(net "FAN_7_TACH_IL_R2")
	)
	(segment
		(start 12.43076 -130.26644)
		(end 11.97356 -130.26644)
		(width 0.2794)
		(layer "F.Cu")
		(net "FAN_6_TACH_IL_R2")
	)
	(segment
		(start 11.799062 -130.440938)
		(end 10.559034 -130.440938)
		(width 0.2794)
		(layer "F.Cu")
		(net "FAN_6_TACH_IL_R2")
	)
	(segment
		(start 13.65885 -131.064)
		(end 13.035788 -130.440938)
		(width 0.2794)
		(layer "F.Cu")
		(net "FAN_6_TACH_IL_R2")
	)
	(segment
		(start 12.605258 -130.440938)
		(end 12.43076 -130.26644)
		(width 0.2794)
		(layer "F.Cu")
		(net "FAN_6_TACH_IL_R2")
	)
	(segment
		(start 11.97356 -130.26644)
		(end 11.799062 -130.440938)
		(width 0.2794)
		(layer "F.Cu")
		(net "FAN_6_TACH_IL_R2")
	)
	(segment
		(start 13.035788 -130.440938)
		(end 12.605258 -130.440938)
		(width 0.2794)
		(layer "F.Cu")
		(net "FAN_6_TACH_IL_R2")
	)
	(via
		(at 11.97356 -130.26644)
		(size 0.762)
		(drill 0.381)
		(layers "F.Cu" "B.Cu")
		(net "FAN_6_TACH_IL_R2")
	)
	(segment
		(start 12.43838 -128.9558)
		(end 11.7602 -128.9558)
		(width 0.2794)
		(layer "F.Cu")
		(net "FAN_6_PWM_R2")
	)
	(segment
		(start 12.82065 -128.9558)
		(end 12.43838 -128.9558)
		(width 0.2794)
		(layer "F.Cu")
		(net "FAN_6_PWM_R2")
	)
	(segment
		(start 13.65885 -129.794)
		(end 12.82065 -128.9558)
		(width 0.2794)
		(layer "F.Cu")
		(net "FAN_6_PWM_R2")
	)
	(segment
		(start 10.774934 -129.941066)
		(end 10.559034 -129.941066)
		(width 0.2794)
		(layer "F.Cu")
		(net "FAN_6_PWM_R2")
	)
	(segment
		(start 11.7602 -128.9558)
		(end 10.774934 -129.941066)
		(width 0.2794)
		(layer "F.Cu")
		(net "FAN_6_PWM_R2")
	)
	(via
		(at 12.43838 -128.9558)
		(size 0.762)
		(drill 0.381)
		(layers "F.Cu" "B.Cu")
		(net "FAN_6_PWM_R2")
	)
	(segment
		(start 10.39876 -128.28524)
		(end 11.21156 -128.28524)
		(width 0.2794)
		(layer "F.Cu")
		(net "FAN_5_TACH_OL_R2")
	)
	(segment
		(start 13.36167 -128.22682)
		(end 11.26998 -128.22682)
		(width 0.2794)
		(layer "F.Cu")
		(net "FAN_5_TACH_OL_R2")
	)
	(segment
		(start 13.65885 -128.524)
		(end 13.36167 -128.22682)
		(width 0.2794)
		(layer "F.Cu")
		(net "FAN_5_TACH_OL_R2")
	)
	(segment
		(start 11.26998 -128.22682)
		(end 11.21156 -128.28524)
		(width 0.2794)
		(layer "F.Cu")
		(net "FAN_5_TACH_OL_R2")
	)
	(segment
		(start 9.758934 -128.925066)
		(end 10.39876 -128.28524)
		(width 0.2794)
		(layer "F.Cu")
		(net "FAN_5_TACH_OL_R2")
	)
	(segment
		(start 9.758934 -129.140966)
		(end 9.758934 -128.925066)
		(width 0.2794)
		(layer "F.Cu")
		(net "FAN_5_TACH_OL_R2")
	)
	(via
		(at 11.21156 -128.28524)
		(size 0.762)
		(drill 0.381)
		(layers "F.Cu" "B.Cu")
		(net "FAN_5_TACH_OL_R2")
	)
	(segment
		(start 12.413488 -127.127)
		(end 10.668 -127.127)
		(width 0.2794)
		(layer "F.Cu")
		(net "FAN_5_PWM_R2")
	)
	(segment
		(start 13.65885 -127.127)
		(end 12.413488 -127.127)
		(width 0.2794)
		(layer "F.Cu")
		(net "FAN_5_PWM_R2")
	)
	(segment
		(start 9.259062 -128.535938)
		(end 9.259062 -129.140966)
		(width 0.2794)
		(layer "F.Cu")
		(net "FAN_5_PWM_R2")
	)
	(segment
		(start 10.668 -127.127)
		(end 9.259062 -128.535938)
		(width 0.2794)
		(layer "F.Cu")
		(net "FAN_5_PWM_R2")
	)
	(via
		(at 12.413488 -127.127)
		(size 0.762)
		(drill 0.381)
		(layers "F.Cu" "B.Cu")
		(net "FAN_5_PWM_R2")
	)
	(segment
		(start 11.672062 -125.857)
		(end 11.049 -125.857)
		(width 0.2794)
		(layer "F.Cu")
		(net "FAN_4_TACH_OL_R2")
	)
	(segment
		(start 11.049 -125.857)
		(end 8.758936 -128.147064)
		(width 0.2794)
		(layer "F.Cu")
		(net "FAN_4_TACH_OL_R2")
	)
	(segment
		(start 13.65885 -125.857)
		(end 11.672062 -125.857)
		(width 0.2794)
		(layer "F.Cu")
		(net "FAN_4_TACH_OL_R2")
	)
	(segment
		(start 8.758936 -128.147064)
		(end 8.758936 -129.140966)
		(width 0.2794)
		(layer "F.Cu")
		(net "FAN_4_TACH_OL_R2")
	)
	(via
		(at 11.672062 -125.857)
		(size 0.762)
		(drill 0.381)
		(layers "F.Cu" "B.Cu")
		(net "FAN_4_TACH_OL_R2")
	)
	(segment
		(start 8.259064 -127.757936)
		(end 8.259064 -129.140966)
		(width 0.2794)
		(layer "F.Cu")
		(net "FAN_5_TACH_IL_R2")
	)
	(segment
		(start 11.43 -124.587)
		(end 8.259064 -127.757936)
		(width 0.2794)
		(layer "F.Cu")
		(net "FAN_5_TACH_IL_R2")
	)
	(segment
		(start 13.65885 -124.587)
		(end 12.451842 -124.587)
		(width 0.2794)
		(layer "F.Cu")
		(net "FAN_5_TACH_IL_R2")
	)
	(segment
		(start 12.451842 -124.587)
		(end 11.43 -124.587)
		(width 0.2794)
		(layer "F.Cu")
		(net "FAN_5_TACH_IL_R2")
	)
	(via
		(at 12.451842 -124.587)
		(size 0.762)
		(drill 0.381)
		(layers "F.Cu" "B.Cu")
		(net "FAN_5_TACH_IL_R2")
	)
	(segment
		(start 11.5443 -123.317)
		(end 10.463784 -124.397516)
		(width 0.2794)
		(layer "F.Cu")
		(net "FAN_4_TACH_IL_R2")
	)
	(segment
		(start 7.758938 -127.102362)
		(end 7.758938 -129.140966)
		(width 0.2794)
		(layer "F.Cu")
		(net "FAN_4_TACH_IL_R2")
	)
	(segment
		(start 13.65885 -123.317)
		(end 11.5443 -123.317)
		(width 0.2794)
		(layer "F.Cu")
		(net "FAN_4_TACH_IL_R2")
	)
	(segment
		(start 10.463784 -124.397516)
		(end 7.758938 -127.102362)
		(width 0.2794)
		(layer "F.Cu")
		(net "FAN_4_TACH_IL_R2")
	)
	(via
		(at 10.463784 -124.397516)
		(size 0.762)
		(drill 0.381)
		(layers "F.Cu" "B.Cu")
		(net "FAN_4_TACH_IL_R2")
	)
	(segment
		(start 11.76528 -122.047)
		(end 7.259066 -126.553214)
		(width 0.2794)
		(layer "F.Cu")
		(net "FAN_4_PWM_R2")
	)
	(segment
		(start 7.259066 -126.553214)
		(end 7.259066 -129.140966)
		(width 0.2794)
		(layer "F.Cu")
		(net "FAN_4_PWM_R2")
	)
	(segment
		(start 13.6779 -122.047)
		(end 12.247118 -122.047)
		(width 0.2794)
		(layer "F.Cu")
		(net "FAN_4_PWM_R2")
	)
	(segment
		(start 12.247118 -122.047)
		(end 11.76528 -122.047)
		(width 0.2794)
		(layer "F.Cu")
		(net "FAN_4_PWM_R2")
	)
	(via
		(at 12.247118 -122.047)
		(size 0.762)
		(drill 0.381)
		(layers "F.Cu" "B.Cu")
		(net "FAN_4_PWM_R2")
	)
	(segment
		(start 45.992034 -127.526034)
		(end 45.992034 -130.322066)
		(width 0.2794)
		(layer "F.Cu")
		(net "FAN_3_TACH_OL_R2")
	)
	(segment
		(start 39.0271 -123.698)
		(end 40.59682 -123.698)
		(width 0.2794)
		(layer "F.Cu")
		(net "FAN_3_TACH_OL_R2")
	)
	(segment
		(start 40.59682 -123.698)
		(end 42.164 -123.698)
		(width 0.2794)
		(layer "F.Cu")
		(net "FAN_3_TACH_OL_R2")
	)
	(segment
		(start 42.164 -123.698)
		(end 45.992034 -127.526034)
		(width 0.2794)
		(layer "F.Cu")
		(net "FAN_3_TACH_OL_R2")
	)
	(via
		(at 40.59682 -123.698)
		(size 0.762)
		(drill 0.381)
		(layers "F.Cu" "B.Cu")
		(net "FAN_3_TACH_OL_R2")
	)
	(segment
		(start 42.607738 -124.968)
		(end 45.191934 -127.552196)
		(width 0.2794)
		(layer "F.Cu")
		(net "FAN_3_PWM_R2")
	)
	(segment
		(start 41.9862 -124.968)
		(end 42.607738 -124.968)
		(width 0.2794)
		(layer "F.Cu")
		(net "FAN_3_PWM_R2")
	)
	(segment
		(start 45.191934 -127.552196)
		(end 45.191934 -129.521966)
		(width 0.2794)
		(layer "F.Cu")
		(net "FAN_3_PWM_R2")
	)
	(segment
		(start 39.04615 -124.968)
		(end 41.9862 -124.968)
		(width 0.2794)
		(layer "F.Cu")
		(net "FAN_3_PWM_R2")
	)
	(via
		(at 41.9862 -124.968)
		(size 0.762)
		(drill 0.381)
		(layers "F.Cu" "B.Cu")
		(net "FAN_3_PWM_R2")
	)
	(segment
		(start 44.692062 -129.521966)
		(end 44.692062 -127.877062)
		(width 0.2794)
		(layer "F.Cu")
		(net "FAN_2_TACH_OL_R2")
	)
	(segment
		(start 40.55872 -126.238)
		(end 39.04615 -126.238)
		(width 0.2794)
		(layer "F.Cu")
		(net "FAN_2_TACH_OL_R2")
	)
	(segment
		(start 44.692062 -127.877062)
		(end 43.053 -126.238)
		(width 0.2794)
		(layer "F.Cu")
		(net "FAN_2_TACH_OL_R2")
	)
	(segment
		(start 43.053 -126.238)
		(end 40.55872 -126.238)
		(width 0.2794)
		(layer "F.Cu")
		(net "FAN_2_TACH_OL_R2")
	)
	(via
		(at 40.55872 -126.238)
		(size 0.762)
		(drill 0.381)
		(layers "F.Cu" "B.Cu")
		(net "FAN_2_TACH_OL_R2")
	)
	(segment
		(start 44.191936 -129.521966)
		(end 44.191936 -128.265936)
		(width 0.2794)
		(layer "F.Cu")
		(net "FAN_3_TACH_IL_R2")
	)
	(segment
		(start 43.434 -127.508)
		(end 42.32402 -127.508)
		(width 0.2794)
		(layer "F.Cu")
		(net "FAN_3_TACH_IL_R2")
	)
	(segment
		(start 44.191936 -128.265936)
		(end 43.434 -127.508)
		(width 0.2794)
		(layer "F.Cu")
		(net "FAN_3_TACH_IL_R2")
	)
	(segment
		(start 42.32402 -127.508)
		(end 39.04615 -127.508)
		(width 0.2794)
		(layer "F.Cu")
		(net "FAN_3_TACH_IL_R2")
	)
	(via
		(at 42.32402 -127.508)
		(size 0.762)
		(drill 0.381)
		(layers "F.Cu" "B.Cu")
		(net "FAN_3_TACH_IL_R2")
	)
	(segment
		(start 39.04615 -128.778)
		(end 39.751254 -128.778)
		(width 0.2794)
		(layer "F.Cu")
		(net "FAN_2_TACH_IL_R2")
	)
	(segment
		(start 43.191938 -128.9304)
		(end 42.912538 -128.651)
		(width 0.2794)
		(layer "F.Cu")
		(net "FAN_2_TACH_IL_R2")
	)
	(segment
		(start 43.191938 -129.521966)
		(end 43.191938 -128.9304)
		(width 0.2794)
		(layer "F.Cu")
		(net "FAN_2_TACH_IL_R2")
	)
	(segment
		(start 42.912538 -128.651)
		(end 41.46296 -128.651)
		(width 0.2794)
		(layer "F.Cu")
		(net "FAN_2_TACH_IL_R2")
	)
	(segment
		(start 39.751254 -128.778)
		(end 40.137334 -128.39192)
		(width 0.2794)
		(layer "F.Cu")
		(net "FAN_2_TACH_IL_R2")
	)
	(segment
		(start 40.137334 -128.39192)
		(end 41.20388 -128.39192)
		(width 0.2794)
		(layer "F.Cu")
		(net "FAN_2_TACH_IL_R2")
	)
	(segment
		(start 41.46296 -128.651)
		(end 41.20388 -128.39192)
		(width 0.2794)
		(layer "F.Cu")
		(net "FAN_2_TACH_IL_R2")
	)
	(via
		(at 41.20388 -128.39192)
		(size 0.762)
		(drill 0.381)
		(layers "F.Cu" "B.Cu")
		(net "FAN_2_TACH_IL_R2")
	)
	(segment
		(start 42.692066 -129.521966)
		(end 40.27678 -129.521966)
		(width 0.2794)
		(layer "F.Cu")
		(net "FAN_2_PWM_R2")
	)
	(segment
		(start 39.572184 -129.521966)
		(end 40.27678 -129.521966)
		(width 0.2794)
		(layer "F.Cu")
		(net "FAN_2_PWM_R2")
	)
	(segment
		(start 39.04615 -130.048)
		(end 39.572184 -129.521966)
		(width 0.2794)
		(layer "F.Cu")
		(net "FAN_2_PWM_R2")
	)
	(via
		(at 40.27678 -129.521966)
		(size 0.762)
		(drill 0.381)
		(layers "F.Cu" "B.Cu")
		(net "FAN_2_PWM_R2")
	)
	(segment
		(start 39.04615 -130.683)
		(end 39.04615 -131.318)
		(width 0.2794)
		(layer "F.Cu")
		(net "FAN_1_TACH_OL_R2")
	)
	(segment
		(start 39.71163 -130.65252)
		(end 39.07663 -130.65252)
		(width 0.2794)
		(layer "F.Cu")
		(net "FAN_1_TACH_OL_R2")
	)
	(segment
		(start 40.042084 -130.322066)
		(end 39.71163 -130.65252)
		(width 0.2794)
		(layer "F.Cu")
		(net "FAN_1_TACH_OL_R2")
	)
	(segment
		(start 39.07663 -130.65252)
		(end 39.04615 -130.683)
		(width 0.2794)
		(layer "F.Cu")
		(net "FAN_1_TACH_OL_R2")
	)
	(segment
		(start 41.891966 -130.322066)
		(end 40.042084 -130.322066)
		(width 0.2794)
		(layer "F.Cu")
		(net "FAN_1_TACH_OL_R2")
	)
	(via
		(at 39.04615 -130.683)
		(size 0.508)
		(drill 0.254)
		(layers "F.Cu" "B.Cu")
		(net "FAN_1_TACH_OL_R2")
	)
	(segment
		(start 40.536622 -130.821938)
		(end 41.891966 -130.821938)
		(width 0.2794)
		(layer "F.Cu")
		(net "FAN_1_PWM_R2")
	)
	(segment
		(start 39.04615 -132.588)
		(end 39.04615 -132.31241)
		(width 0.2794)
		(layer "F.Cu")
		(net "FAN_1_PWM_R2")
	)
	(segment
		(start 39.04615 -132.31241)
		(end 40.23614 -131.12242)
		(width 0.2794)
		(layer "F.Cu")
		(net "FAN_1_PWM_R2")
	)
	(segment
		(start 40.23614 -131.12242)
		(end 40.536622 -130.821938)
		(width 0.2794)
		(layer "F.Cu")
		(net "FAN_1_PWM_R2")
	)
	(via
		(at 40.23614 -131.12242)
		(size 0.762)
		(drill 0.381)
		(layers "F.Cu" "B.Cu")
		(net "FAN_1_PWM_R2")
	)
	(segment
		(start 40.515032 -131.79552)
		(end 40.389302 -131.79552)
		(width 0.2794)
		(layer "F.Cu")
		(net "FAN_0_TACH_OL_R2")
	)
	(segment
		(start 39.27094 -133.223)
		(end 39.04615 -133.223)
		(width 0.2794)
		(layer "F.Cu")
		(net "FAN_0_TACH_OL_R2")
	)
	(segment
		(start 41.891966 -131.322064)
		(end 40.988488 -131.322064)
		(width 0.2794)
		(layer "F.Cu")
		(net "FAN_0_TACH_OL_R2")
	)
	(segment
		(start 40.988488 -131.322064)
		(end 40.515032 -131.79552)
		(width 0.2794)
		(layer "F.Cu")
		(net "FAN_0_TACH_OL_R2")
	)
	(segment
		(start 39.63035 -132.554472)
		(end 39.63035 -132.86359)
		(width 0.2794)
		(layer "F.Cu")
		(net "FAN_0_TACH_OL_R2")
	)
	(segment
		(start 40.389302 -131.79552)
		(end 39.63035 -132.554472)
		(width 0.2794)
		(layer "F.Cu")
		(net "FAN_0_TACH_OL_R2")
	)
	(segment
		(start 39.63035 -132.86359)
		(end 39.27094 -133.223)
		(width 0.2794)
		(layer "F.Cu")
		(net "FAN_0_TACH_OL_R2")
	)
	(segment
		(start 39.04615 -133.858)
		(end 39.04615 -133.223)
		(width 0.2794)
		(layer "F.Cu")
		(net "FAN_0_TACH_OL_R2")
	)
	(via
		(at 39.04615 -133.223)
		(size 0.508)
		(drill 0.254)
		(layers "F.Cu" "B.Cu")
		(net "FAN_0_TACH_OL_R2")
	)
	(segment
		(start 39.04615 -134.817104)
		(end 40.35298 -133.510274)
		(width 0.2794)
		(layer "F.Cu")
		(net "FAN_1_TACH_IL_R2")
	)
	(segment
		(start 39.04615 -135.128)
		(end 39.04615 -134.817104)
		(width 0.2794)
		(layer "F.Cu")
		(net "FAN_1_TACH_IL_R2")
	)
	(segment
		(start 40.35298 -132.74802)
		(end 41.279064 -131.821936)
		(width 0.2794)
		(layer "F.Cu")
		(net "FAN_1_TACH_IL_R2")
	)
	(segment
		(start 40.35298 -133.47954)
		(end 40.35298 -132.74802)
		(width 0.2794)
		(layer "F.Cu")
		(net "FAN_1_TACH_IL_R2")
	)
	(segment
		(start 41.279064 -131.821936)
		(end 41.891966 -131.821936)
		(width 0.2794)
		(layer "F.Cu")
		(net "FAN_1_TACH_IL_R2")
	)
	(segment
		(start 40.35298 -133.510274)
		(end 40.35298 -133.47954)
		(width 0.2794)
		(layer "F.Cu")
		(net "FAN_1_TACH_IL_R2")
	)
	(via
		(at 40.35298 -133.47954)
		(size 0.762)
		(drill 0.381)
		(layers "F.Cu" "B.Cu")
		(net "FAN_1_TACH_IL_R2")
	)
	(segment
		(start 41.11752 -132.61848)
		(end 41.11752 -133.888734)
		(width 0.2794)
		(layer "F.Cu")
		(net "FAN_0_TACH_IL_R2")
	)
	(segment
		(start 39.609014 -136.398)
		(end 40.33266 -135.674354)
		(width 0.2794)
		(layer "F.Cu")
		(net "FAN_0_TACH_IL_R2")
	)
	(segment
		(start 41.891966 -132.322062)
		(end 41.413938 -132.322062)
		(width 0.2794)
		(layer "F.Cu")
		(net "FAN_0_TACH_IL_R2")
	)
	(segment
		(start 41.413938 -132.322062)
		(end 41.11752 -132.61848)
		(width 0.2794)
		(layer "F.Cu")
		(net "FAN_0_TACH_IL_R2")
	)
	(segment
		(start 40.33266 -135.674354)
		(end 40.33266 -135.4836)
		(width 0.2794)
		(layer "F.Cu")
		(net "FAN_0_TACH_IL_R2")
	)
	(segment
		(start 39.04615 -136.398)
		(end 39.609014 -136.398)
		(width 0.2794)
		(layer "F.Cu")
		(net "FAN_0_TACH_IL_R2")
	)
	(segment
		(start 40.33266 -134.673594)
		(end 40.33266 -135.4836)
		(width 0.2794)
		(layer "F.Cu")
		(net "FAN_0_TACH_IL_R2")
	)
	(segment
		(start 41.11752 -133.888734)
		(end 40.33266 -134.673594)
		(width 0.2794)
		(layer "F.Cu")
		(net "FAN_0_TACH_IL_R2")
	)
	(via
		(at 40.33266 -135.4836)
		(size 0.762)
		(drill 0.381)
		(layers "F.Cu" "B.Cu")
		(net "FAN_0_TACH_IL_R2")
	)
	(segment
		(start 41.02354 -135.1534)
		(end 41.02354 -136.58596)
		(width 0.2794)
		(layer "F.Cu")
		(net "FAN_0_PWM_R2")
	)
	(segment
		(start 41.02354 -136.58596)
		(end 40.57142 -137.03808)
		(width 0.2794)
		(layer "F.Cu")
		(net "FAN_0_PWM_R2")
	)
	(segment
		(start 41.891966 -134.284974)
		(end 41.02354 -135.1534)
		(width 0.2794)
		(layer "F.Cu")
		(net "FAN_0_PWM_R2")
	)
	(segment
		(start 39.65702 -137.03808)
		(end 40.57142 -137.03808)
		(width 0.2794)
		(layer "F.Cu")
		(net "FAN_0_PWM_R2")
	)
	(segment
		(start 39.0271 -137.668)
		(end 39.65702 -137.03808)
		(width 0.2794)
		(layer "F.Cu")
		(net "FAN_0_PWM_R2")
	)
	(segment
		(start 41.891966 -132.821934)
		(end 41.891966 -134.284974)
		(width 0.2794)
		(layer "F.Cu")
		(net "FAN_0_PWM_R2")
	)
	(via
		(at 40.57142 -137.03808)
		(size 0.762)
		(drill 0.381)
		(layers "F.Cu" "B.Cu")
		(net "FAN_0_PWM_R2")
	)
	(segment
		(start 5.6134 -133.49224)
		(end 6.458966 -132.646674)
		(width 0.2794)
		(layer "F.Cu")
		(net "SMB_PDBV_FAN_R_U404_SCL")
	)
	(segment
		(start 5.6134 -134.62635)
		(end 5.6134 -133.63448)
		(width 0.2794)
		(layer "F.Cu")
		(net "SMB_PDBV_FAN_R_U404_SCL")
	)
	(segment
		(start 5.842 -134.85495)
		(end 5.6134 -134.62635)
		(width 0.2794)
		(layer "F.Cu")
		(net "SMB_PDBV_FAN_R_U404_SCL")
	)
	(segment
		(start 5.6134 -133.63448)
		(end 5.6134 -133.49224)
		(width 0.2794)
		(layer "F.Cu")
		(net "SMB_PDBV_FAN_R_U404_SCL")
	)
	(segment
		(start 6.458966 -132.646674)
		(end 6.458966 -132.440934)
		(width 0.2794)
		(layer "F.Cu")
		(net "SMB_PDBV_FAN_R_U404_SCL")
	)
	(via
		(at 5.6134 -133.63448)
		(size 0.762)
		(drill 0.381)
		(layers "F.Cu" "B.Cu")
		(net "SMB_PDBV_FAN_R_U404_SCL")
	)
	(segment
		(start 4.826 -134.85495)
		(end 4.21132 -134.24027)
		(width 0.2794)
		(layer "F.Cu")
		(net "SMB_PDBV_FAN_R_U404_SDA")
	)
	(segment
		(start 5.980684 -131.941062)
		(end 6.458966 -131.941062)
		(width 0.2794)
		(layer "F.Cu")
		(net "SMB_PDBV_FAN_R_U404_SDA")
	)
	(segment
		(start 4.21132 -133.65988)
		(end 4.775454 -133.095746)
		(width 0.2794)
		(layer "F.Cu")
		(net "SMB_PDBV_FAN_R_U404_SDA")
	)
	(segment
		(start 4.21132 -134.24027)
		(end 4.21132 -133.65988)
		(width 0.2794)
		(layer "F.Cu")
		(net "SMB_PDBV_FAN_R_U404_SDA")
	)
	(segment
		(start 4.826 -133.095746)
		(end 5.980684 -131.941062)
		(width 0.2794)
		(layer "F.Cu")
		(net "SMB_PDBV_FAN_R_U404_SDA")
	)
	(segment
		(start 4.775454 -133.095746)
		(end 4.826 -133.095746)
		(width 0.2794)
		(layer "F.Cu")
		(net "SMB_PDBV_FAN_R_U404_SDA")
	)
	(via
		(at 4.21132 -133.65988)
		(size 0.762)
		(drill 0.381)
		(layers "F.Cu" "B.Cu")
		(net "SMB_PDBV_FAN_R_U404_SDA")
	)
	(segment
		(start 6.858 -134.85495)
		(end 6.858 -134.345934)
		(width 0.2794)
		(layer "F.Cu")
		(net "U404_ADD0")
	)
	(segment
		(start 8.358886 -134.878064)
		(end 8.382 -134.85495)
		(width 0.2794)
		(layer "F.Cu")
		(net "U404_ADD0")
	)
	(segment
		(start 7.00532 -134.198614)
		(end 7.259066 -133.944868)
		(width 0.2794)
		(layer "F.Cu")
		(net "U404_ADD0")
	)
	(segment
		(start 6.858 -134.345934)
		(end 7.00532 -134.198614)
		(width 0.2794)
		(layer "F.Cu")
		(net "U404_ADD0")
	)
	(segment
		(start 6.858 -134.85495)
		(end 6.881114 -134.878064)
		(width 0.2794)
		(layer "F.Cu")
		(net "U404_ADD0")
	)
	(segment
		(start 7.259066 -133.944868)
		(end 7.259066 -133.241034)
		(width 0.2794)
		(layer "F.Cu")
		(net "U404_ADD0")
	)
	(segment
		(start 6.881114 -134.878064)
		(end 8.358886 -134.878064)
		(width 0.2794)
		(layer "F.Cu")
		(net "U404_ADD0")
	)
	(via
		(at 7.00532 -134.198614)
		(size 0.508)
		(drill 0.254)
		(layers "F.Cu" "B.Cu")
		(net "U404_ADD0")
	)
	(segment
		(start 4.21005 -130.937)
		(end 4.698746 -130.937)
		(width 0.2794)
		(layer "F.Cu")
		(net "U404_ADD1")
	)
	(segment
		(start 4.21005 -129.794)
		(end 4.21005 -130.937)
		(width 0.2794)
		(layer "F.Cu")
		(net "U404_ADD1")
	)
	(segment
		(start 5.194808 -130.440938)
		(end 6.458966 -130.440938)
		(width 0.2794)
		(layer "F.Cu")
		(net "U404_ADD1")
	)
	(segment
		(start 4.698746 -130.937)
		(end 5.194808 -130.440938)
		(width 0.2794)
		(layer "F.Cu")
		(net "U404_ADD1")
	)
	(via
		(at 5.194808 -130.440938)
		(size 0.508)
		(drill 0.254)
		(layers "F.Cu" "B.Cu")
		(net "U404_ADD1")
	)
	(segment
		(start 5.41528 -128.651)
		(end 4.21005 -128.651)
		(width 0.2794)
		(layer "F.Cu")
		(net "U404_ADD2")
	)
	(segment
		(start 4.21005 -127.508)
		(end 4.21005 -128.651)
		(width 0.2794)
		(layer "F.Cu")
		(net "U404_ADD2")
	)
	(segment
		(start 6.235446 -129.941066)
		(end 5.41528 -129.1209)
		(width 0.2794)
		(layer "F.Cu")
		(net "U404_ADD2")
	)
	(segment
		(start 5.41528 -129.1209)
		(end 5.41528 -128.651)
		(width 0.2794)
		(layer "F.Cu")
		(net "U404_ADD2")
	)
	(segment
		(start 6.458966 -129.941066)
		(end 6.235446 -129.941066)
		(width 0.2794)
		(layer "F.Cu")
		(net "U404_ADD2")
	)
	(via
		(at 5.41528 -128.651)
		(size 0.762)
		(drill 0.381)
		(layers "F.Cu" "B.Cu")
		(net "U404_ADD2")
	)
	(segment
		(start 18.039588 -132.307584)
		(end 18.370804 -131.507738)
		(width 0.1016)
		(layer "F.Cu")
		(net "FAN_7_TACH_OL_R1")
	)
	(segment
		(start 16.1163 -136.144)
		(end 16.49603 -135.76427)
		(width 0.2794)
		(layer "F.Cu")
		(net "FAN_7_TACH_OL_R1")
	)
	(segment
		(start 16.764 -135.4963)
		(end 16.764 -134.252716)
		(width 0.2794)
		(layer "F.Cu")
		(net "FAN_7_TACH_OL_R1")
	)
	(segment
		(start 18.60804 -129.9591)
		(end 18.955004 -129.9591)
		(width 0.1016)
		(layer "F.Cu")
		(net "FAN_7_TACH_OL_R1")
	)
	(segment
		(start 17.166082 -133.282182)
		(end 18.039588 -132.408676)
		(width 0.1016)
		(layer "F.Cu")
		(net "FAN_7_TACH_OL_R1")
	)
	(segment
		(start 15.2781 -136.144)
		(end 16.1163 -136.144)
		(width 0.2794)
		(layer "F.Cu")
		(net "FAN_7_TACH_OL_R1")
	)
	(segment
		(start 16.764 -134.252716)
		(end 17.166082 -133.282182)
		(width 0.1016)
		(layer "F.Cu")
		(net "FAN_7_TACH_OL_R1")
	)
	(segment
		(start 18.039588 -132.408676)
		(end 18.039588 -132.307584)
		(width 0.1016)
		(layer "F.Cu")
		(net "FAN_7_TACH_OL_R1")
	)
	(segment
		(start 18.370804 -131.507738)
		(end 18.370804 -130.196336)
		(width 0.1016)
		(layer "F.Cu")
		(net "FAN_7_TACH_OL_R1")
	)
	(segment
		(start 18.370804 -130.196336)
		(end 18.60804 -129.9591)
		(width 0.1016)
		(layer "F.Cu")
		(net "FAN_7_TACH_OL_R1")
	)
	(segment
		(start 16.49603 -135.76427)
		(end 16.764 -135.4963)
		(width 0.2794)
		(layer "F.Cu")
		(net "FAN_7_TACH_OL_R1")
	)
	(via
		(at 16.49603 -135.76427)
		(size 0.762)
		(drill 0.381)
		(layers "F.Cu" "B.Cu")
		(net "FAN_7_TACH_OL_R1")
	)
	(segment
		(start 17.958308 -131.242562)
		(end 17.660874 -131.96062)
		(width 0.1016)
		(layer "F.Cu")
		(net "FAN_7_PWM_R1")
	)
	(segment
		(start 18.459196 -129.55905)
		(end 17.958308 -130.059938)
		(width 0.1016)
		(layer "F.Cu")
		(net "FAN_7_PWM_R1")
	)
	(segment
		(start 17.660874 -131.96062)
		(end 17.455134 -132.16636)
		(width 0.1016)
		(layer "F.Cu")
		(net "FAN_7_PWM_R1")
	)
	(segment
		(start 15.25905 -134.874)
		(end 16.002 -134.13105)
		(width 0.2794)
		(layer "F.Cu")
		(net "FAN_7_PWM_R1")
	)
	(segment
		(start 16.002 -133.944868)
		(end 16.43634 -133.51002)
		(width 0.2794)
		(layer "F.Cu")
		(net "FAN_7_PWM_R1")
	)
	(segment
		(start 18.955004 -129.55905)
		(end 18.459196 -129.55905)
		(width 0.1016)
		(layer "F.Cu")
		(net "FAN_7_PWM_R1")
	)
	(segment
		(start 17.455134 -132.16636)
		(end 16.43634 -133.185154)
		(width 0.2794)
		(layer "F.Cu")
		(net "FAN_7_PWM_R1")
	)
	(segment
		(start 17.958308 -130.059938)
		(end 17.958308 -131.242562)
		(width 0.1016)
		(layer "F.Cu")
		(net "FAN_7_PWM_R1")
	)
	(segment
		(start 16.43634 -133.185154)
		(end 16.43634 -133.51002)
		(width 0.2794)
		(layer "F.Cu")
		(net "FAN_7_PWM_R1")
	)
	(segment
		(start 16.002 -134.13105)
		(end 16.002 -133.944868)
		(width 0.2794)
		(layer "F.Cu")
		(net "FAN_7_PWM_R1")
	)
	(via
		(at 16.43634 -133.51002)
		(size 0.762)
		(drill 0.381)
		(layers "F.Cu" "B.Cu")
		(net "FAN_7_PWM_R1")
	)
	(segment
		(start 17.551908 -130.835654)
		(end 17.551908 -129.891536)
		(width 0.1016)
		(layer "F.Cu")
		(net "FAN_6_TACH_OL_R1")
	)
	(segment
		(start 17.551908 -129.891536)
		(end 17.618456 -129.824988)
		(width 0.1016)
		(layer "F.Cu")
		(net "FAN_6_TACH_OL_R1")
	)
	(segment
		(start 15.25905 -133.604)
		(end 15.25905 -133.36143)
		(width 0.2794)
		(layer "F.Cu")
		(net "FAN_6_TACH_OL_R1")
	)
	(segment
		(start 17.618456 -129.82448)
		(end 18.283936 -129.159)
		(width 0.1016)
		(layer "F.Cu")
		(net "FAN_6_TACH_OL_R1")
	)
	(segment
		(start 16.46428 -132.1562)
		(end 16.867124 -131.753356)
		(width 0.2794)
		(layer "F.Cu")
		(net "FAN_6_TACH_OL_R1")
	)
	(segment
		(start 17.263872 -131.53136)
		(end 17.551908 -130.835654)
		(width 0.1016)
		(layer "F.Cu")
		(net "FAN_6_TACH_OL_R1")
	)
	(segment
		(start 16.867124 -131.753356)
		(end 17.041876 -131.753356)
		(width 0.2794)
		(layer "F.Cu")
		(net "FAN_6_TACH_OL_R1")
	)
	(segment
		(start 15.25905 -133.36143)
		(end 16.46428 -132.1562)
		(width 0.2794)
		(layer "F.Cu")
		(net "FAN_6_TACH_OL_R1")
	)
	(segment
		(start 17.618456 -129.824988)
		(end 17.618456 -129.82448)
		(width 0.1016)
		(layer "F.Cu")
		(net "FAN_6_TACH_OL_R1")
	)
	(segment
		(start 18.283936 -129.159)
		(end 18.955004 -129.159)
		(width 0.1016)
		(layer "F.Cu")
		(net "FAN_6_TACH_OL_R1")
	)
	(segment
		(start 17.041876 -131.753356)
		(end 17.263872 -131.53136)
		(width 0.1016)
		(layer "F.Cu")
		(net "FAN_6_TACH_OL_R1")
	)
	(via
		(at 16.46428 -132.1562)
		(size 0.762)
		(drill 0.381)
		(layers "F.Cu" "B.Cu")
		(net "FAN_6_TACH_OL_R1")
	)
	(segment
		(start 18.955004 -128.75895)
		(end 18.034254 -128.75895)
		(width 0.1016)
		(layer "F.Cu")
		(net "FAN_7_TACH_IL_R1")
	)
	(segment
		(start 16.993362 -129.799842)
		(end 16.993362 -130.089656)
		(width 0.1016)
		(layer "F.Cu")
		(net "FAN_7_TACH_IL_R1")
	)
	(segment
		(start 16.83766 -130.75539)
		(end 16.83766 -130.86588)
		(width 0.2794)
		(layer "F.Cu")
		(net "FAN_7_TACH_IL_R1")
	)
	(segment
		(start 16.72717 -130.86588)
		(end 16.83766 -130.86588)
		(width 0.2794)
		(layer "F.Cu")
		(net "FAN_7_TACH_IL_R1")
	)
	(segment
		(start 16.993362 -130.089656)
		(end 16.993362 -130.599688)
		(width 0.2794)
		(layer "F.Cu")
		(net "FAN_7_TACH_IL_R1")
	)
	(segment
		(start 15.25905 -132.334)
		(end 16.72717 -130.86588)
		(width 0.2794)
		(layer "F.Cu")
		(net "FAN_7_TACH_IL_R1")
	)
	(segment
		(start 16.993362 -130.599688)
		(end 16.83766 -130.75539)
		(width 0.2794)
		(layer "F.Cu")
		(net "FAN_7_TACH_IL_R1")
	)
	(segment
		(start 18.034254 -128.75895)
		(end 16.993362 -129.799842)
		(width 0.1016)
		(layer "F.Cu")
		(net "FAN_7_TACH_IL_R1")
	)
	(via
		(at 16.83766 -130.86588)
		(size 0.762)
		(drill 0.381)
		(layers "F.Cu" "B.Cu")
		(net "FAN_7_TACH_IL_R1")
	)
	(segment
		(start 16.123666 -129.883154)
		(end 16.4592 -129.54762)
		(width 0.2794)
		(layer "F.Cu")
		(net "FAN_6_TACH_IL_R1")
	)
	(segment
		(start 17.733518 -128.3589)
		(end 18.955004 -128.3589)
		(width 0.1016)
		(layer "F.Cu")
		(net "FAN_6_TACH_IL_R1")
	)
	(segment
		(start 17.050512 -129.041906)
		(end 17.733518 -128.3589)
		(width 0.1016)
		(layer "F.Cu")
		(net "FAN_6_TACH_IL_R1")
	)
	(segment
		(start 16.4592 -129.54762)
		(end 16.964914 -129.041906)
		(width 0.2794)
		(layer "F.Cu")
		(net "FAN_6_TACH_IL_R1")
	)
	(segment
		(start 16.123666 -130.199384)
		(end 16.123666 -129.883154)
		(width 0.2794)
		(layer "F.Cu")
		(net "FAN_6_TACH_IL_R1")
	)
	(segment
		(start 15.25905 -131.064)
		(end 16.123666 -130.199384)
		(width 0.2794)
		(layer "F.Cu")
		(net "FAN_6_TACH_IL_R1")
	)
	(segment
		(start 16.964914 -129.041906)
		(end 17.050512 -129.041906)
		(width 0.2794)
		(layer "F.Cu")
		(net "FAN_6_TACH_IL_R1")
	)
	(via
		(at 16.4592 -129.54762)
		(size 0.762)
		(drill 0.381)
		(layers "F.Cu" "B.Cu")
		(net "FAN_6_TACH_IL_R1")
	)
	(segment
		(start 17.51838 -127.8763)
		(end 17.601184 -127.959104)
		(width 0.1016)
		(layer "F.Cu")
		(net "FAN_6_PWM_R1")
	)
	(segment
		(start 17.601184 -127.959104)
		(end 18.955004 -127.959104)
		(width 0.1016)
		(layer "F.Cu")
		(net "FAN_6_PWM_R1")
	)
	(segment
		(start 16.631666 -128.221486)
		(end 16.976852 -127.8763)
		(width 0.2794)
		(layer "F.Cu")
		(net "FAN_6_PWM_R1")
	)
	(segment
		(start 16.976852 -127.8763)
		(end 17.51838 -127.8763)
		(width 0.2794)
		(layer "F.Cu")
		(net "FAN_6_PWM_R1")
	)
	(segment
		(start 15.25905 -129.794)
		(end 15.25905 -129.59588)
		(width 0.2794)
		(layer "F.Cu")
		(net "FAN_6_PWM_R1")
	)
	(segment
		(start 15.25905 -129.59588)
		(end 16.631666 -128.22174)
		(width 0.2794)
		(layer "F.Cu")
		(net "FAN_6_PWM_R1")
	)
	(segment
		(start 16.631666 -128.22174)
		(end 16.631666 -128.221486)
		(width 0.2794)
		(layer "F.Cu")
		(net "FAN_6_PWM_R1")
	)
	(via
		(at 16.631666 -128.221486)
		(size 0.762)
		(drill 0.381)
		(layers "F.Cu" "B.Cu")
		(net "FAN_6_PWM_R1")
	)
	(segment
		(start 19.218148 -127.20066)
		(end 19.279108 -127.1397)
		(width 0.2794)
		(layer "F.Cu")
		(net "FAN_5_TACH_OL_R1")
	)
	(segment
		(start 15.25905 -128.524)
		(end 16.58239 -127.20066)
		(width 0.2794)
		(layer "F.Cu")
		(net "FAN_5_TACH_OL_R1")
	)
	(segment
		(start 17.59966 -127.20066)
		(end 19.218148 -127.20066)
		(width 0.2794)
		(layer "F.Cu")
		(net "FAN_5_TACH_OL_R1")
	)
	(segment
		(start 16.58239 -127.20066)
		(end 17.59966 -127.20066)
		(width 0.2794)
		(layer "F.Cu")
		(net "FAN_5_TACH_OL_R1")
	)
	(segment
		(start 19.7358 -127.1397)
		(end 19.755104 -127.159004)
		(width 0.1016)
		(layer "F.Cu")
		(net "FAN_5_TACH_OL_R1")
	)
	(segment
		(start 19.279108 -127.1397)
		(end 19.7358 -127.1397)
		(width 0.1016)
		(layer "F.Cu")
		(net "FAN_5_TACH_OL_R1")
	)
	(via
		(at 17.59966 -127.20066)
		(size 0.762)
		(drill 0.381)
		(layers "F.Cu" "B.Cu")
		(net "FAN_5_TACH_OL_R1")
	)
	(segment
		(start 16.393414 -126.504954)
		(end 16.42872 -126.54026)
		(width 0.2794)
		(layer "F.Cu")
		(net "FAN_5_PWM_R1")
	)
	(segment
		(start 19.509486 -126.504954)
		(end 19.984466 -126.504954)
		(width 0.1016)
		(layer "F.Cu")
		(net "FAN_5_PWM_R1")
	)
	(segment
		(start 15.25905 -127.127)
		(end 15.881096 -126.504954)
		(width 0.2794)
		(layer "F.Cu")
		(net "FAN_5_PWM_R1")
	)
	(segment
		(start 19.984466 -126.504954)
		(end 20.1549 -126.675388)
		(width 0.1016)
		(layer "F.Cu")
		(net "FAN_5_PWM_R1")
	)
	(segment
		(start 20.1549 -126.675388)
		(end 20.1549 -127.159004)
		(width 0.1016)
		(layer "F.Cu")
		(net "FAN_5_PWM_R1")
	)
	(segment
		(start 16.469106 -126.504954)
		(end 19.509486 -126.504954)
		(width 0.2794)
		(layer "F.Cu")
		(net "FAN_5_PWM_R1")
	)
	(segment
		(start 16.42872 -126.54026)
		(end 16.4338 -126.54026)
		(width 0.2794)
		(layer "F.Cu")
		(net "FAN_5_PWM_R1")
	)
	(segment
		(start 15.881096 -126.504954)
		(end 16.393414 -126.504954)
		(width 0.2794)
		(layer "F.Cu")
		(net "FAN_5_PWM_R1")
	)
	(segment
		(start 16.4338 -126.54026)
		(end 16.469106 -126.504954)
		(width 0.2794)
		(layer "F.Cu")
		(net "FAN_5_PWM_R1")
	)
	(via
		(at 16.4338 -126.54026)
		(size 0.762)
		(drill 0.381)
		(layers "F.Cu" "B.Cu")
		(net "FAN_5_PWM_R1")
	)
	(segment
		(start 20.036536 -125.857)
		(end 20.55495 -126.375414)
		(width 0.1016)
		(layer "F.Cu")
		(net "FAN_4_TACH_OL_R1")
	)
	(segment
		(start 15.25905 -125.857)
		(end 17.80032 -125.857)
		(width 0.2794)
		(layer "F.Cu")
		(net "FAN_4_TACH_OL_R1")
	)
	(segment
		(start 19.681444 -125.857)
		(end 20.036536 -125.857)
		(width 0.1016)
		(layer "F.Cu")
		(net "FAN_4_TACH_OL_R1")
	)
	(segment
		(start 20.55495 -126.375414)
		(end 20.55495 -127.159004)
		(width 0.1016)
		(layer "F.Cu")
		(net "FAN_4_TACH_OL_R1")
	)
	(segment
		(start 17.89684 -125.76048)
		(end 17.99336 -125.857)
		(width 0.2794)
		(layer "F.Cu")
		(net "FAN_4_TACH_OL_R1")
	)
	(segment
		(start 17.99336 -125.857)
		(end 19.681444 -125.857)
		(width 0.2794)
		(layer "F.Cu")
		(net "FAN_4_TACH_OL_R1")
	)
	(segment
		(start 17.80032 -125.857)
		(end 17.89684 -125.76048)
		(width 0.2794)
		(layer "F.Cu")
		(net "FAN_4_TACH_OL_R1")
	)
	(via
		(at 17.89684 -125.76048)
		(size 0.762)
		(drill 0.381)
		(layers "F.Cu" "B.Cu")
		(net "FAN_4_TACH_OL_R1")
	)
	(segment
		(start 20.955 -125.880368)
		(end 20.955 -127.159004)
		(width 0.1016)
		(layer "F.Cu")
		(net "FAN_5_TACH_IL_R1")
	)
	(segment
		(start 18.620994 -124.587)
		(end 19.283934 -125.24994)
		(width 0.2794)
		(layer "F.Cu")
		(net "FAN_5_TACH_IL_R1")
	)
	(segment
		(start 15.25905 -124.587)
		(end 16.5862 -124.587)
		(width 0.2794)
		(layer "F.Cu")
		(net "FAN_5_TACH_IL_R1")
	)
	(segment
		(start 16.5862 -124.587)
		(end 18.620994 -124.587)
		(width 0.2794)
		(layer "F.Cu")
		(net "FAN_5_TACH_IL_R1")
	)
	(segment
		(start 20.324572 -125.24994)
		(end 20.955 -125.880368)
		(width 0.2794)
		(layer "F.Cu")
		(net "FAN_5_TACH_IL_R1")
	)
	(segment
		(start 19.283934 -125.24994)
		(end 20.324572 -125.24994)
		(width 0.2794)
		(layer "F.Cu")
		(net "FAN_5_TACH_IL_R1")
	)
	(via
		(at 16.5862 -124.587)
		(size 0.762)
		(drill 0.381)
		(layers "F.Cu" "B.Cu")
		(net "FAN_5_TACH_IL_R1")
	)
	(segment
		(start 19.763486 -124.66574)
		(end 20.566634 -124.66574)
		(width 0.2794)
		(layer "F.Cu")
		(net "FAN_4_TACH_IL_R1")
	)
	(segment
		(start 21.22297 -125.322076)
		(end 21.35505 -125.454156)
		(width 0.1016)
		(layer "F.Cu")
		(net "FAN_4_TACH_IL_R1")
	)
	(segment
		(start 21.35505 -125.454156)
		(end 21.35505 -127.159004)
		(width 0.1016)
		(layer "F.Cu")
		(net "FAN_4_TACH_IL_R1")
	)
	(segment
		(start 18.414746 -123.317)
		(end 19.763486 -124.66574)
		(width 0.2794)
		(layer "F.Cu")
		(net "FAN_4_TACH_IL_R1")
	)
	(segment
		(start 15.25905 -123.317)
		(end 17.50822 -123.317)
		(width 0.2794)
		(layer "F.Cu")
		(net "FAN_4_TACH_IL_R1")
	)
	(segment
		(start 17.50822 -123.317)
		(end 18.414746 -123.317)
		(width 0.2794)
		(layer "F.Cu")
		(net "FAN_4_TACH_IL_R1")
	)
	(segment
		(start 20.566634 -124.66574)
		(end 21.22297 -125.322076)
		(width 0.2794)
		(layer "F.Cu")
		(net "FAN_4_TACH_IL_R1")
	)
	(via
		(at 17.50822 -123.317)
		(size 0.762)
		(drill 0.381)
		(layers "F.Cu" "B.Cu")
		(net "FAN_4_TACH_IL_R1")
	)
	(segment
		(start 16.5862 -122.047)
		(end 18.262346 -122.047)
		(width 0.2794)
		(layer "F.Cu")
		(net "FAN_4_PWM_R1")
	)
	(segment
		(start 20.296886 -124.08154)
		(end 20.83054 -124.08154)
		(width 0.2794)
		(layer "F.Cu")
		(net "FAN_4_PWM_R1")
	)
	(segment
		(start 18.262346 -122.047)
		(end 20.296886 -124.08154)
		(width 0.2794)
		(layer "F.Cu")
		(net "FAN_4_PWM_R1")
	)
	(segment
		(start 21.5519 -124.8029)
		(end 21.7551 -125.0061)
		(width 0.1016)
		(layer "F.Cu")
		(net "FAN_4_PWM_R1")
	)
	(segment
		(start 20.83054 -124.08154)
		(end 21.5519 -124.8029)
		(width 0.2794)
		(layer "F.Cu")
		(net "FAN_4_PWM_R1")
	)
	(segment
		(start 15.2781 -122.047)
		(end 16.5862 -122.047)
		(width 0.2794)
		(layer "F.Cu")
		(net "FAN_4_PWM_R1")
	)
	(segment
		(start 21.7551 -125.0061)
		(end 21.7551 -127.159004)
		(width 0.1016)
		(layer "F.Cu")
		(net "FAN_4_PWM_R1")
	)
	(via
		(at 16.5862 -122.047)
		(size 0.762)
		(drill 0.381)
		(layers "F.Cu" "B.Cu")
		(net "FAN_4_PWM_R1")
	)
	(segment
		(start 16.61795 -24.892)
		(end 16.5989 -24.91105)
		(width 0.2794)
		(layer "F.Cu")
		(net "FAN_4_OK_LED_R_N")
	)
	(segment
		(start 16.5989 -25.908)
		(end 16.5989 -26.924)
		(width 0.2794)
		(layer "F.Cu")
		(net "FAN_4_OK_LED_R_N")
	)
	(segment
		(start 15.901162 -26.924)
		(end 16.5989 -26.924)
		(width 0.2794)
		(layer "F.Cu")
		(net "FAN_4_OK_LED_R_N")
	)
	(segment
		(start 16.5989 -24.91105)
		(end 16.5989 -25.908)
		(width 0.2794)
		(layer "F.Cu")
		(net "FAN_4_OK_LED_R_N")
	)
	(segment
		(start 15.113 -27.32405)
		(end 15.501112 -27.32405)
		(width 0.2794)
		(layer "F.Cu")
		(net "FAN_4_OK_LED_R_N")
	)
	(segment
		(start 15.501112 -27.32405)
		(end 15.901162 -26.924)
		(width 0.2794)
		(layer "F.Cu")
		(net "FAN_4_OK_LED_R_N")
	)
	(via
		(at 16.5989 -25.908)
		(size 0.508)
		(drill 0.254)
		(layers "F.Cu" "B.Cu")
		(net "FAN_4_OK_LED_R_N")
	)
	(segment
		(start 15.741396 -296.799)
		(end 14.75105 -296.799)
		(width 0.2794)
		(layer "F.Cu")
		(net "FAN_7_FAIL_LED_R_N")
	)
	(segment
		(start 16.36395 -296.037)
		(end 16.36395 -296.672)
		(width 0.2794)
		(layer "F.Cu")
		(net "FAN_7_FAIL_LED_R_N")
	)
	(segment
		(start 16.36395 -296.037)
		(end 16.637 -295.76395)
		(width 0.2794)
		(layer "F.Cu")
		(net "FAN_7_FAIL_LED_R_N")
	)
	(segment
		(start 15.868396 -296.672)
		(end 15.741396 -296.799)
		(width 0.2794)
		(layer "F.Cu")
		(net "FAN_7_FAIL_LED_R_N")
	)
	(segment
		(start 16.637 -295.76395)
		(end 16.637 -294.8051)
		(width 0.2794)
		(layer "F.Cu")
		(net "FAN_7_FAIL_LED_R_N")
	)
	(segment
		(start 16.36395 -296.672)
		(end 15.868396 -296.672)
		(width 0.2794)
		(layer "F.Cu")
		(net "FAN_7_FAIL_LED_R_N")
	)
	(segment
		(start 16.637 -294.8051)
		(end 16.4719 -294.64)
		(width 0.2794)
		(layer "F.Cu")
		(net "FAN_7_FAIL_LED_R_N")
	)
	(via
		(at 16.36395 -296.037)
		(size 0.508)
		(drill 0.254)
		(layers "F.Cu" "B.Cu")
		(net "FAN_7_FAIL_LED_R_N")
	)
	(segment
		(start 16.26235 -23.51405)
		(end 16.5989 -23.1775)
		(width 0.2794)
		(layer "F.Cu")
		(net "FAN_4_FAIL_LED_R_N")
	)
	(segment
		(start 16.61795 -22.01545)
		(end 16.5989 -22.0345)
		(width 0.2794)
		(layer "F.Cu")
		(net "FAN_4_FAIL_LED_R_N")
	)
	(segment
		(start 15.113 -23.51405)
		(end 16.26235 -23.51405)
		(width 0.2794)
		(layer "F.Cu")
		(net "FAN_4_FAIL_LED_R_N")
	)
	(segment
		(start 16.61795 -20.574)
		(end 16.61795 -22.01545)
		(width 0.2794)
		(layer "F.Cu")
		(net "FAN_4_FAIL_LED_R_N")
	)
	(segment
		(start 16.5989 -22.0345)
		(end 16.5989 -22.606)
		(width 0.2794)
		(layer "F.Cu")
		(net "FAN_4_FAIL_LED_R_N")
	)
	(segment
		(start 16.5989 -23.1775)
		(end 16.5989 -22.606)
		(width 0.2794)
		(layer "F.Cu")
		(net "FAN_4_FAIL_LED_R_N")
	)
	(via
		(at 16.26235 -23.51405)
		(size 0.508)
		(drill 0.254)
		(layers "F.Cu" "B.Cu")
		(net "FAN_4_FAIL_LED_R_N")
	)
	(segment
		(start 16.5989 -208.3689)
		(end 16.5989 -207.938116)
		(width 0.2794)
		(layer "F.Cu")
		(net "FAN_6_OK_LED_R_N")
	)
	(segment
		(start 16.4719 -207.264)
		(end 14.75105 -207.264)
		(width 0.2794)
		(layer "F.Cu")
		(net "FAN_6_OK_LED_R_N")
	)
	(segment
		(start 16.5989 -207.137)
		(end 16.4719 -207.264)
		(width 0.2794)
		(layer "F.Cu")
		(net "FAN_6_OK_LED_R_N")
	)
	(segment
		(start 18.14195 -209.169)
		(end 17.399 -209.169)
		(width 0.2794)
		(layer "F.Cu")
		(net "FAN_6_OK_LED_R_N")
	)
	(segment
		(start 16.5989 -207.938116)
		(end 16.5989 -207.137)
		(width 0.2794)
		(layer "F.Cu")
		(net "FAN_6_OK_LED_R_N")
	)
	(segment
		(start 17.399 -209.169)
		(end 16.5989 -208.3689)
		(width 0.2794)
		(layer "F.Cu")
		(net "FAN_6_OK_LED_R_N")
	)
	(via
		(at 16.5989 -207.938116)
		(size 0.508)
		(drill 0.254)
		(layers "F.Cu" "B.Cu")
		(net "FAN_6_OK_LED_R_N")
	)
	(segment
		(start 16.10995 -111.27105)
		(end 16.5989 -110.7821)
		(width 0.2794)
		(layer "F.Cu")
		(net "FAN_5_FAIL_LED_R_N")
	)
	(segment
		(start 16.5989 -108.9279)
		(end 17.018 -109.347)
		(width 0.2794)
		(layer "F.Cu")
		(net "FAN_5_FAIL_LED_R_N")
	)
	(segment
		(start 16.49095 -108.458)
		(end 16.5989 -108.56595)
		(width 0.2794)
		(layer "F.Cu")
		(net "FAN_5_FAIL_LED_R_N")
	)
	(segment
		(start 16.5989 -108.56595)
		(end 16.5989 -108.9279)
		(width 0.2794)
		(layer "F.Cu")
		(net "FAN_5_FAIL_LED_R_N")
	)
	(segment
		(start 15.113 -111.27105)
		(end 16.10995 -111.27105)
		(width 0.2794)
		(layer "F.Cu")
		(net "FAN_5_FAIL_LED_R_N")
	)
	(segment
		(start 16.5989 -110.7821)
		(end 16.5989 -110.49)
		(width 0.2794)
		(layer "F.Cu")
		(net "FAN_5_FAIL_LED_R_N")
	)
	(segment
		(start 16.5989 -110.49)
		(end 16.5989 -109.7661)
		(width 0.2794)
		(layer "F.Cu")
		(net "FAN_5_FAIL_LED_R_N")
	)
	(segment
		(start 16.5989 -109.7661)
		(end 17.018 -109.347)
		(width 0.2794)
		(layer "F.Cu")
		(net "FAN_5_FAIL_LED_R_N")
	)
	(via
		(at 17.018 -109.347)
		(size 0.508)
		(drill 0.254)
		(layers "F.Cu" "B.Cu")
		(net "FAN_5_FAIL_LED_R_N")
	)
	(segment
		(start 16.4719 -299.7581)
		(end 16.4719 -299.466)
		(width 0.2794)
		(layer "F.Cu")
		(net "FAN_7_OK_LED_R_N")
	)
	(segment
		(start 16.4719 -299.466)
		(end 16.4719 -298.704)
		(width 0.2794)
		(layer "F.Cu")
		(net "FAN_7_OK_LED_R_N")
	)
	(segment
		(start 14.75105 -299.339)
		(end 14.75105 -299.3136)
		(width 0.2794)
		(layer "F.Cu")
		(net "FAN_7_OK_LED_R_N")
	)
	(segment
		(start 16.36395 -299.86605)
		(end 16.4719 -299.7581)
		(width 0.2794)
		(layer "F.Cu")
		(net "FAN_7_OK_LED_R_N")
	)
	(segment
		(start 15.36065 -298.704)
		(end 16.4719 -298.704)
		(width 0.2794)
		(layer "F.Cu")
		(net "FAN_7_OK_LED_R_N")
	)
	(segment
		(start 14.75105 -299.3136)
		(end 15.36065 -298.704)
		(width 0.2794)
		(layer "F.Cu")
		(net "FAN_7_OK_LED_R_N")
	)
	(segment
		(start 16.36395 -300.736)
		(end 16.36395 -299.86605)
		(width 0.2794)
		(layer "F.Cu")
		(net "FAN_7_OK_LED_R_N")
	)
	(via
		(at 16.4719 -299.466)
		(size 0.508)
		(drill 0.254)
		(layers "F.Cu" "B.Cu")
		(net "FAN_7_OK_LED_R_N")
	)
	(segment
		(start 16.5989 -112.75695)
		(end 16.5989 -113.665)
		(width 0.2794)
		(layer "F.Cu")
		(net "FAN_5_OK_LED_R_N")
	)
	(segment
		(start 16.49095 -112.649)
		(end 16.5989 -112.75695)
		(width 0.2794)
		(layer "F.Cu")
		(net "FAN_5_OK_LED_R_N")
	)
	(segment
		(start 16.5989 -113.665)
		(end 16.5989 -114.681)
		(width 0.2794)
		(layer "F.Cu")
		(net "FAN_5_OK_LED_R_N")
	)
	(segment
		(start 15.113 -114.82705)
		(end 16.45285 -114.82705)
		(width 0.2794)
		(layer "F.Cu")
		(net "FAN_5_OK_LED_R_N")
	)
	(segment
		(start 16.45285 -114.82705)
		(end 16.5989 -114.681)
		(width 0.2794)
		(layer "F.Cu")
		(net "FAN_5_OK_LED_R_N")
	)
	(via
		(at 16.5989 -113.665)
		(size 0.508)
		(drill 0.254)
		(layers "F.Cu" "B.Cu")
		(net "FAN_5_OK_LED_R_N")
	)
	(segment
		(start 16.5989 -204.99705)
		(end 16.5989 -203.073)
		(width 0.2794)
		(layer "F.Cu")
		(net "FAN_6_FAIL_LED_R_N")
	)
	(segment
		(start 16.162782 -203.073)
		(end 16.5989 -203.073)
		(width 0.2794)
		(layer "F.Cu")
		(net "FAN_6_FAIL_LED_R_N")
	)
	(segment
		(start 15.762732 -204.074522)
		(end 15.367254 -204.47)
		(width 0.2794)
		(layer "F.Cu")
		(net "FAN_6_FAIL_LED_R_N")
	)
	(segment
		(start 16.49095 -205.105)
		(end 16.5989 -204.99705)
		(width 0.2794)
		(layer "F.Cu")
		(net "FAN_6_FAIL_LED_R_N")
	)
	(segment
		(start 15.762732 -203.47305)
		(end 16.162782 -203.073)
		(width 0.2794)
		(layer "F.Cu")
		(net "FAN_6_FAIL_LED_R_N")
	)
	(segment
		(start 15.762732 -203.47305)
		(end 15.762732 -204.074522)
		(width 0.2794)
		(layer "F.Cu")
		(net "FAN_6_FAIL_LED_R_N")
	)
	(segment
		(start 15.367254 -204.47)
		(end 14.75105 -204.47)
		(width 0.2794)
		(layer "F.Cu")
		(net "FAN_6_FAIL_LED_R_N")
	)
	(via
		(at 15.762732 -203.47305)
		(size 0.508)
		(drill 0.254)
		(layers "F.Cu" "B.Cu")
		(net "FAN_6_FAIL_LED_R_N")
	)
	(segment
		(start 36.20135 -109.855)
		(end 35.3441 -109.855)
		(width 0.2794)
		(layer "F.Cu")
		(net "FAN_2_FAIL_LED_R_N")
	)
	(segment
		(start 36.83 -109.96295)
		(end 36.3093 -109.96295)
		(width 0.2794)
		(layer "F.Cu")
		(net "FAN_2_FAIL_LED_R_N")
	)
	(segment
		(start 32.838136 -108.531914)
		(end 34.744914 -108.531914)
		(width 0.2794)
		(layer "F.Cu")
		(net "FAN_2_FAIL_LED_R_N")
	)
	(segment
		(start 32.40405 -108.966)
		(end 32.838136 -108.531914)
		(width 0.2794)
		(layer "F.Cu")
		(net "FAN_2_FAIL_LED_R_N")
	)
	(segment
		(start 34.744914 -108.531914)
		(end 35.3441 -109.1311)
		(width 0.2794)
		(layer "F.Cu")
		(net "FAN_2_FAIL_LED_R_N")
	)
	(segment
		(start 35.3441 -109.1311)
		(end 35.3441 -109.855)
		(width 0.2794)
		(layer "F.Cu")
		(net "FAN_2_FAIL_LED_R_N")
	)
	(segment
		(start 36.3093 -109.96295)
		(end 36.20135 -109.855)
		(width 0.2794)
		(layer "F.Cu")
		(net "FAN_2_FAIL_LED_R_N")
	)
	(via
		(at 35.3441 -109.1311)
		(size 0.508)
		(drill 0.254)
		(layers "F.Cu" "B.Cu")
		(net "FAN_2_FAIL_LED_R_N")
	)
	(segment
		(start 35.2171 -295.148)
		(end 35.2171 -296.037)
		(width 0.2794)
		(layer "F.Cu")
		(net "FAN_0_FAIL_LED_R_N")
	)
	(segment
		(start 36.93795 -293.624)
		(end 36.195 -293.624)
		(width 0.2794)
		(layer "F.Cu")
		(net "FAN_0_FAIL_LED_R_N")
	)
	(segment
		(start 35.2171 -294.6019)
		(end 35.2171 -295.148)
		(width 0.2794)
		(layer "F.Cu")
		(net "FAN_0_FAIL_LED_R_N")
	)
	(segment
		(start 35.32505 -296.81805)
		(end 35.2171 -296.7101)
		(width 0.2794)
		(layer "F.Cu")
		(net "FAN_0_FAIL_LED_R_N")
	)
	(segment
		(start 36.195 -293.624)
		(end 35.2171 -294.6019)
		(width 0.2794)
		(layer "F.Cu")
		(net "FAN_0_FAIL_LED_R_N")
	)
	(segment
		(start 35.32505 -297.18)
		(end 35.32505 -296.81805)
		(width 0.2794)
		(layer "F.Cu")
		(net "FAN_0_FAIL_LED_R_N")
	)
	(segment
		(start 35.2171 -296.7101)
		(end 35.2171 -296.037)
		(width 0.2794)
		(layer "F.Cu")
		(net "FAN_0_FAIL_LED_R_N")
	)
	(via
		(at 35.2171 -296.037)
		(size 0.508)
		(drill 0.254)
		(layers "F.Cu" "B.Cu")
		(net "FAN_0_FAIL_LED_R_N")
	)
	(segment
		(start 36.81095 -202.311)
		(end 35.7251 -202.311)
		(width 0.2794)
		(layer "F.Cu")
		(net "FAN_1_FAIL_LED_R_N")
	)
	(segment
		(start 32.258 -204.36205)
		(end 32.343852 -204.36205)
		(width 0.2794)
		(layer "F.Cu")
		(net "FAN_1_FAIL_LED_R_N")
	)
	(segment
		(start 32.784288 -204.802486)
		(end 34.449512 -204.802486)
		(width 0.2794)
		(layer "F.Cu")
		(net "FAN_1_FAIL_LED_R_N")
	)
	(segment
		(start 35.2171 -202.819)
		(end 35.32505 -202.92695)
		(width 0.2794)
		(layer "F.Cu")
		(net "FAN_1_FAIL_LED_R_N")
	)
	(segment
		(start 35.32505 -202.92695)
		(end 35.32505 -203.703936)
		(width 0.2794)
		(layer "F.Cu")
		(net "FAN_1_FAIL_LED_R_N")
	)
	(segment
		(start 32.343852 -204.36205)
		(end 32.784288 -204.802486)
		(width 0.2794)
		(layer "F.Cu")
		(net "FAN_1_FAIL_LED_R_N")
	)
	(segment
		(start 35.32505 -203.926948)
		(end 35.32505 -203.703936)
		(width 0.2794)
		(layer "F.Cu")
		(net "FAN_1_FAIL_LED_R_N")
	)
	(segment
		(start 34.449512 -204.802486)
		(end 35.32505 -203.926948)
		(width 0.2794)
		(layer "F.Cu")
		(net "FAN_1_FAIL_LED_R_N")
	)
	(segment
		(start 35.7251 -202.311)
		(end 35.2171 -202.819)
		(width 0.2794)
		(layer "F.Cu")
		(net "FAN_1_FAIL_LED_R_N")
	)
	(via
		(at 35.32505 -203.703936)
		(size 0.508)
		(drill 0.254)
		(layers "F.Cu" "B.Cu")
		(net "FAN_1_FAIL_LED_R_N")
	)
	(segment
		(start 35.83305 -105.791)
		(end 35.3441 -105.791)
		(width 0.2794)
		(layer "F.Cu")
		(net "FAN_2_OK_LED_R_N")
	)
	(segment
		(start 35.3441 -106.729022)
		(end 35.3441 -105.791)
		(width 0.2794)
		(layer "F.Cu")
		(net "FAN_2_OK_LED_R_N")
	)
	(segment
		(start 36.703 -106.66095)
		(end 35.83305 -105.791)
		(width 0.2794)
		(layer "F.Cu")
		(net "FAN_2_OK_LED_R_N")
	)
	(segment
		(start 35.45205 -107.823)
		(end 35.3441 -107.71505)
		(width 0.2794)
		(layer "F.Cu")
		(net "FAN_2_OK_LED_R_N")
	)
	(segment
		(start 35.3441 -107.71505)
		(end 35.3441 -106.729022)
		(width 0.2794)
		(layer "F.Cu")
		(net "FAN_2_OK_LED_R_N")
	)
	(via
		(at 35.3441 -106.729022)
		(size 0.508)
		(drill 0.254)
		(layers "F.Cu" "B.Cu")
		(net "FAN_2_OK_LED_R_N")
	)
	(segment
		(start 35.2171 -291.973)
		(end 35.2171 -291.084)
		(width 0.2794)
		(layer "F.Cu")
		(net "FAN_0_OK_LED_R_N")
	)
	(segment
		(start 35.32505 -293.116)
		(end 35.2171 -293.00805)
		(width 0.2794)
		(layer "F.Cu")
		(net "FAN_0_OK_LED_R_N")
	)
	(segment
		(start 36.068 -291.084)
		(end 35.2171 -291.084)
		(width 0.2794)
		(layer "F.Cu")
		(net "FAN_0_OK_LED_R_N")
	)
	(segment
		(start 36.1696 -291.1856)
		(end 36.068 -291.084)
		(width 0.2794)
		(layer "F.Cu")
		(net "FAN_0_OK_LED_R_N")
	)
	(segment
		(start 36.93795 -291.1856)
		(end 36.1696 -291.1856)
		(width 0.2794)
		(layer "F.Cu")
		(net "FAN_0_OK_LED_R_N")
	)
	(segment
		(start 35.2171 -293.00805)
		(end 35.2171 -291.973)
		(width 0.2794)
		(layer "F.Cu")
		(net "FAN_0_OK_LED_R_N")
	)
	(via
		(at 35.2171 -291.973)
		(size 0.508)
		(drill 0.254)
		(layers "F.Cu" "B.Cu")
		(net "FAN_0_OK_LED_R_N")
	)
	(segment
		(start 35.4711 -199.61987)
		(end 35.4711 -198.8058)
		(width 0.2794)
		(layer "F.Cu")
		(net "FAN_1_OK_LED_R_N")
	)
	(segment
		(start 35.4711 -200.71715)
		(end 35.4711 -199.61987)
		(width 0.2794)
		(layer "F.Cu")
		(net "FAN_1_OK_LED_R_N")
	)
	(segment
		(start 36.703254 -199.771)
		(end 36.81095 -199.771)
		(width 0.2794)
		(layer "F.Cu")
		(net "FAN_1_OK_LED_R_N")
	)
	(segment
		(start 35.4711 -198.8058)
		(end 35.738054 -198.8058)
		(width 0.2794)
		(layer "F.Cu")
		(net "FAN_1_OK_LED_R_N")
	)
	(segment
		(start 35.32505 -200.8632)
		(end 35.4711 -200.71715)
		(width 0.2794)
		(layer "F.Cu")
		(net "FAN_1_OK_LED_R_N")
	)
	(segment
		(start 35.738054 -198.8058)
		(end 36.703254 -199.771)
		(width 0.2794)
		(layer "F.Cu")
		(net "FAN_1_OK_LED_R_N")
	)
	(via
		(at 35.4711 -199.61987)
		(size 0.508)
		(drill 0.254)
		(layers "F.Cu" "B.Cu")
		(net "FAN_1_OK_LED_R_N")
	)
	(segment
		(start 35.2171 -23.876)
		(end 35.2171 -22.606)
		(width 0.2794)
		(layer "F.Cu")
		(net "FAN_3_FAIL_LED_R_N")
	)
	(segment
		(start 35.2171 -24.61895)
		(end 35.2171 -23.876)
		(width 0.2794)
		(layer "F.Cu")
		(net "FAN_3_FAIL_LED_R_N")
	)
	(segment
		(start 35.32505 -22.49805)
		(end 35.2171 -22.606)
		(width 0.2794)
		(layer "F.Cu")
		(net "FAN_3_FAIL_LED_R_N")
	)
	(segment
		(start 36.703 -22.49805)
		(end 35.32505 -22.49805)
		(width 0.2794)
		(layer "F.Cu")
		(net "FAN_3_FAIL_LED_R_N")
	)
	(segment
		(start 35.19805 -24.638)
		(end 35.2171 -24.61895)
		(width 0.2794)
		(layer "F.Cu")
		(net "FAN_3_FAIL_LED_R_N")
	)
	(via
		(at 35.2171 -23.876)
		(size 0.508)
		(drill 0.254)
		(layers "F.Cu" "B.Cu")
		(net "FAN_3_FAIL_LED_R_N")
	)
	(segment
		(start 35.2171 -18.542)
		(end 35.61715 -18.94205)
		(width 0.2794)
		(layer "F.Cu")
		(net "FAN_3_OK_LED_R_N")
	)
	(segment
		(start 35.61715 -18.94205)
		(end 36.068 -18.94205)
		(width 0.2794)
		(layer "F.Cu")
		(net "FAN_3_OK_LED_R_N")
	)
	(segment
		(start 36.068 -18.94205)
		(end 36.703 -18.94205)
		(width 0.2794)
		(layer "F.Cu")
		(net "FAN_3_OK_LED_R_N")
	)
	(segment
		(start 35.19805 -18.56105)
		(end 35.2171 -18.542)
		(width 0.2794)
		(layer "F.Cu")
		(net "FAN_3_OK_LED_R_N")
	)
	(segment
		(start 35.19805 -20.574)
		(end 35.19805 -18.56105)
		(width 0.2794)
		(layer "F.Cu")
		(net "FAN_3_OK_LED_R_N")
	)
	(via
		(at 36.068 -18.94205)
		(size 0.508)
		(drill 0.254)
		(layers "F.Cu" "B.Cu")
		(net "FAN_3_OK_LED_R_N")
	)
	(via
		(at 18.9992 -254.878078)
		(size 0.6604)
		(drill 0.3302)
		(layers "F.Cu" "B.Cu")
		(net "NC_U398_P1")
	)
	(segment
		(start 17.783556 -254.878078)
		(end 18.9992 -254.878078)
		(width 0.2794)
		(layer "B.Cu")
		(net "NC_U398_P1")
	)
	(via
		(at 3.059938 -254.8636)
		(size 0.6604)
		(drill 0.3302)
		(layers "F.Cu" "B.Cu")
		(net "NC_U397_P1")
	)
	(segment
		(start 3.059938 -253.629922)
		(end 3.059938 -254.8636)
		(width 0.2794)
		(layer "B.Cu")
		(net "NC_U397_P1")
	)
	(via
		(at 18.8849 -70.27799)
		(size 0.6604)
		(drill 0.3302)
		(layers "F.Cu" "B.Cu")
		(net "NC_U393_P1")
	)
	(segment
		(start 17.656556 -70.27799)
		(end 18.8849 -70.27799)
		(width 0.2794)
		(layer "B.Cu")
		(net "NC_U393_P1")
	)
	(via
		(at 1.83896 -68.844922)
		(size 0.6604)
		(drill 0.3302)
		(layers "F.Cu" "B.Cu")
		(net "NC_U392_P1")
	)
	(segment
		(start 3.059938 -68.844922)
		(end 1.83896 -68.844922)
		(width 0.2794)
		(layer "B.Cu")
		(net "NC_U392_P1")
	)
	(via
		(at 46.6344 -255.4478)
		(size 0.6604)
		(drill 0.3302)
		(layers "F.Cu" "B.Cu")
		(net "NC_U394_P1")
	)
	(segment
		(start 45.417994 -254.878078)
		(end 45.987716 -255.4478)
		(width 0.2794)
		(layer "B.Cu")
		(net "NC_U394_P1")
	)
	(segment
		(start 45.987716 -255.4478)
		(end 46.6344 -255.4478)
		(width 0.2794)
		(layer "B.Cu")
		(net "NC_U394_P1")
	)
	(via
		(at 46.6344 -70.27799)
		(size 0.6604)
		(drill 0.3302)
		(layers "F.Cu" "B.Cu")
		(net "NC_U396_P1")
	)
	(segment
		(start 46.6344 -70.27799)
		(end 45.417994 -70.27799)
		(width 0.2794)
		(layer "B.Cu")
		(net "NC_U396_P1")
	)
	(via
		(at 32.6898 -253.921768)
		(size 0.6604)
		(drill 0.3302)
		(layers "F.Cu" "B.Cu")
		(net "NC_U395_P1")
	)
	(segment
		(start 32.6898 -253.921768)
		(end 33.916366 -253.921768)
		(width 0.2794)
		(layer "B.Cu")
		(net "NC_U395_P1")
	)
	(segment
		(start 29.986986 -290.50996)
		(end 30.5562 -291.079174)
		(width 0.2794)
		(layer "F.Cu")
		(net "NC_U402_P1")
	)
	(segment
		(start 30.5562 -291.079174)
		(end 30.5562 -291.719)
		(width 0.2794)
		(layer "F.Cu")
		(net "NC_U402_P1")
	)
	(via
		(at 30.5562 -291.719)
		(size 0.762)
		(drill 0.381)
		(layers "F.Cu" "B.Cu")
		(net "NC_U402_P1")
	)
	(segment
		(start 30.41396 -105.59796)
		(end 31.0134 -106.1974)
		(width 0.2794)
		(layer "F.Cu")
		(net "NC_U400_P1")
	)
	(segment
		(start 29.859986 -105.59796)
		(end 30.41396 -105.59796)
		(width 0.2794)
		(layer "F.Cu")
		(net "NC_U400_P1")
	)
	(via
		(at 31.0134 -106.1974)
		(size 0.762)
		(drill 0.381)
		(layers "F.Cu" "B.Cu")
		(net "NC_U400_P1")
	)
	(segment
		(start 21.24964 -24.70404)
		(end 21.829014 -24.70404)
		(width 0.2794)
		(layer "F.Cu")
		(net "NC_U66_P1")
	)
	(segment
		(start 20.6756 -24.13)
		(end 21.24964 -24.70404)
		(width 0.2794)
		(layer "F.Cu")
		(net "NC_U66_P1")
	)
	(via
		(at 20.6756 -24.13)
		(size 0.762)
		(drill 0.381)
		(layers "F.Cu" "B.Cu")
		(net "NC_U66_P1")
	)
	(segment
		(start 20.4851 -116.2431)
		(end 21.09216 -115.63604)
		(width 0.2794)
		(layer "F.Cu")
		(net "NC_U64_P1")
	)
	(segment
		(start 21.09216 -115.63604)
		(end 21.829014 -115.63604)
		(width 0.2794)
		(layer "F.Cu")
		(net "NC_U64_P1")
	)
	(via
		(at 20.4851 -116.2431)
		(size 0.762)
		(drill 0.381)
		(layers "F.Cu" "B.Cu")
		(net "NC_U64_P1")
	)
	(segment
		(start 20.447 -208.915)
		(end 21.219668 -208.915)
		(width 0.2794)
		(layer "F.Cu")
		(net "NC_U62_P1")
	)
	(segment
		(start 21.829014 -208.305654)
		(end 21.829014 -207.83804)
		(width 0.2794)
		(layer "F.Cu")
		(net "NC_U62_P1")
	)
	(segment
		(start 21.219668 -208.915)
		(end 21.829014 -208.305654)
		(width 0.2794)
		(layer "F.Cu")
		(net "NC_U62_P1")
	)
	(via
		(at 20.447 -208.915)
		(size 0.762)
		(drill 0.381)
		(layers "F.Cu" "B.Cu")
		(net "NC_U62_P1")
	)
	(segment
		(start 20.317714 -300.04004)
		(end 21.829014 -300.04004)
		(width 0.2794)
		(layer "F.Cu")
		(net "NC_U60_P1")
	)
	(via
		(at 20.317714 -300.04004)
		(size 0.762)
		(drill 0.381)
		(layers "F.Cu" "B.Cu")
		(net "NC_U60_P1")
	)
	(segment
		(start 23.5331 -129.9591)
		(end 23.749 -130.175)
		(width 0.1016)
		(layer "F.Cu")
		(net "U330_FAN FS_N")
	)
	(segment
		(start 24.45385 -133.29285)
		(end 25.019 -133.858)
		(width 0.2794)
		(layer "F.Cu")
		(net "U330_FAN FS_N")
	)
	(segment
		(start 24.45385 -132.0165)
		(end 24.45385 -133.29285)
		(width 0.2794)
		(layer "F.Cu")
		(net "U330_FAN FS_N")
	)
	(segment
		(start 22.954996 -129.9591)
		(end 23.5331 -129.9591)
		(width 0.1016)
		(layer "F.Cu")
		(net "U330_FAN FS_N")
	)
	(segment
		(start 25.019 -133.858)
		(end 25.12695 -133.858)
		(width 0.2794)
		(layer "F.Cu")
		(net "U330_FAN FS_N")
	)
	(segment
		(start 23.749 -130.175)
		(end 24.003 -130.175)
		(width 0.1016)
		(layer "F.Cu")
		(net "U330_FAN FS_N")
	)
	(segment
		(start 24.45385 -130.62585)
		(end 24.45385 -132.0165)
		(width 0.2794)
		(layer "F.Cu")
		(net "U330_FAN FS_N")
	)
	(segment
		(start 24.003 -130.175)
		(end 24.45385 -130.62585)
		(width 0.2794)
		(layer "F.Cu")
		(net "U330_FAN FS_N")
	)
	(via
		(at 24.45385 -132.0165)
		(size 0.508)
		(drill 0.254)
		(layers "F.Cu" "B.Cu")
		(net "U330_FAN FS_N")
	)
	(segment
		(start 23.906988 -126.926594)
		(end 24.033988 -127.053594)
		(width 0.2794)
		(layer "F.Cu")
		(net "U330_FAN FAIL_N")
	)
	(segment
		(start 25.92705 -135.001)
		(end 25.92705 -135.636)
		(width 0.2794)
		(layer "F.Cu")
		(net "U330_FAN FAIL_N")
	)
	(segment
		(start 24.033988 -127.053594)
		(end 24.033988 -128.319276)
		(width 0.1016)
		(layer "F.Cu")
		(net "U330_FAN FAIL_N")
	)
	(segment
		(start 25.92705 -133.858)
		(end 25.92705 -135.001)
		(width 0.2794)
		(layer "F.Cu")
		(net "U330_FAN FAIL_N")
	)
	(segment
		(start 23.906988 -125.691646)
		(end 23.906988 -126.926594)
		(width 0.2794)
		(layer "F.Cu")
		(net "U330_FAN FAIL_N")
	)
	(segment
		(start 23.594314 -128.75895)
		(end 22.954996 -128.75895)
		(width 0.1016)
		(layer "F.Cu")
		(net "U330_FAN FAIL_N")
	)
	(segment
		(start 24.033988 -128.319276)
		(end 23.594314 -128.75895)
		(width 0.1016)
		(layer "F.Cu")
		(net "U330_FAN FAIL_N")
	)
	(segment
		(start 24.176736 -125.421898)
		(end 23.906988 -125.691646)
		(width 0.2794)
		(layer "F.Cu")
		(net "U330_FAN FAIL_N")
	)
	(via
		(at 24.176736 -125.421898)
		(size 0.508)
		(drill 0.254)
		(layers "F.Cu" "B.Cu")
		(net "U330_FAN FAIL_N")
	)
	(via
		(at 25.92705 -135.636)
		(size 0.508)
		(drill 0.254)
		(layers "F.Cu" "B.Cu")
		(net "U330_FAN FAIL_N")
	)
	(segment
		(start 24.176736 -126.672594)
		(end 24.176736 -125.421898)
		(width 0.2286)
		(layer "In2.Cu")
		(net "U330_FAN FAIL_N")
	)
	(segment
		(start 23.8125 -127.03683)
		(end 24.176736 -126.672594)
		(width 0.2286)
		(layer "In2.Cu")
		(net "U330_FAN FAIL_N")
	)
	(segment
		(start 23.8125 -132.64515)
		(end 23.8125 -127.03683)
		(width 0.2286)
		(layer "In2.Cu")
		(net "U330_FAN FAIL_N")
	)
	(segment
		(start 25.92705 -134.7597)
		(end 23.8125 -132.64515)
		(width 0.2286)
		(layer "In2.Cu")
		(net "U330_FAN FAIL_N")
	)
	(segment
		(start 25.92705 -135.636)
		(end 25.92705 -134.7597)
		(width 0.2286)
		(layer "In2.Cu")
		(net "U330_FAN FAIL_N")
	)
	(segment
		(start 27.559 -130.048)
		(end 27.813 -129.794)
		(width 0.2794)
		(layer "F.Cu")
		(net "U317_FAN FAIL_N")
	)
	(segment
		(start 27.813 -129.794)
		(end 28.04795 -129.55905)
		(width 0.1016)
		(layer "F.Cu")
		(net "U317_FAN FAIL_N")
	)
	(segment
		(start 27.686 -123.19)
		(end 27.686 -123.80595)
		(width 0.2794)
		(layer "F.Cu")
		(net "U317_FAN FAIL_N")
	)
	(segment
		(start 28.04795 -129.55905)
		(end 29.496004 -129.55905)
		(width 0.1016)
		(layer "F.Cu")
		(net "U317_FAN FAIL_N")
	)
	(segment
		(start 27.686 -122.32005)
		(end 27.686 -123.19)
		(width 0.2794)
		(layer "F.Cu")
		(net "U317_FAN FAIL_N")
	)
	(via
		(at 27.686 -123.19)
		(size 0.508)
		(drill 0.254)
		(layers "F.Cu" "B.Cu")
		(net "U317_FAN FAIL_N")
	)
	(via
		(at 27.559 -130.048)
		(size 0.508)
		(drill 0.254)
		(layers "F.Cu" "B.Cu")
		(net "U317_FAN FAIL_N")
	)
	(segment
		(start 27.432 -126.5174)
		(end 27.1653 -126.7841)
		(width 0.2286)
		(layer "In2.Cu")
		(net "U317_FAN FAIL_N")
	)
	(segment
		(start 27.559 -129.413)
		(end 27.559 -130.048)
		(width 0.2286)
		(layer "In2.Cu")
		(net "U317_FAN FAIL_N")
	)
	(segment
		(start 27.432 -123.444)
		(end 27.432 -126.5174)
		(width 0.2286)
		(layer "In2.Cu")
		(net "U317_FAN FAIL_N")
	)
	(segment
		(start 27.1653 -129.0193)
		(end 27.559 -129.413)
		(width 0.2286)
		(layer "In2.Cu")
		(net "U317_FAN FAIL_N")
	)
	(segment
		(start 27.686 -123.19)
		(end 27.432 -123.444)
		(width 0.2286)
		(layer "In2.Cu")
		(net "U317_FAN FAIL_N")
	)
	(segment
		(start 27.1653 -126.7841)
		(end 27.1653 -129.0193)
		(width 0.2286)
		(layer "In2.Cu")
		(net "U317_FAN FAIL_N")
	)
	(segment
		(start 28.46578 -126.38278)
		(end 27.686 -125.603)
		(width 0.2794)
		(layer "F.Cu")
		(net "U317_FAN FS_N")
	)
	(segment
		(start 28.9179 -128.3589)
		(end 29.496004 -128.3589)
		(width 0.1016)
		(layer "F.Cu")
		(net "U317_FAN FS_N")
	)
	(segment
		(start 28.575 -128.016)
		(end 28.9179 -128.3589)
		(width 0.1016)
		(layer "F.Cu")
		(net "U317_FAN FS_N")
	)
	(segment
		(start 28.46578 -126.94666)
		(end 28.46578 -127.90678)
		(width 0.2794)
		(layer "F.Cu")
		(net "U317_FAN FS_N")
	)
	(segment
		(start 28.46578 -126.94666)
		(end 28.46578 -126.38278)
		(width 0.2794)
		(layer "F.Cu")
		(net "U317_FAN FS_N")
	)
	(segment
		(start 28.46578 -127.90678)
		(end 28.575 -128.016)
		(width 0.2794)
		(layer "F.Cu")
		(net "U317_FAN FS_N")
	)
	(segment
		(start 27.686 -125.603)
		(end 27.686 -124.60605)
		(width 0.2794)
		(layer "F.Cu")
		(net "U317_FAN FS_N")
	)
	(via
		(at 28.46578 -126.94666)
		(size 0.508)
		(drill 0.254)
		(layers "F.Cu" "B.Cu")
		(net "U317_FAN FS_N")
	)
	(segment
		(start -8.208772 -287.44545)
		(end -8.208772 -212.644736)
		(width 0.2794)
		(layer "F.Cu")
		(net "TDR_SE_50_OHM_TOP")
	)
	(segment
		(start -7.841742 -287.81248)
		(end -8.208772 -287.44545)
		(width 0.2794)
		(layer "F.Cu")
		(net "TDR_SE_50_OHM_TOP")
	)
	(segment
		(start -5.668772 -212.644736)
		(end -5.668772 -287.444688)
		(width 0.2794)
		(layer "F.Cu")
		(net "TDR_SE_50_OHM_TOP")
	)
	(segment
		(start -5.668772 -287.444688)
		(end -6.036564 -287.81248)
		(width 0.2794)
		(layer "F.Cu")
		(net "TDR_SE_50_OHM_TOP")
	)
	(segment
		(start -6.036564 -287.81248)
		(end -7.841742 -287.81248)
		(width 0.2794)
		(layer "F.Cu")
		(net "TDR_SE_50_OHM_TOP")
	)
	(segment
		(start -5.668772 -217.996008)
		(end -5.668772 -292.815264)
		(width 0.2286)
		(layer "In3.Cu")
		(net "TDR_SE_50_OHM_IN2")
	)
	(segment
		(start -8.208772 -217.999818)
		(end -7.904734 -217.69578)
		(width 0.2286)
		(layer "In3.Cu")
		(net "TDR_SE_50_OHM_IN2")
	)
	(segment
		(start -5.969 -217.69578)
		(end -5.668772 -217.996008)
		(width 0.2286)
		(layer "In3.Cu")
		(net "TDR_SE_50_OHM_IN2")
	)
	(segment
		(start -7.904734 -217.69578)
		(end -5.969 -217.69578)
		(width 0.2286)
		(layer "In3.Cu")
		(net "TDR_SE_50_OHM_IN2")
	)
	(segment
		(start -8.208772 -292.815264)
		(end -8.208772 -217.999818)
		(width 0.2286)
		(layer "In3.Cu")
		(net "TDR_SE_50_OHM_IN2")
	)
	(segment
		(start -16.111474 -292.815264)
		(end -16.111474 -218.063318)
		(width 0.2286)
		(layer "In2.Cu")
		(net "TDR_SE_50_OHM_IN1")
	)
	(segment
		(start -14.031722 -217.59926)
		(end -13.571474 -218.059508)
		(width 0.2286)
		(layer "In2.Cu")
		(net "TDR_SE_50_OHM_IN1")
	)
	(segment
		(start -15.647416 -217.59926)
		(end -14.031722 -217.59926)
		(width 0.2286)
		(layer "In2.Cu")
		(net "TDR_SE_50_OHM_IN1")
	)
	(segment
		(start -13.571474 -218.059508)
		(end -13.571474 -292.815264)
		(width 0.2286)
		(layer "In2.Cu")
		(net "TDR_SE_50_OHM_IN1")
	)
	(segment
		(start -16.111474 -218.063318)
		(end -15.647416 -217.59926)
		(width 0.2286)
		(layer "In2.Cu")
		(net "TDR_SE_50_OHM_IN1")
	)
	(segment
		(start -16.197834 -287.40735)
		(end -16.197834 -212.731096)
		(width 0.2794)
		(layer "B.Cu")
		(net "TDR_SE_50_OHM_BOT")
	)
	(segment
		(start -15.810484 -287.7947)
		(end -16.197834 -287.40735)
		(width 0.2794)
		(layer "B.Cu")
		(net "TDR_SE_50_OHM_BOT")
	)
	(segment
		(start -16.197834 -212.731096)
		(end -16.111474 -212.644736)
		(width 0.2794)
		(layer "B.Cu")
		(net "TDR_SE_50_OHM_BOT")
	)
	(segment
		(start -13.571474 -212.644736)
		(end -13.657834 -212.731096)
		(width 0.2794)
		(layer "B.Cu")
		(net "TDR_SE_50_OHM_BOT")
	)
	(segment
		(start -13.657834 -287.406588)
		(end -14.045946 -287.7947)
		(width 0.2794)
		(layer "B.Cu")
		(net "TDR_SE_50_OHM_BOT")
	)
	(segment
		(start -13.657834 -212.731096)
		(end -13.657834 -287.406588)
		(width 0.2794)
		(layer "B.Cu")
		(net "TDR_SE_50_OHM_BOT")
	)
	(segment
		(start -14.045946 -287.7947)
		(end -15.810484 -287.7947)
		(width 0.2794)
		(layer "B.Cu")
		(net "TDR_SE_50_OHM_BOT")
	)
	(segment
		(start 8.74395 -184.785)
		(end 8.61695 -184.912)
		(width 0.2794)
		(layer "F.Cu")
		(net "PU_U7_PIN2")
	)
	(segment
		(start 7.366 -184.912)
		(end 7.366 -183.53405)
		(width 0.2794)
		(layer "F.Cu")
		(net "PU_U7_PIN2")
	)
	(segment
		(start 8.61695 -184.912)
		(end 7.366 -184.912)
		(width 0.2794)
		(layer "F.Cu")
		(net "PU_U7_PIN2")
	)
	(via
		(at 7.366 -184.912)
		(size 0.762)
		(drill 0.381)
		(layers "F.Cu" "B.Cu")
		(net "PU_U7_PIN2")
	)
	(segment
		(start 17.9324 -288.036)
		(end 18.279872 -288.383472)
		(width 0.2794)
		(layer "F.Cu")
		(net "FAN_7_TACH_IL_R")
	)
	(segment
		(start 17.446244 -289.558222)
		(end 17.446244 -288.522156)
		(width 0.2794)
		(layer "F.Cu")
		(net "FAN_7_TACH_IL_R")
	)
	(segment
		(start 18.279872 -288.383472)
		(end 18.279872 -289.168078)
		(width 0.2794)
		(layer "F.Cu")
		(net "FAN_7_TACH_IL_R")
	)
	(segment
		(start 16.470122 -289.278568)
		(end 16.749776 -289.558222)
		(width 0.2794)
		(layer "F.Cu")
		(net "FAN_7_TACH_IL_R")
	)
	(segment
		(start 18.279872 -290.2331)
		(end 18.279872 -289.189922)
		(width 0.2794)
		(layer "F.Cu")
		(net "FAN_7_TACH_IL_R")
	)
	(segment
		(start 18.279872 -289.189922)
		(end 18.26895 -289.179)
		(width 0.2794)
		(layer "F.Cu")
		(net "FAN_7_TACH_IL_R")
	)
	(segment
		(start 17.446244 -288.522156)
		(end 17.9324 -288.036)
		(width 0.2794)
		(layer "F.Cu")
		(net "FAN_7_TACH_IL_R")
	)
	(segment
		(start 16.749776 -289.558222)
		(end 17.446244 -289.558222)
		(width 0.2794)
		(layer "F.Cu")
		(net "FAN_7_TACH_IL_R")
	)
	(segment
		(start 18.279872 -289.168078)
		(end 18.26895 -289.179)
		(width 0.2794)
		(layer "F.Cu")
		(net "FAN_7_TACH_IL_R")
	)
	(segment
		(start 16.470122 -288.5821)
		(end 16.470122 -289.278568)
		(width 0.2794)
		(layer "F.Cu")
		(net "FAN_7_TACH_IL_R")
	)
	(via
		(at 17.446244 -289.558222)
		(size 0.508)
		(drill 0.254)
		(layers "F.Cu" "B.Cu")
		(net "FAN_7_TACH_IL_R")
	)
	(segment
		(start 17.79905 -211.836)
		(end 18.77695 -211.836)
		(width 0.2794)
		(layer "F.Cu")
		(net "FAN_6_TACH_OL_R")
	)
	(segment
		(start 17.79905 -211.181696)
		(end 17.79905 -211.836)
		(width 0.2794)
		(layer "F.Cu")
		(net "FAN_6_TACH_OL_R")
	)
	(segment
		(start 17.270222 -210.252056)
		(end 17.457166 -210.439)
		(width 0.2794)
		(layer "F.Cu")
		(net "FAN_6_TACH_OL_R")
	)
	(segment
		(start 18.0594 -210.439)
		(end 18.0594 -210.921346)
		(width 0.2794)
		(layer "F.Cu")
		(net "FAN_6_TACH_OL_R")
	)
	(segment
		(start 16.470122 -210.125056)
		(end 17.143222 -210.125056)
		(width 0.2794)
		(layer "F.Cu")
		(net "FAN_6_TACH_OL_R")
	)
	(segment
		(start 17.143222 -210.125056)
		(end 17.270222 -210.252056)
		(width 0.2794)
		(layer "F.Cu")
		(net "FAN_6_TACH_OL_R")
	)
	(segment
		(start 17.457166 -210.439)
		(end 18.0594 -210.439)
		(width 0.2794)
		(layer "F.Cu")
		(net "FAN_6_TACH_OL_R")
	)
	(segment
		(start 18.0594 -210.921346)
		(end 17.79905 -211.181696)
		(width 0.2794)
		(layer "F.Cu")
		(net "FAN_6_TACH_OL_R")
	)
	(via
		(at 17.270222 -210.252056)
		(size 0.508)
		(drill 0.254)
		(layers "F.Cu" "B.Cu")
		(net "FAN_6_TACH_OL_R")
	)
	(segment
		(start 16.597122 -30.566868)
		(end 16.597122 -29.519118)
		(width 0.2794)
		(layer "F.Cu")
		(net "FAN_4_TACH_OL_R")
	)
	(segment
		(start 18.019522 -30.353)
		(end 18.161 -30.494478)
		(width 0.2794)
		(layer "F.Cu")
		(net "FAN_4_TACH_OL_R")
	)
	(segment
		(start 18.161 -31.60395)
		(end 19.177 -31.60395)
		(width 0.2794)
		(layer "F.Cu")
		(net "FAN_4_TACH_OL_R")
	)
	(segment
		(start 18.019522 -29.373068)
		(end 18.019522 -30.353)
		(width 0.2794)
		(layer "F.Cu")
		(net "FAN_4_TACH_OL_R")
	)
	(segment
		(start 17.09674 -29.0195)
		(end 17.665954 -29.0195)
		(width 0.2794)
		(layer "F.Cu")
		(net "FAN_4_TACH_OL_R")
	)
	(segment
		(start 17.665954 -29.0195)
		(end 18.019522 -29.373068)
		(width 0.2794)
		(layer "F.Cu")
		(net "FAN_4_TACH_OL_R")
	)
	(segment
		(start 16.597122 -29.519118)
		(end 17.09674 -29.0195)
		(width 0.2794)
		(layer "F.Cu")
		(net "FAN_4_TACH_OL_R")
	)
	(segment
		(start 18.161 -30.494478)
		(end 18.161 -31.60395)
		(width 0.2794)
		(layer "F.Cu")
		(net "FAN_4_TACH_OL_R")
	)
	(via
		(at 17.09674 -29.0195)
		(size 0.762)
		(drill 0.381)
		(layers "F.Cu" "B.Cu")
		(net "FAN_4_TACH_OL_R")
	)
	(segment
		(start 40.837358 -70.024752)
		(end 40.125142 -70.024752)
		(width 0.2794)
		(layer "F.Cu")
		(net "FAN_2_ON")
	)
	(segment
		(start 40.125142 -70.024752)
		(end 39.606982 -70.542912)
		(width 0.2794)
		(layer "F.Cu")
		(net "FAN_2_ON")
	)
	(via
		(at 41.346882 -76.571602)
		(size 0.508)
		(drill 0.254)
		(layers "F.Cu" "B.Cu")
		(net "FAN_2_ON")
	)
	(via
		(at 40.837358 -70.024752)
		(size 0.762)
		(drill 0.254)
		(layers "F.Cu" "B.Cu")
		(net "FAN_2_ON")
	)
	(segment
		(start 41.346882 -76.571602)
		(end 41.416732 -76.740258)
		(width 0.1016)
		(layer "B.Cu")
		(net "FAN_2_ON")
	)
	(segment
		(start 41.416732 -76.740258)
		(end 41.416732 -77.45476)
		(width 0.1016)
		(layer "B.Cu")
		(net "FAN_2_ON")
	)
	(segment
		(start 41.210484 -76.708)
		(end 40.386 -76.708)
		(width 0.2286)
		(layer "In2.Cu")
		(net "FAN_2_ON")
	)
	(segment
		(start 40.258492 -70.024752)
		(end 40.837358 -70.024752)
		(width 0.2286)
		(layer "In2.Cu")
		(net "FAN_2_ON")
	)
	(segment
		(start 40.386 -76.708)
		(end 39.3192 -75.6412)
		(width 0.2286)
		(layer "In2.Cu")
		(net "FAN_2_ON")
	)
	(segment
		(start 39.3192 -70.964044)
		(end 40.258492 -70.024752)
		(width 0.2286)
		(layer "In2.Cu")
		(net "FAN_2_ON")
	)
	(segment
		(start 41.346882 -76.571602)
		(end 41.210484 -76.708)
		(width 0.2286)
		(layer "In2.Cu")
		(net "FAN_2_ON")
	)
	(segment
		(start 39.3192 -75.6412)
		(end 39.3192 -70.964044)
		(width 0.2286)
		(layer "In2.Cu")
		(net "FAN_2_ON")
	)
	(segment
		(start 42.235882 -71.831962)
		(end 42.635932 -71.431912)
		(width 0.2794)
		(layer "F.Cu")
		(net "FAN_2_PRESENT_R")
	)
	(segment
		(start 42.635932 -71.431912)
		(end 42.635932 -70.94474)
		(width 0.2794)
		(layer "F.Cu")
		(net "FAN_2_PRESENT_R")
	)
	(segment
		(start 42.235882 -72.066912)
		(end 42.235882 -71.831962)
		(width 0.2794)
		(layer "F.Cu")
		(net "FAN_2_PRESENT_R")
	)
	(via
		(at 42.635932 -70.94474)
		(size 0.508)
		(drill 0.254)
		(layers "F.Cu" "B.Cu")
		(net "FAN_2_PRESENT_R")
	)
	(segment
		(start 42.635932 -71.431912)
		(end 42.112946 -71.954898)
		(width 0.2794)
		(layer "B.Cu")
		(net "FAN_2_PRESENT_R")
	)
	(segment
		(start 42.112946 -71.954898)
		(end 40.931338 -71.954898)
		(width 0.2794)
		(layer "B.Cu")
		(net "FAN_2_PRESENT_R")
	)
	(segment
		(start 42.635932 -70.94474)
		(end 42.635932 -71.431912)
		(width 0.2794)
		(layer "B.Cu")
		(net "FAN_2_PRESENT_R")
	)
	(segment
		(start 39.0779 -99.455986)
		(end 38.027864 -98.40595)
		(width 0.2794)
		(layer "F.Cu")
		(net "FAN_2_PRESENT")
	)
	(segment
		(start 43.035982 -72.682862)
		(end 43.016932 -72.701912)
		(width 0.2794)
		(layer "F.Cu")
		(net "FAN_2_PRESENT")
	)
	(segment
		(start 38.027864 -98.40595)
		(end 37.719 -98.40595)
		(width 0.2794)
		(layer "F.Cu")
		(net "FAN_2_PRESENT")
	)
	(segment
		(start 29.22905 -98.40595)
		(end 37.719 -98.40595)
		(width 0.2794)
		(layer "F.Cu")
		(net "FAN_2_PRESENT")
	)
	(segment
		(start 43.035982 -72.066912)
		(end 43.035982 -72.682862)
		(width 0.2794)
		(layer "F.Cu")
		(net "FAN_2_PRESENT")
	)
	(segment
		(start 27.94 -99.695)
		(end 29.22905 -98.40595)
		(width 0.2794)
		(layer "F.Cu")
		(net "FAN_2_PRESENT")
	)
	(via
		(at 27.94 -99.695)
		(size 0.762)
		(drill 0.254)
		(layers "F.Cu" "B.Cu")
		(net "FAN_2_PRESENT")
	)
	(via
		(at 43.016932 -72.701912)
		(size 0.508)
		(drill 0.254)
		(layers "F.Cu" "B.Cu")
		(net "FAN_2_PRESENT")
	)
	(segment
		(start 26.0985 -74.7395)
		(end 29.337 -71.501)
		(width 0.2794)
		(layer "B.Cu")
		(net "FAN_2_PRESENT")
	)
	(segment
		(start 29.337 -71.501)
		(end 36.449 -71.501)
		(width 0.2794)
		(layer "B.Cu")
		(net "FAN_2_PRESENT")
	)
	(segment
		(start 27.94 -97.536)
		(end 26.0985 -95.6945)
		(width 0.2794)
		(layer "B.Cu")
		(net "FAN_2_PRESENT")
	)
	(segment
		(start 37.649912 -72.701912)
		(end 43.016932 -72.701912)
		(width 0.2794)
		(layer "B.Cu")
		(net "FAN_2_PRESENT")
	)
	(segment
		(start 43.293792 -72.701912)
		(end 43.91787 -72.077834)
		(width 0.2794)
		(layer "B.Cu")
		(net "FAN_2_PRESENT")
	)
	(segment
		(start 36.449 -71.501)
		(end 37.649912 -72.701912)
		(width 0.2794)
		(layer "B.Cu")
		(net "FAN_2_PRESENT")
	)
	(segment
		(start 26.0985 -95.6945)
		(end 26.0985 -74.7395)
		(width 0.2794)
		(layer "B.Cu")
		(net "FAN_2_PRESENT")
	)
	(segment
		(start 27.94 -99.695)
		(end 27.94 -97.536)
		(width 0.2794)
		(layer "B.Cu")
		(net "FAN_2_PRESENT")
	)
	(segment
		(start 43.016932 -72.701912)
		(end 43.293792 -72.701912)
		(width 0.2794)
		(layer "B.Cu")
		(net "FAN_2_PRESENT")
	)
	(via
		(at 40.825928 -248.403364)
		(size 0.762)
		(drill 0.254)
		(layers "F.Cu" "B.Cu")
		(net "FAN_1_TEMP")
	)
	(segment
		(start 40.36441 -247.941846)
		(end 39.746428 -247.941846)
		(width 0.2794)
		(layer "B.Cu")
		(net "FAN_1_TEMP")
	)
	(segment
		(start 41.12768 -249.83694)
		(end 41.12768 -248.705116)
		(width 0.2794)
		(layer "B.Cu")
		(net "FAN_1_TEMP")
	)
	(segment
		(start 41.12768 -249.83694)
		(end 42.164 -249.83694)
		(width 0.2794)
		(layer "B.Cu")
		(net "FAN_1_TEMP")
	)
	(segment
		(start 39.746428 -247.941846)
		(end 39.117778 -247.313196)
		(width 0.1016)
		(layer "B.Cu")
		(net "FAN_1_TEMP")
	)
	(segment
		(start 39.117778 -247.313196)
		(end 39.117778 -246.744998)
		(width 0.1016)
		(layer "B.Cu")
		(net "FAN_1_TEMP")
	)
	(segment
		(start 41.12768 -248.705116)
		(end 40.825928 -248.403364)
		(width 0.2794)
		(layer "B.Cu")
		(net "FAN_1_TEMP")
	)
	(segment
		(start 40.825928 -248.403364)
		(end 40.36441 -247.941846)
		(width 0.2794)
		(layer "B.Cu")
		(net "FAN_1_TEMP")
	)
	(segment
		(start 13.531088 -107.880912)
		(end 12.7 -108.712)
		(width 0.2794)
		(layer "F.Cu")
		(net "SMB_FAN5_SCL_R")
	)
	(segment
		(start 12.7 -108.712)
		(end 12.697968 -108.709968)
		(width 0.2794)
		(layer "F.Cu")
		(net "SMB_FAN5_SCL_R")
	)
	(segment
		(start 12.697968 -108.709968)
		(end 8.700008 -108.709968)
		(width 0.2794)
		(layer "F.Cu")
		(net "SMB_FAN5_SCL_R")
	)
	(segment
		(start 13.95095 -107.880912)
		(end 13.531088 -107.880912)
		(width 0.2794)
		(layer "F.Cu")
		(net "SMB_FAN5_SCL_R")
	)
	(via
		(at 12.7 -108.712)
		(size 0.762)
		(drill 0.381)
		(layers "F.Cu" "B.Cu")
		(net "SMB_FAN5_SCL_R")
	)
	(via
		(at 34.031428 -248.688098)
		(size 0.6604)
		(drill 0.3302)
		(layers "F.Cu" "B.Cu")
		(net "FAN_1_IMON")
	)
	(segment
		(start 35.517582 -247.201944)
		(end 35.03168 -247.687846)
		(width 0.1016)
		(layer "B.Cu")
		(net "FAN_1_IMON")
	)
	(segment
		(start 35.517582 -246.744998)
		(end 35.517582 -247.201944)
		(width 0.1016)
		(layer "B.Cu")
		(net "FAN_1_IMON")
	)
	(segment
		(start 33.147 -249.83694)
		(end 33.147 -249.572526)
		(width 0.2794)
		(layer "B.Cu")
		(net "FAN_1_IMON")
	)
	(segment
		(start 33.147 -249.572526)
		(end 34.031428 -248.688098)
		(width 0.2794)
		(layer "B.Cu")
		(net "FAN_1_IMON")
	)
	(segment
		(start 35.03168 -247.687846)
		(end 34.031428 -248.688098)
		(width 0.2794)
		(layer "B.Cu")
		(net "FAN_1_IMON")
	)
	(via
		(at 35.20567 -248.322846)
		(size 0.762)
		(drill 0.254)
		(layers "F.Cu" "B.Cu")
		(net "FAN_1_SS")
	)
	(segment
		(start 34.26206 -249.83694)
		(end 34.163 -249.83694)
		(width 0.2794)
		(layer "B.Cu")
		(net "FAN_1_SS")
	)
	(segment
		(start 35.20567 -248.89333)
		(end 34.26206 -249.83694)
		(width 0.2794)
		(layer "B.Cu")
		(net "FAN_1_SS")
	)
	(segment
		(start 35.198558 -248.315734)
		(end 35.198558 -248.171716)
		(width 0.1016)
		(layer "B.Cu")
		(net "FAN_1_SS")
	)
	(segment
		(start 35.198558 -248.171716)
		(end 35.917632 -247.452642)
		(width 0.1016)
		(layer "B.Cu")
		(net "FAN_1_SS")
	)
	(segment
		(start 35.917632 -247.452642)
		(end 35.917632 -246.744998)
		(width 0.1016)
		(layer "B.Cu")
		(net "FAN_1_SS")
	)
	(segment
		(start 35.20567 -248.322846)
		(end 35.20567 -248.89333)
		(width 0.2794)
		(layer "B.Cu")
		(net "FAN_1_SS")
	)
	(segment
		(start 35.20567 -248.322846)
		(end 35.198558 -248.315734)
		(width 0.1016)
		(layer "B.Cu")
		(net "FAN_1_SS")
	)
	(segment
		(start 17.377664 -16.215868)
		(end 16.470122 -16.215868)
		(width 0.2794)
		(layer "F.Cu")
		(net "FAN_4_TACH_IL_R")
	)
	(segment
		(start 17.377664 -16.215868)
		(end 17.591532 -16.002)
		(width 0.2794)
		(layer "F.Cu")
		(net "FAN_4_TACH_IL_R")
	)
	(segment
		(start 18.415 -17.12595)
		(end 18.43405 -17.145)
		(width 0.2794)
		(layer "F.Cu")
		(net "FAN_4_TACH_IL_R")
	)
	(segment
		(start 18.910046 -17.145)
		(end 18.914364 -17.149318)
		(width 0.2794)
		(layer "F.Cu")
		(net "FAN_4_TACH_IL_R")
	)
	(segment
		(start 18.415 -16.1036)
		(end 18.415 -17.12595)
		(width 0.2794)
		(layer "F.Cu")
		(net "FAN_4_TACH_IL_R")
	)
	(segment
		(start 17.591532 -16.002)
		(end 18.3134 -16.002)
		(width 0.2794)
		(layer "F.Cu")
		(net "FAN_4_TACH_IL_R")
	)
	(segment
		(start 18.43405 -17.145)
		(end 18.910046 -17.145)
		(width 0.2794)
		(layer "F.Cu")
		(net "FAN_4_TACH_IL_R")
	)
	(segment
		(start 19.407632 -17.149318)
		(end 19.431 -17.12595)
		(width 0.2794)
		(layer "F.Cu")
		(net "FAN_4_TACH_IL_R")
	)
	(segment
		(start 18.3134 -16.002)
		(end 18.415 -16.1036)
		(width 0.2794)
		(layer "F.Cu")
		(net "FAN_4_TACH_IL_R")
	)
	(segment
		(start 18.914364 -17.149318)
		(end 19.407632 -17.149318)
		(width 0.2794)
		(layer "F.Cu")
		(net "FAN_4_TACH_IL_R")
	)
	(via
		(at 17.377664 -16.215868)
		(size 0.508)
		(drill 0.254)
		(layers "F.Cu" "B.Cu")
		(net "FAN_4_TACH_IL_R")
	)
	(segment
		(start 38.608 -251.206)
		(end 38.989 -250.825)
		(width 0.2794)
		(layer "F.Cu")
		(net "FAN_1_P3V_R")
	)
	(segment
		(start 37.86505 -250.19)
		(end 37.86505 -251.206)
		(width 0.2794)
		(layer "F.Cu")
		(net "FAN_1_P3V_R")
	)
	(segment
		(start 38.989 -248.7295)
		(end 38.817042 -248.557542)
		(width 0.2794)
		(layer "F.Cu")
		(net "FAN_1_P3V_R")
	)
	(segment
		(start 37.86505 -251.206)
		(end 38.608 -251.206)
		(width 0.2794)
		(layer "F.Cu")
		(net "FAN_1_P3V_R")
	)
	(segment
		(start 38.989 -250.825)
		(end 38.989 -248.7295)
		(width 0.2794)
		(layer "F.Cu")
		(net "FAN_1_P3V_R")
	)
	(via
		(at 38.817042 -248.557542)
		(size 0.762)
		(drill 0.254)
		(layers "F.Cu" "B.Cu")
		(net "FAN_1_P3V_R")
	)
	(segment
		(start 38.512242 -247.82145)
		(end 38.817042 -248.557542)
		(width 0.1016)
		(layer "B.Cu")
		(net "FAN_1_P3V_R")
	)
	(segment
		(start 38.317678 -246.744998)
		(end 38.317678 -247.136666)
		(width 0.1016)
		(layer "B.Cu")
		(net "FAN_1_P3V_R")
	)
	(segment
		(start 38.512242 -247.606566)
		(end 38.512242 -247.82145)
		(width 0.1016)
		(layer "B.Cu")
		(net "FAN_1_P3V_R")
	)
	(segment
		(start 38.317678 -247.136666)
		(end 38.512242 -247.606566)
		(width 0.1016)
		(layer "B.Cu")
		(net "FAN_1_P3V_R")
	)
	(segment
		(start 38.817042 -248.557542)
		(end 38.817042 -248.621042)
		(width 0.2794)
		(layer "B.Cu")
		(net "FAN_1_P3V_R")
	)
	(segment
		(start 38.817042 -248.621042)
		(end 38.989 -248.793)
		(width 0.2794)
		(layer "B.Cu")
		(net "FAN_1_P3V_R")
	)
	(segment
		(start 38.989 -248.793)
		(end 38.989 -249.83694)
		(width 0.2794)
		(layer "B.Cu")
		(net "FAN_1_P3V_R")
	)
	(segment
		(start 36.717732 -248.286016)
		(end 36.459668 -248.909332)
		(width 0.1016)
		(layer "B.Cu")
		(net "FAN_1_TIMER")
	)
	(segment
		(start 36.717732 -246.744998)
		(end 36.717732 -248.286016)
		(width 0.1016)
		(layer "B.Cu")
		(net "FAN_1_TIMER")
	)
	(segment
		(start 36.322 -249.047)
		(end 35.96894 -249.047)
		(width 0.2794)
		(layer "B.Cu")
		(net "FAN_1_TIMER")
	)
	(segment
		(start 36.459668 -248.909332)
		(end 36.322 -249.047)
		(width 0.2794)
		(layer "B.Cu")
		(net "FAN_1_TIMER")
	)
	(segment
		(start 35.96894 -249.047)
		(end 35.179 -249.83694)
		(width 0.2794)
		(layer "B.Cu")
		(net "FAN_1_TIMER")
	)
	(via
		(at 37.21227 -248.61393)
		(size 0.6604)
		(drill 0.3302)
		(layers "F.Cu" "B.Cu")
		(net "FAN_1_CLREF")
	)
	(segment
		(start 37.21227 -248.61393)
		(end 37.117782 -248.708418)
		(width 0.2794)
		(layer "B.Cu")
		(net "FAN_1_CLREF")
	)
	(segment
		(start 36.195 -249.83694)
		(end 37.211 -249.83694)
		(width 0.2794)
		(layer "B.Cu")
		(net "FAN_1_CLREF")
	)
	(segment
		(start 37.117782 -249.334782)
		(end 37.211 -249.428)
		(width 0.2794)
		(layer "B.Cu")
		(net "FAN_1_CLREF")
	)
	(segment
		(start 37.21227 -248.61393)
		(end 37.21227 -248.49963)
		(width 0.1016)
		(layer "B.Cu")
		(net "FAN_1_CLREF")
	)
	(segment
		(start 37.211 -249.428)
		(end 37.211 -249.83694)
		(width 0.2794)
		(layer "B.Cu")
		(net "FAN_1_CLREF")
	)
	(segment
		(start 37.117782 -248.405142)
		(end 37.117782 -246.744998)
		(width 0.1016)
		(layer "B.Cu")
		(net "FAN_1_CLREF")
	)
	(segment
		(start 37.21227 -248.49963)
		(end 37.117782 -248.405142)
		(width 0.1016)
		(layer "B.Cu")
		(net "FAN_1_CLREF")
	)
	(segment
		(start 37.117782 -248.708418)
		(end 37.117782 -249.334782)
		(width 0.2794)
		(layer "B.Cu")
		(net "FAN_1_CLREF")
	)
	(segment
		(start 18.26895 -103.124)
		(end 17.77365 -103.124)
		(width 0.2794)
		(layer "F.Cu")
		(net "FAN_5_TACH_IL_R")
	)
	(segment
		(start 18.279872 -104.129078)
		(end 18.279872 -103.655622)
		(width 0.2794)
		(layer "F.Cu")
		(net "FAN_5_TACH_IL_R")
	)
	(segment
		(start 18.26895 -104.14)
		(end 18.26895 -105.23855)
		(width 0.2794)
		(layer "F.Cu")
		(net "FAN_5_TACH_IL_R")
	)
	(segment
		(start 16.470122 -104.633522)
		(end 16.470122 -103.855012)
		(width 0.2794)
		(layer "F.Cu")
		(net "FAN_5_TACH_IL_R")
	)
	(segment
		(start 18.26895 -105.23855)
		(end 18.4404 -105.41)
		(width 0.2794)
		(layer "F.Cu")
		(net "FAN_5_TACH_IL_R")
	)
	(segment
		(start 17.4752 -104.394)
		(end 16.9672 -104.902)
		(width 0.2794)
		(layer "F.Cu")
		(net "FAN_5_TACH_IL_R")
	)
	(segment
		(start 16.9672 -104.902)
		(end 16.7386 -104.902)
		(width 0.2794)
		(layer "F.Cu")
		(net "FAN_5_TACH_IL_R")
	)
	(segment
		(start 18.26895 -103.6447)
		(end 18.26895 -103.124)
		(width 0.2794)
		(layer "F.Cu")
		(net "FAN_5_TACH_IL_R")
	)
	(segment
		(start 17.77365 -103.124)
		(end 17.4752 -103.42245)
		(width 0.2794)
		(layer "F.Cu")
		(net "FAN_5_TACH_IL_R")
	)
	(segment
		(start 17.4752 -103.42245)
		(end 17.4752 -104.394)
		(width 0.2794)
		(layer "F.Cu")
		(net "FAN_5_TACH_IL_R")
	)
	(segment
		(start 16.7386 -104.902)
		(end 16.470122 -104.633522)
		(width 0.2794)
		(layer "F.Cu")
		(net "FAN_5_TACH_IL_R")
	)
	(segment
		(start 18.26895 -104.14)
		(end 18.279872 -104.129078)
		(width 0.2794)
		(layer "F.Cu")
		(net "FAN_5_TACH_IL_R")
	)
	(segment
		(start 18.279872 -103.655622)
		(end 18.26895 -103.6447)
		(width 0.2794)
		(layer "F.Cu")
		(net "FAN_5_TACH_IL_R")
	)
	(via
		(at 16.7386 -104.902)
		(size 0.508)
		(drill 0.254)
		(layers "F.Cu" "B.Cu")
		(net "FAN_5_TACH_IL_R")
	)
	(segment
		(start 35.564826 -247.492266)
		(end 34.532316 -247.492266)
		(width 0.2794)
		(layer "F.Cu")
		(net "FAN_1_FAULT")
	)
	(segment
		(start 35.446462 -250.56338)
		(end 34.67227 -250.56338)
		(width 0.2794)
		(layer "F.Cu")
		(net "FAN_1_FAULT")
	)
	(segment
		(start 34.258758 -247.765824)
		(end 34.258758 -248.8819)
		(width 0.2794)
		(layer "F.Cu")
		(net "FAN_1_FAULT")
	)
	(segment
		(start 36.068 -247.99544)
		(end 35.564826 -247.492266)
		(width 0.2794)
		(layer "F.Cu")
		(net "FAN_1_FAULT")
	)
	(segment
		(start 35.965892 -250.04395)
		(end 35.446462 -250.56338)
		(width 0.2794)
		(layer "F.Cu")
		(net "FAN_1_FAULT")
	)
	(segment
		(start 36.068 -248.285)
		(end 36.068 -247.99544)
		(width 0.2794)
		(layer "F.Cu")
		(net "FAN_1_FAULT")
	)
	(segment
		(start 34.67227 -249.295412)
		(end 34.67227 -250.56338)
		(width 0.2794)
		(layer "F.Cu")
		(net "FAN_1_FAULT")
	)
	(segment
		(start 34.532316 -247.492266)
		(end 34.258758 -247.765824)
		(width 0.2794)
		(layer "F.Cu")
		(net "FAN_1_FAULT")
	)
	(segment
		(start 36.068 -250.04395)
		(end 35.965892 -250.04395)
		(width 0.2794)
		(layer "F.Cu")
		(net "FAN_1_FAULT")
	)
	(segment
		(start 34.258758 -248.8819)
		(end 34.67227 -249.295412)
		(width 0.2794)
		(layer "F.Cu")
		(net "FAN_1_FAULT")
	)
	(via
		(at 36.068 -248.285)
		(size 0.508)
		(drill 0.254)
		(layers "F.Cu" "B.Cu")
		(net "FAN_1_FAULT")
	)
	(via
		(at 34.67227 -250.56338)
		(size 0.762)
		(drill 0.381)
		(layers "F.Cu" "B.Cu")
		(net "FAN_1_FAULT")
	)
	(segment
		(start 36.063428 -248.280428)
		(end 36.063428 -247.942354)
		(width 0.2794)
		(layer "B.Cu")
		(net "FAN_1_FAULT")
	)
	(segment
		(start 36.063428 -247.942354)
		(end 36.317682 -247.328182)
		(width 0.1016)
		(layer "B.Cu")
		(net "FAN_1_FAULT")
	)
	(segment
		(start 36.317682 -247.328182)
		(end 36.317682 -246.744998)
		(width 0.1016)
		(layer "B.Cu")
		(net "FAN_1_FAULT")
	)
	(segment
		(start 36.068 -248.285)
		(end 36.063428 -248.280428)
		(width 0.2794)
		(layer "B.Cu")
		(net "FAN_1_FAULT")
	)
	(segment
		(start 6.700012 -18.40992)
		(end 7.710932 -17.399)
		(width 0.2794)
		(layer "F.Cu")
		(net "SMB_FAN4_SDA_R")
	)
	(segment
		(start 9.476232 -17.399)
		(end 12.69619 -20.618958)
		(width 0.2794)
		(layer "F.Cu")
		(net "SMB_FAN4_SDA_R")
	)
	(segment
		(start 12.69619 -20.618958)
		(end 13.462 -21.384768)
		(width 0.2794)
		(layer "F.Cu")
		(net "SMB_FAN4_SDA_R")
	)
	(segment
		(start 7.710932 -17.399)
		(end 9.476232 -17.399)
		(width 0.2794)
		(layer "F.Cu")
		(net "SMB_FAN4_SDA_R")
	)
	(segment
		(start 13.462 -21.384768)
		(end 13.95095 -21.384768)
		(width 0.2794)
		(layer "F.Cu")
		(net "SMB_FAN4_SDA_R")
	)
	(via
		(at 12.69619 -20.618958)
		(size 0.762)
		(drill 0.381)
		(layers "F.Cu" "B.Cu")
		(net "SMB_FAN4_SDA_R")
	)
	(segment
		(start 31.6738 -125.9332)
		(end 31.8135 -125.7935)
		(width 0.2794)
		(layer "F.Cu")
		(net "MAX31790_U317_ADD0")
	)
	(segment
		(start 32.874204 -124.60605)
		(end 33.02 -124.60605)
		(width 0.2794)
		(layer "F.Cu")
		(net "MAX31790_U317_ADD0")
	)
	(segment
		(start 33.02 -124.60605)
		(end 33.171892 -124.60605)
		(width 0.2794)
		(layer "F.Cu")
		(net "MAX31790_U317_ADD0")
	)
	(segment
		(start 31.496 -126.36246)
		(end 31.6738 -125.9332)
		(width 0.1016)
		(layer "F.Cu")
		(net "MAX31790_U317_ADD0")
	)
	(segment
		(start 32.02178 -125.458474)
		(end 32.874204 -124.60605)
		(width 0.2794)
		(layer "F.Cu")
		(net "MAX31790_U317_ADD0")
	)
	(segment
		(start 31.8135 -125.7935)
		(end 31.8135 -125.666754)
		(width 0.2794)
		(layer "F.Cu")
		(net "MAX31790_U317_ADD0")
	)
	(segment
		(start 33.6931 -124.084842)
		(end 33.6931 -122.99315)
		(width 0.2794)
		(layer "F.Cu")
		(net "MAX31790_U317_ADD0")
	)
	(segment
		(start 33.6931 -122.99315)
		(end 33.02 -122.32005)
		(width 0.2794)
		(layer "F.Cu")
		(net "MAX31790_U317_ADD0")
	)
	(segment
		(start 31.496 -127.159004)
		(end 31.496 -126.36246)
		(width 0.1016)
		(layer "F.Cu")
		(net "MAX31790_U317_ADD0")
	)
	(segment
		(start 33.171892 -124.60605)
		(end 33.6931 -124.084842)
		(width 0.2794)
		(layer "F.Cu")
		(net "MAX31790_U317_ADD0")
	)
	(segment
		(start 31.8135 -125.666754)
		(end 32.02178 -125.458474)
		(width 0.2794)
		(layer "F.Cu")
		(net "MAX31790_U317_ADD0")
	)
	(via
		(at 32.02178 -125.458474)
		(size 0.508)
		(drill 0.254)
		(layers "F.Cu" "B.Cu")
		(net "MAX31790_U317_ADD0")
	)
	(via
		(at 32.794448 -248.607326)
		(size 0.762)
		(drill 0.254)
		(layers "F.Cu" "B.Cu")
		(net "FAN_1_CS")
	)
	(segment
		(start 35.117786 -246.855488)
		(end 35.117786 -246.744998)
		(width 0.1016)
		(layer "B.Cu")
		(net "FAN_1_CS")
	)
	(segment
		(start 32.794448 -248.607326)
		(end 33.38957 -248.360946)
		(width 0.2794)
		(layer "B.Cu")
		(net "FAN_1_CS")
	)
	(segment
		(start 32.131 -249.83694)
		(end 32.131 -249.270774)
		(width 0.2794)
		(layer "B.Cu")
		(net "FAN_1_CS")
	)
	(segment
		(start 33.38957 -248.360946)
		(end 34.289746 -247.46077)
		(width 0.2794)
		(layer "B.Cu")
		(net "FAN_1_CS")
	)
	(segment
		(start 34.289746 -247.46077)
		(end 34.960814 -247.01246)
		(width 0.1016)
		(layer "B.Cu")
		(net "FAN_1_CS")
	)
	(segment
		(start 34.960814 -247.01246)
		(end 35.117786 -246.855488)
		(width 0.1016)
		(layer "B.Cu")
		(net "FAN_1_CS")
	)
	(segment
		(start 32.131 -249.270774)
		(end 32.794448 -248.607326)
		(width 0.2794)
		(layer "B.Cu")
		(net "FAN_1_CS")
	)
	(segment
		(start 39.243508 -246.659654)
		(end 38.201346 -246.659654)
		(width 0.2794)
		(layer "F.Cu")
		(net "FAN_1_MODE")
	)
	(segment
		(start 36.68395 -249.047)
		(end 36.68395 -249.809)
		(width 0.2794)
		(layer "F.Cu")
		(net "FAN_1_MODE")
	)
	(segment
		(start 36.68395 -249.809)
		(end 37.06495 -250.19)
		(width 0.2794)
		(layer "F.Cu")
		(net "FAN_1_MODE")
	)
	(segment
		(start 38.201346 -246.659654)
		(end 36.68395 -248.17705)
		(width 0.2794)
		(layer "F.Cu")
		(net "FAN_1_MODE")
	)
	(segment
		(start 40.030654 -246.659654)
		(end 39.243508 -246.659654)
		(width 0.2794)
		(layer "F.Cu")
		(net "FAN_1_MODE")
	)
	(segment
		(start 40.386 -247.015)
		(end 40.030654 -246.659654)
		(width 0.2794)
		(layer "F.Cu")
		(net "FAN_1_MODE")
	)
	(segment
		(start 36.68395 -248.17705)
		(end 36.68395 -249.047)
		(width 0.2794)
		(layer "F.Cu")
		(net "FAN_1_MODE")
	)
	(via
		(at 40.386 -247.015)
		(size 0.508)
		(drill 0.254)
		(layers "F.Cu" "B.Cu")
		(net "FAN_1_MODE")
	)
	(via
		(at 39.243508 -246.659654)
		(size 0.762)
		(drill 0.381)
		(layers "F.Cu" "B.Cu")
		(net "FAN_1_MODE")
	)
	(segment
		(start 40.386 -247.015)
		(end 40.296846 -246.925846)
		(width 0.2794)
		(layer "B.Cu")
		(net "FAN_1_MODE")
	)
	(segment
		(start 40.296846 -246.925846)
		(end 39.698422 -246.925846)
		(width 0.2794)
		(layer "B.Cu")
		(net "FAN_1_MODE")
	)
	(segment
		(start 39.698422 -246.925846)
		(end 39.517574 -246.744998)
		(width 0.1016)
		(layer "B.Cu")
		(net "FAN_1_MODE")
	)
	(segment
		(start 36.068 -250.84405)
		(end 36.703 -250.84405)
		(width 0.2794)
		(layer "F.Cu")
		(net "FAN_1_FAULT_R")
	)
	(segment
		(start 36.703 -250.84405)
		(end 37.06495 -251.206)
		(width 0.2794)
		(layer "F.Cu")
		(net "FAN_1_FAULT_R")
	)
	(segment
		(start 10.922 -296.291)
		(end 11.938 -296.291)
		(width 0.2794)
		(layer "F.Cu")
		(net "SMB_FAN7_SDA_R")
	)
	(segment
		(start 13.335254 -295.656)
		(end 12.700254 -296.291)
		(width 0.2794)
		(layer "F.Cu")
		(net "SMB_FAN7_SDA_R")
	)
	(segment
		(start 10.287 -295.656)
		(end 10.922 -296.291)
		(width 0.2794)
		(layer "F.Cu")
		(net "SMB_FAN7_SDA_R")
	)
	(segment
		(start 13.95095 -295.656)
		(end 13.335254 -295.656)
		(width 0.2794)
		(layer "F.Cu")
		(net "SMB_FAN7_SDA_R")
	)
	(segment
		(start 12.700254 -296.291)
		(end 11.938 -296.291)
		(width 0.2794)
		(layer "F.Cu")
		(net "SMB_FAN7_SDA_R")
	)
	(via
		(at 11.938 -296.291)
		(size 0.762)
		(drill 0.381)
		(layers "F.Cu" "B.Cu")
		(net "SMB_FAN7_SDA_R")
	)
	(via
		(at 10.287 -295.656)
		(size 0.508)
		(drill 0.254)
		(layers "F.Cu" "B.Cu")
		(net "SMB_FAN7_SDA_R")
	)
	(segment
		(start 10.287 -295.656)
		(end 10.287 -295.0718)
		(width 0.2286)
		(layer "In2.Cu")
		(net "SMB_FAN7_SDA_R")
	)
	(segment
		(start 10.287 -295.0718)
		(end 9.525 -294.3098)
		(width 0.2286)
		(layer "In2.Cu")
		(net "SMB_FAN7_SDA_R")
	)
	(segment
		(start 9.525 -294.3098)
		(end 7.700264 -294.3098)
		(width 0.2286)
		(layer "In2.Cu")
		(net "SMB_FAN7_SDA_R")
	)
	(segment
		(start 7.700264 -294.3098)
		(end 6.700012 -295.310052)
		(width 0.2286)
		(layer "In2.Cu")
		(net "SMB_FAN7_SDA_R")
	)
	(segment
		(start 38.938454 -298.196)
		(end 37.73805 -298.196)
		(width 0.2794)
		(layer "F.Cu")
		(net "SMB_FAN0_SCL_R")
	)
	(segment
		(start 40.052498 -299.310044)
		(end 39.442644 -298.70019)
		(width 0.2794)
		(layer "F.Cu")
		(net "SMB_FAN0_SCL_R")
	)
	(segment
		(start 42.999914 -299.310044)
		(end 40.052498 -299.310044)
		(width 0.2794)
		(layer "F.Cu")
		(net "SMB_FAN0_SCL_R")
	)
	(segment
		(start 39.442644 -298.70019)
		(end 38.938454 -298.196)
		(width 0.2794)
		(layer "F.Cu")
		(net "SMB_FAN0_SCL_R")
	)
	(via
		(at 39.442644 -298.70019)
		(size 0.762)
		(drill 0.381)
		(layers "F.Cu" "B.Cu")
		(net "SMB_FAN0_SCL_R")
	)
	(via
		(at 39.878 -248.666)
		(size 0.6604)
		(drill 0.3302)
		(layers "F.Cu" "B.Cu")
		(net "FAN_1_P5V")
	)
	(segment
		(start 38.717728 -247.268238)
		(end 39.297356 -248.35231)
		(width 0.1016)
		(layer "B.Cu")
		(net "FAN_1_P5V")
	)
	(segment
		(start 40.11168 -248.89968)
		(end 39.878 -248.666)
		(width 0.2794)
		(layer "B.Cu")
		(net "FAN_1_P5V")
	)
	(segment
		(start 39.297356 -248.35231)
		(end 39.616888 -248.614438)
		(width 0.1016)
		(layer "B.Cu")
		(net "FAN_1_P5V")
	)
	(segment
		(start 39.616888 -248.614438)
		(end 39.84498 -248.683526)
		(width 0.1016)
		(layer "B.Cu")
		(net "FAN_1_P5V")
	)
	(segment
		(start 38.717728 -246.744998)
		(end 38.717728 -247.268238)
		(width 0.1016)
		(layer "B.Cu")
		(net "FAN_1_P5V")
	)
	(segment
		(start 40.11168 -249.83694)
		(end 40.11168 -248.89968)
		(width 0.2794)
		(layer "B.Cu")
		(net "FAN_1_P5V")
	)
	(segment
		(start 39.84498 -248.683526)
		(end 39.878 -248.666)
		(width 0.1016)
		(layer "B.Cu")
		(net "FAN_1_P5V")
	)
	(segment
		(start 19.527774 -133.58495)
		(end 19.582892 -133.58495)
		(width 0.2794)
		(layer "F.Cu")
		(net "MAX31790_U330_ADD0")
	)
	(segment
		(start 20.955 -132.061712)
		(end 20.475702 -132.54101)
		(width 0.1016)
		(layer "F.Cu")
		(net "MAX31790_U330_ADD0")
	)
	(segment
		(start 20.955 -131.158996)
		(end 20.955 -132.061712)
		(width 0.1016)
		(layer "F.Cu")
		(net "MAX31790_U330_ADD0")
	)
	(segment
		(start 20.475702 -132.637022)
		(end 20.140422 -132.972302)
		(width 0.2794)
		(layer "F.Cu")
		(net "MAX31790_U330_ADD0")
	)
	(segment
		(start 20.1041 -134.106158)
		(end 20.1041 -135.19785)
		(width 0.2794)
		(layer "F.Cu")
		(net "MAX31790_U330_ADD0")
	)
	(segment
		(start 19.582892 -133.58495)
		(end 20.1041 -134.106158)
		(width 0.2794)
		(layer "F.Cu")
		(net "MAX31790_U330_ADD0")
	)
	(segment
		(start 20.475702 -132.54101)
		(end 20.475702 -132.637022)
		(width 0.2794)
		(layer "F.Cu")
		(net "MAX31790_U330_ADD0")
	)
	(segment
		(start 20.140422 -132.972302)
		(end 19.527774 -133.58495)
		(width 0.2794)
		(layer "F.Cu")
		(net "MAX31790_U330_ADD0")
	)
	(segment
		(start 19.431 -133.58495)
		(end 19.527774 -133.58495)
		(width 0.2794)
		(layer "F.Cu")
		(net "MAX31790_U330_ADD0")
	)
	(segment
		(start 20.1041 -135.19785)
		(end 19.685 -135.61695)
		(width 0.2794)
		(layer "F.Cu")
		(net "MAX31790_U330_ADD0")
	)
	(segment
		(start 19.685 -135.61695)
		(end 19.431 -135.61695)
		(width 0.2794)
		(layer "F.Cu")
		(net "MAX31790_U330_ADD0")
	)
	(via
		(at 20.140422 -132.972302)
		(size 0.508)
		(drill 0.254)
		(layers "F.Cu" "B.Cu")
		(net "MAX31790_U330_ADD0")
	)
	(segment
		(start 31.242 -206.555848)
		(end 31.727648 -206.0702)
		(width 0.2794)
		(layer "F.Cu")
		(net "FAN_1_TACH_IL")
	)
	(segment
		(start 31.727648 -206.0702)
		(end 33.844484 -206.0702)
		(width 0.2794)
		(layer "F.Cu")
		(net "FAN_1_TACH_IL")
	)
	(segment
		(start 31.242 -208.534)
		(end 31.242 -206.555848)
		(width 0.2794)
		(layer "F.Cu")
		(net "FAN_1_TACH_IL")
	)
	(segment
		(start 32.61995 -209.451956)
		(end 32.159956 -209.451956)
		(width 0.2794)
		(layer "F.Cu")
		(net "FAN_1_TACH_IL")
	)
	(segment
		(start 32.159956 -209.451956)
		(end 31.242 -208.534)
		(width 0.2794)
		(layer "F.Cu")
		(net "FAN_1_TACH_IL")
	)
	(segment
		(start 38.24605 -135.128)
		(end 38.24605 -135.763)
		(width 0.2794)
		(layer "F.Cu")
		(net "FAN_1_TACH_IL")
	)
	(via
		(at 33.844484 -206.0702)
		(size 0.508)
		(drill 0.254)
		(layers "F.Cu" "B.Cu")
		(net "FAN_1_TACH_IL")
	)
	(via
		(at 38.24605 -135.763)
		(size 0.508)
		(drill 0.254)
		(layers "F.Cu" "B.Cu")
		(net "FAN_1_TACH_IL")
	)
	(segment
		(start 38.24605 -135.763)
		(end 38.432486 -135.763)
		(width 0.2794)
		(layer "B.Cu")
		(net "FAN_1_TACH_IL")
	)
	(segment
		(start 38.432486 -135.763)
		(end 40.49395 -133.701536)
		(width 0.2794)
		(layer "B.Cu")
		(net "FAN_1_TACH_IL")
	)
	(segment
		(start 40.49395 -133.701536)
		(end 40.49395 -133.477)
		(width 0.2794)
		(layer "B.Cu")
		(net "FAN_1_TACH_IL")
	)
	(segment
		(start 35.87115 -157.867604)
		(end 36.376356 -159.086042)
		(width 0.2286)
		(layer "In2.Cu")
		(net "FAN_1_TACH_IL")
	)
	(segment
		(start 39.437564 -136.954514)
		(end 39.437564 -140.344398)
		(width 0.2286)
		(layer "In2.Cu")
		(net "FAN_1_TACH_IL")
	)
	(segment
		(start 35.87115 -143.910812)
		(end 35.87115 -157.867604)
		(width 0.2286)
		(layer "In2.Cu")
		(net "FAN_1_TACH_IL")
	)
	(segment
		(start 36.376356 -159.086042)
		(end 36.93795 -160.440624)
		(width 0.2286)
		(layer "In2.Cu")
		(net "FAN_1_TACH_IL")
	)
	(segment
		(start 35.380168 -189.290452)
		(end 29.196792 -195.473828)
		(width 0.2286)
		(layer "In2.Cu")
		(net "FAN_1_TACH_IL")
	)
	(segment
		(start 37.1094 -160.85439)
		(end 37.1094 -162.7378)
		(width 0.2286)
		(layer "In2.Cu")
		(net "FAN_1_TACH_IL")
	)
	(segment
		(start 35.380168 -184.173876)
		(end 35.380168 -189.290452)
		(width 0.2286)
		(layer "In2.Cu")
		(net "FAN_1_TACH_IL")
	)
	(segment
		(start 37.6428 -163.2712)
		(end 37.6428 -181.911244)
		(width 0.2286)
		(layer "In2.Cu")
		(net "FAN_1_TACH_IL")
	)
	(segment
		(start 38.24605 -135.763)
		(end 39.437564 -136.954514)
		(width 0.2286)
		(layer "In2.Cu")
		(net "FAN_1_TACH_IL")
	)
	(segment
		(start 33.844484 -205.018894)
		(end 33.844484 -206.0702)
		(width 0.2286)
		(layer "In2.Cu")
		(net "FAN_1_TACH_IL")
	)
	(segment
		(start 29.196792 -195.473828)
		(end 29.196792 -200.371202)
		(width 0.2286)
		(layer "In2.Cu")
		(net "FAN_1_TACH_IL")
	)
	(segment
		(start 37.6428 -181.911244)
		(end 35.380168 -184.173876)
		(width 0.2286)
		(layer "In2.Cu")
		(net "FAN_1_TACH_IL")
	)
	(segment
		(start 37.1094 -162.7378)
		(end 37.6428 -163.2712)
		(width 0.2286)
		(layer "In2.Cu")
		(net "FAN_1_TACH_IL")
	)
	(segment
		(start 29.196792 -200.371202)
		(end 33.844484 -205.018894)
		(width 0.2286)
		(layer "In2.Cu")
		(net "FAN_1_TACH_IL")
	)
	(segment
		(start 39.437564 -140.344398)
		(end 35.87115 -143.910812)
		(width 0.2286)
		(layer "In2.Cu")
		(net "FAN_1_TACH_IL")
	)
	(segment
		(start 36.93795 -160.440624)
		(end 37.1094 -160.85439)
		(width 0.2286)
		(layer "In2.Cu")
		(net "FAN_1_TACH_IL")
	)
	(segment
		(start 20.979892 -133.58495)
		(end 20.828 -133.58495)
		(width 0.2794)
		(layer "F.Cu")
		(net "MAX31790_U330_ADD1")
	)
	(segment
		(start 20.828 -133.138926)
		(end 20.828 -133.58495)
		(width 0.2794)
		(layer "F.Cu")
		(net "MAX31790_U330_ADD1")
	)
	(segment
		(start 21.35505 -132.201666)
		(end 21.35505 -132.611876)
		(width 0.2794)
		(layer "F.Cu")
		(net "MAX31790_U330_ADD1")
	)
	(segment
		(start 20.828 -135.61695)
		(end 21.082 -135.61695)
		(width 0.2794)
		(layer "F.Cu")
		(net "MAX31790_U330_ADD1")
	)
	(segment
		(start 21.35505 -132.611876)
		(end 20.828 -133.138926)
		(width 0.2794)
		(layer "F.Cu")
		(net "MAX31790_U330_ADD1")
	)
	(segment
		(start 21.519642 -134.1247)
		(end 20.979892 -133.58495)
		(width 0.2794)
		(layer "F.Cu")
		(net "MAX31790_U330_ADD1")
	)
	(segment
		(start 21.082 -135.61695)
		(end 21.519642 -135.179308)
		(width 0.2794)
		(layer "F.Cu")
		(net "MAX31790_U330_ADD1")
	)
	(segment
		(start 21.35505 -131.158996)
		(end 21.35505 -132.201666)
		(width 0.1016)
		(layer "F.Cu")
		(net "MAX31790_U330_ADD1")
	)
	(segment
		(start 21.519642 -135.179308)
		(end 21.519642 -134.1247)
		(width 0.2794)
		(layer "F.Cu")
		(net "MAX31790_U330_ADD1")
	)
	(via
		(at 21.519642 -135.179308)
		(size 0.508)
		(drill 0.254)
		(layers "F.Cu" "B.Cu")
		(net "MAX31790_U330_ADD1")
	)
	(segment
		(start 26.390092 -156.945584)
		(end 27.178 -157.734)
		(width 0.2794)
		(layer "F.Cu")
		(net "SMB_FAN5_R_SCL")
	)
	(segment
		(start 28.956 -159.61995)
		(end 28.956 -159.512762)
		(width 0.2794)
		(layer "F.Cu")
		(net "SMB_FAN5_R_SCL")
	)
	(segment
		(start 28.956 -162.54095)
		(end 28.956 -161.701734)
		(width 0.2794)
		(layer "F.Cu")
		(net "SMB_FAN5_R_SCL")
	)
	(segment
		(start 29.63672 -159.899604)
		(end 29.357066 -159.61995)
		(width 0.2794)
		(layer "F.Cu")
		(net "SMB_FAN5_R_SCL")
	)
	(segment
		(start 26.390092 -154.94)
		(end 26.390092 -156.945584)
		(width 0.2794)
		(layer "F.Cu")
		(net "SMB_FAN5_R_SCL")
	)
	(segment
		(start 29.357066 -159.61995)
		(end 28.956 -159.61995)
		(width 0.2794)
		(layer "F.Cu")
		(net "SMB_FAN5_R_SCL")
	)
	(segment
		(start 28.956 -159.512762)
		(end 27.178 -157.734)
		(width 0.2794)
		(layer "F.Cu")
		(net "SMB_FAN5_R_SCL")
	)
	(segment
		(start 29.63672 -161.021014)
		(end 29.63672 -159.899604)
		(width 0.2794)
		(layer "F.Cu")
		(net "SMB_FAN5_R_SCL")
	)
	(segment
		(start 28.956 -161.701734)
		(end 29.63672 -161.021014)
		(width 0.2794)
		(layer "F.Cu")
		(net "SMB_FAN5_R_SCL")
	)
	(via
		(at 27.178 -157.734)
		(size 0.762)
		(drill 0.381)
		(layers "F.Cu" "B.Cu")
		(net "SMB_FAN5_R_SCL")
	)
	(segment
		(start 38.24605 -128.778)
		(end 38.24605 -129.413)
		(width 0.2794)
		(layer "F.Cu")
		(net "FAN_2_TACH_IL")
	)
	(segment
		(start 32.61995 -118.237)
		(end 32.61995 -118.72595)
		(width 0.2794)
		(layer "F.Cu")
		(net "FAN_2_TACH_IL")
	)
	(segment
		(start 32.61995 -118.72595)
		(end 32.766 -118.872)
		(width 0.2794)
		(layer "F.Cu")
		(net "FAN_2_TACH_IL")
	)
	(via
		(at 38.24605 -129.413)
		(size 0.508)
		(drill 0.254)
		(layers "F.Cu" "B.Cu")
		(net "FAN_2_TACH_IL")
	)
	(via
		(at 32.766 -118.872)
		(size 0.508)
		(drill 0.254)
		(layers "F.Cu" "B.Cu")
		(net "FAN_2_TACH_IL")
	)
	(segment
		(start 39.85895 -129.413)
		(end 38.24605 -129.413)
		(width 0.2794)
		(layer "B.Cu")
		(net "FAN_2_TACH_IL")
	)
	(segment
		(start 40.49395 -130.048)
		(end 39.85895 -129.413)
		(width 0.2794)
		(layer "B.Cu")
		(net "FAN_2_TACH_IL")
	)
	(segment
		(start 36.56584 -124.876306)
		(end 37.49294 -125.803406)
		(width 0.2286)
		(layer "In2.Cu")
		(net "FAN_2_TACH_IL")
	)
	(segment
		(start 32.766 -119.49938)
		(end 36.56584 -123.29922)
		(width 0.2286)
		(layer "In2.Cu")
		(net "FAN_2_TACH_IL")
	)
	(segment
		(start 37.49294 -128.65989)
		(end 38.24605 -129.413)
		(width 0.2286)
		(layer "In2.Cu")
		(net "FAN_2_TACH_IL")
	)
	(segment
		(start 32.766 -118.872)
		(end 32.766 -119.49938)
		(width 0.2286)
		(layer "In2.Cu")
		(net "FAN_2_TACH_IL")
	)
	(segment
		(start 37.49294 -125.803406)
		(end 37.49294 -128.65989)
		(width 0.2286)
		(layer "In2.Cu")
		(net "FAN_2_TACH_IL")
	)
	(segment
		(start 36.56584 -123.29922)
		(end 36.56584 -124.876306)
		(width 0.2286)
		(layer "In2.Cu")
		(net "FAN_2_TACH_IL")
	)
	(segment
		(start 13.95095 -109.023912)
		(end 13.217398 -109.757464)
		(width 0.2794)
		(layer "F.Cu")
		(net "SMB_FAN5_SDA_R")
	)
	(segment
		(start 13.217398 -109.757464)
		(end 11.811 -109.757464)
		(width 0.2794)
		(layer "F.Cu")
		(net "SMB_FAN5_SDA_R")
	)
	(segment
		(start 11.725656 -109.67212)
		(end 7.737856 -109.67212)
		(width 0.2794)
		(layer "F.Cu")
		(net "SMB_FAN5_SDA_R")
	)
	(segment
		(start 7.737856 -109.67212)
		(end 6.700012 -110.709964)
		(width 0.2794)
		(layer "F.Cu")
		(net "SMB_FAN5_SDA_R")
	)
	(segment
		(start 11.811 -109.757464)
		(end 11.725656 -109.67212)
		(width 0.2794)
		(layer "F.Cu")
		(net "SMB_FAN5_SDA_R")
	)
	(via
		(at 11.811 -109.757464)
		(size 0.762)
		(drill 0.381)
		(layers "F.Cu" "B.Cu")
		(net "SMB_FAN5_SDA_R")
	)
	(segment
		(start 31.75 -28.956)
		(end 31.369 -29.337)
		(width 0.2794)
		(layer "F.Cu")
		(net "FAN_3_TACH_IL")
	)
	(segment
		(start 38.24605 -127.508)
		(end 38.24605 -128.143)
		(width 0.2794)
		(layer "F.Cu")
		(net "FAN_3_TACH_IL")
	)
	(segment
		(start 32.49295 -28.956)
		(end 31.75 -28.956)
		(width 0.2794)
		(layer "F.Cu")
		(net "FAN_3_TACH_IL")
	)
	(via
		(at 31.369 -29.337)
		(size 0.508)
		(drill 0.254)
		(layers "F.Cu" "B.Cu")
		(net "FAN_3_TACH_IL")
	)
	(via
		(at 38.24605 -128.143)
		(size 0.508)
		(drill 0.254)
		(layers "F.Cu" "B.Cu")
		(net "FAN_3_TACH_IL")
	)
	(segment
		(start 39.73195 -128.143)
		(end 40.49395 -128.905)
		(width 0.2794)
		(layer "B.Cu")
		(net "FAN_3_TACH_IL")
	)
	(segment
		(start 38.24605 -128.143)
		(end 39.73195 -128.143)
		(width 0.2794)
		(layer "B.Cu")
		(net "FAN_3_TACH_IL")
	)
	(segment
		(start 33.7058 -33.557972)
		(end 33.7058 -30.5308)
		(width 0.2286)
		(layer "In2.Cu")
		(net "FAN_3_TACH_IL")
	)
	(segment
		(start 33.342834 -51.420268)
		(end 33.342834 -33.920938)
		(width 0.2286)
		(layer "In2.Cu")
		(net "FAN_3_TACH_IL")
	)
	(segment
		(start 39.75227 -126.63678)
		(end 39.75227 -117.363748)
		(width 0.2286)
		(layer "In2.Cu")
		(net "FAN_3_TACH_IL")
	)
	(segment
		(start 38.24605 -128.143)
		(end 39.75227 -126.63678)
		(width 0.2286)
		(layer "In2.Cu")
		(net "FAN_3_TACH_IL")
	)
	(segment
		(start 33.7058 -30.5308)
		(end 32.512 -29.337)
		(width 0.2286)
		(layer "In2.Cu")
		(net "FAN_3_TACH_IL")
	)
	(segment
		(start 27.8003 -64.80683)
		(end 33.342834 -51.420268)
		(width 0.2286)
		(layer "In2.Cu")
		(net "FAN_3_TACH_IL")
	)
	(segment
		(start 28.575 -82.7024)
		(end 27.8003 -81.9277)
		(width 0.2286)
		(layer "In2.Cu")
		(net "FAN_3_TACH_IL")
	)
	(segment
		(start 32.602932 -111.988854)
		(end 31.242 -110.627922)
		(width 0.2286)
		(layer "In2.Cu")
		(net "FAN_3_TACH_IL")
	)
	(segment
		(start 32.9692 -100.828094)
		(end 28.575 -96.433894)
		(width 0.2286)
		(layer "In2.Cu")
		(net "FAN_3_TACH_IL")
	)
	(segment
		(start 27.8003 -81.9277)
		(end 27.8003 -64.80683)
		(width 0.2286)
		(layer "In2.Cu")
		(net "FAN_3_TACH_IL")
	)
	(segment
		(start 31.242 -110.627922)
		(end 31.242 -106.161586)
		(width 0.2286)
		(layer "In2.Cu")
		(net "FAN_3_TACH_IL")
	)
	(segment
		(start 32.512 -29.337)
		(end 31.369 -29.337)
		(width 0.2286)
		(layer "In2.Cu")
		(net "FAN_3_TACH_IL")
	)
	(segment
		(start 39.75227 -117.363748)
		(end 34.377376 -111.988854)
		(width 0.2286)
		(layer "In2.Cu")
		(net "FAN_3_TACH_IL")
	)
	(segment
		(start 31.242 -106.161586)
		(end 32.9692 -104.434386)
		(width 0.2286)
		(layer "In2.Cu")
		(net "FAN_3_TACH_IL")
	)
	(segment
		(start 33.342834 -33.920938)
		(end 33.7058 -33.557972)
		(width 0.2286)
		(layer "In2.Cu")
		(net "FAN_3_TACH_IL")
	)
	(segment
		(start 32.9692 -104.434386)
		(end 32.9692 -100.828094)
		(width 0.2286)
		(layer "In2.Cu")
		(net "FAN_3_TACH_IL")
	)
	(segment
		(start 28.575 -96.433894)
		(end 28.575 -82.7024)
		(width 0.2286)
		(layer "In2.Cu")
		(net "FAN_3_TACH_IL")
	)
	(segment
		(start 34.377376 -111.988854)
		(end 32.602932 -111.988854)
		(width 0.2286)
		(layer "In2.Cu")
		(net "FAN_3_TACH_IL")
	)
	(segment
		(start 28.34005 -155.22575)
		(end 28.34005 -154.94)
		(width 0.2794)
		(layer "F.Cu")
		(net "SMB_FAN4_R_SDA")
	)
	(segment
		(start 35.179 -160.007554)
		(end 34.79165 -159.61995)
		(width 0.2794)
		(layer "F.Cu")
		(net "SMB_FAN4_R_SDA")
	)
	(segment
		(start 35.179 -162.54095)
		(end 35.179 -160.007554)
		(width 0.2794)
		(layer "F.Cu")
		(net "SMB_FAN4_R_SDA")
	)
	(segment
		(start 34.29 -159.61995)
		(end 34.29 -159.131254)
		(width 0.2794)
		(layer "F.Cu")
		(net "SMB_FAN4_R_SDA")
	)
	(segment
		(start 34.79165 -159.61995)
		(end 34.29 -159.61995)
		(width 0.2794)
		(layer "F.Cu")
		(net "SMB_FAN4_R_SDA")
	)
	(segment
		(start 29.0703 -155.956)
		(end 28.34005 -155.22575)
		(width 0.2794)
		(layer "F.Cu")
		(net "SMB_FAN4_R_SDA")
	)
	(segment
		(start 31.114746 -155.956)
		(end 29.0703 -155.956)
		(width 0.2794)
		(layer "F.Cu")
		(net "SMB_FAN4_R_SDA")
	)
	(segment
		(start 33.49625 -158.337504)
		(end 31.114746 -155.956)
		(width 0.2794)
		(layer "F.Cu")
		(net "SMB_FAN4_R_SDA")
	)
	(segment
		(start 34.29 -159.131254)
		(end 33.49625 -158.337504)
		(width 0.2794)
		(layer "F.Cu")
		(net "SMB_FAN4_R_SDA")
	)
	(via
		(at 33.49625 -158.337504)
		(size 0.762)
		(drill 0.381)
		(layers "F.Cu" "B.Cu")
		(net "SMB_FAN4_R_SDA")
	)
	(segment
		(start 18.288 -119.253)
		(end 18.288 -119.1006)
		(width 0.2794)
		(layer "F.Cu")
		(net "FAN_5_TACH_OL_R")
	)
	(segment
		(start 17.8816 -119.1006)
		(end 18.288 -119.1006)
		(width 0.2794)
		(layer "F.Cu")
		(net "FAN_5_TACH_OL_R")
	)
	(segment
		(start 17.272 -117.825012)
		(end 17.272 -118.491)
		(width 0.2794)
		(layer "F.Cu")
		(net "FAN_5_TACH_OL_R")
	)
	(segment
		(start 17.50695 -120.65)
		(end 17.50695 -120.03405)
		(width 0.2794)
		(layer "F.Cu")
		(net "FAN_5_TACH_OL_R")
	)
	(segment
		(start 17.272 -118.491)
		(end 17.8816 -119.1006)
		(width 0.2794)
		(layer "F.Cu")
		(net "FAN_5_TACH_OL_R")
	)
	(segment
		(start 15.64005 -120.65)
		(end 17.50695 -120.65)
		(width 0.2794)
		(layer "F.Cu")
		(net "FAN_5_TACH_OL_R")
	)
	(segment
		(start 16.470122 -117.825012)
		(end 17.272 -117.825012)
		(width 0.2794)
		(layer "F.Cu")
		(net "FAN_5_TACH_OL_R")
	)
	(segment
		(start 17.50695 -120.03405)
		(end 18.288 -119.253)
		(width 0.2794)
		(layer "F.Cu")
		(net "FAN_5_TACH_OL_R")
	)
	(via
		(at 17.272 -117.825012)
		(size 0.508)
		(drill 0.254)
		(layers "F.Cu" "B.Cu")
		(net "FAN_5_TACH_OL_R")
	)
	(segment
		(start 18.415 -17.92605)
		(end 18.053304 -17.92605)
		(width 0.2794)
		(layer "F.Cu")
		(net "FAN_4_TACH_IL")
	)
	(segment
		(start 18.053304 -17.92605)
		(end 17.907254 -17.78)
		(width 0.2794)
		(layer "F.Cu")
		(net "FAN_4_TACH_IL")
	)
	(segment
		(start 17.907254 -17.78)
		(end 17.399 -17.78)
		(width 0.2794)
		(layer "F.Cu")
		(net "FAN_4_TACH_IL")
	)
	(segment
		(start 14.45895 -123.317)
		(end 14.45895 -123.952)
		(width 0.2794)
		(layer "F.Cu")
		(net "FAN_4_TACH_IL")
	)
	(via
		(at 17.399 -17.78)
		(size 0.508)
		(drill 0.254)
		(layers "F.Cu" "B.Cu")
		(net "FAN_4_TACH_IL")
	)
	(via
		(at 14.45895 -123.952)
		(size 0.508)
		(drill 0.254)
		(layers "F.Cu" "B.Cu")
		(net "FAN_4_TACH_IL")
	)
	(segment
		(start 17.25295 -126.238)
		(end 16.74495 -126.238)
		(width 0.2794)
		(layer "B.Cu")
		(net "FAN_4_TACH_IL")
	)
	(segment
		(start 16.74495 -126.238)
		(end 14.45895 -123.952)
		(width 0.2794)
		(layer "B.Cu")
		(net "FAN_4_TACH_IL")
	)
	(segment
		(start 17.399 -17.78)
		(end 16.803878 -17.78)
		(width 0.2286)
		(layer "In2.Cu")
		(net "FAN_4_TACH_IL")
	)
	(segment
		(start 16.28648 -109.27588)
		(end 15.97025 -109.59211)
		(width 0.2286)
		(layer "In2.Cu")
		(net "FAN_4_TACH_IL")
	)
	(segment
		(start 13.9192 -20.664678)
		(end 13.9192 -28.3972)
		(width 0.2286)
		(layer "In2.Cu")
		(net "FAN_4_TACH_IL")
	)
	(segment
		(start 15.97025 -109.59211)
		(end 15.97025 -113.8809)
		(width 0.2286)
		(layer "In2.Cu")
		(net "FAN_4_TACH_IL")
	)
	(segment
		(start 15.91437 -52.488846)
		(end 20.160488 -62.755526)
		(width 0.2286)
		(layer "In2.Cu")
		(net "FAN_4_TACH_IL")
	)
	(segment
		(start 19.7866 -100.2538)
		(end 17.653 -102.3874)
		(width 0.2286)
		(layer "In2.Cu")
		(net "FAN_4_TACH_IL")
	)
	(segment
		(start 19.7866 -99.2124)
		(end 19.7866 -100.2538)
		(width 0.2286)
		(layer "In2.Cu")
		(net "FAN_4_TACH_IL")
	)
	(segment
		(start 17.653 -105.3846)
		(end 16.28648 -106.75112)
		(width 0.2286)
		(layer "In2.Cu")
		(net "FAN_4_TACH_IL")
	)
	(segment
		(start 16.002 -113.91265)
		(end 16.002 -122.40895)
		(width 0.2286)
		(layer "In2.Cu")
		(net "FAN_4_TACH_IL")
	)
	(segment
		(start 20.160488 -84.843874)
		(end 20.905216 -85.588602)
		(width 0.2286)
		(layer "In2.Cu")
		(net "FAN_4_TACH_IL")
	)
	(segment
		(start 20.905216 -85.588602)
		(end 20.905216 -98.093784)
		(width 0.2286)
		(layer "In2.Cu")
		(net "FAN_4_TACH_IL")
	)
	(segment
		(start 16.28648 -106.75112)
		(end 16.28648 -109.27588)
		(width 0.2286)
		(layer "In2.Cu")
		(net "FAN_4_TACH_IL")
	)
	(segment
		(start 15.91437 -34.163)
		(end 15.91437 -52.488846)
		(width 0.2286)
		(layer "In2.Cu")
		(net "FAN_4_TACH_IL")
	)
	(segment
		(start 20.905216 -98.093784)
		(end 19.7866 -99.2124)
		(width 0.2286)
		(layer "In2.Cu")
		(net "FAN_4_TACH_IL")
	)
	(segment
		(start 16.51 -30.988)
		(end 16.51 -33.56737)
		(width 0.2286)
		(layer "In2.Cu")
		(net "FAN_4_TACH_IL")
	)
	(segment
		(start 20.160488 -62.755526)
		(end 20.160488 -84.843874)
		(width 0.2286)
		(layer "In2.Cu")
		(net "FAN_4_TACH_IL")
	)
	(segment
		(start 17.653 -102.3874)
		(end 17.653 -105.3846)
		(width 0.2286)
		(layer "In2.Cu")
		(net "FAN_4_TACH_IL")
	)
	(segment
		(start 16.51 -33.56737)
		(end 15.91437 -34.163)
		(width 0.2286)
		(layer "In2.Cu")
		(net "FAN_4_TACH_IL")
	)
	(segment
		(start 13.9192 -28.3972)
		(end 16.51 -30.988)
		(width 0.2286)
		(layer "In2.Cu")
		(net "FAN_4_TACH_IL")
	)
	(segment
		(start 16.803878 -17.78)
		(end 13.9192 -20.664678)
		(width 0.2286)
		(layer "In2.Cu")
		(net "FAN_4_TACH_IL")
	)
	(segment
		(start 16.002 -122.40895)
		(end 14.45895 -123.952)
		(width 0.2286)
		(layer "In2.Cu")
		(net "FAN_4_TACH_IL")
	)
	(segment
		(start 15.97025 -113.8809)
		(end 16.002 -113.91265)
		(width 0.2286)
		(layer "In2.Cu")
		(net "FAN_4_TACH_IL")
	)
	(segment
		(start 33.906714 -142.36446)
		(end 33.528 -142.743174)
		(width 0.2794)
		(layer "F.Cu")
		(net "SMB_FAN3_SDA")
	)
	(segment
		(start 36.068 -25.105868)
		(end 36.93795 -25.105868)
		(width 0.2794)
		(layer "F.Cu")
		(net "SMB_FAN3_SDA")
	)
	(segment
		(start 33.528 -142.743174)
		(end 33.528 -143.36395)
		(width 0.2794)
		(layer "F.Cu")
		(net "SMB_FAN3_SDA")
	)
	(segment
		(start 33.528 -143.36395)
		(end 33.401 -143.49095)
		(width 0.2794)
		(layer "F.Cu")
		(net "SMB_FAN3_SDA")
	)
	(via
		(at 34.912046 -28.78836)
		(size 0.508)
		(drill 0.254)
		(layers "F.Cu" "B.Cu")
		(net "SMB_FAN3_SDA")
	)
	(via
		(at 33.906714 -142.36446)
		(size 0.508)
		(drill 0.254)
		(layers "F.Cu" "B.Cu")
		(net "SMB_FAN3_SDA")
	)
	(via
		(at 36.068 -25.105868)
		(size 0.508)
		(drill 0.254)
		(layers "F.Cu" "B.Cu")
		(net "SMB_FAN3_SDA")
	)
	(segment
		(start 36.703 -139.568174)
		(end 36.703 -131.577588)
		(width 0.2286)
		(layer "In2.Cu")
		(net "SMB_FAN3_SDA")
	)
	(segment
		(start 34.163 -35.306254)
		(end 35.052 -34.417254)
		(width 0.2286)
		(layer "In2.Cu")
		(net "SMB_FAN3_SDA")
	)
	(segment
		(start 36.703 -131.577588)
		(end 38.110668 -130.16992)
		(width 0.2286)
		(layer "In2.Cu")
		(net "SMB_FAN3_SDA")
	)
	(segment
		(start 40.43807 -128.464564)
		(end 40.43807 -117.079522)
		(width 0.2286)
		(layer "In2.Cu")
		(net "SMB_FAN3_SDA")
	)
	(segment
		(start 33.655 -100.543868)
		(end 29.2608 -96.149668)
		(width 0.2286)
		(layer "In2.Cu")
		(net "SMB_FAN3_SDA")
	)
	(segment
		(start 34.661602 -111.303054)
		(end 32.887158 -111.303054)
		(width 0.2286)
		(layer "In2.Cu")
		(net "SMB_FAN3_SDA")
	)
	(segment
		(start 35.353244 -28.347162)
		(end 35.353244 -25.820624)
		(width 0.2286)
		(layer "In2.Cu")
		(net "SMB_FAN3_SDA")
	)
	(segment
		(start 34.912046 -28.78836)
		(end 35.353244 -28.347162)
		(width 0.2286)
		(layer "In2.Cu")
		(net "SMB_FAN3_SDA")
	)
	(segment
		(start 31.9405 -107.04322)
		(end 33.655 -105.32872)
		(width 0.2286)
		(layer "In2.Cu")
		(net "SMB_FAN3_SDA")
	)
	(segment
		(start 29.2608 -96.149668)
		(end 29.2608 -82.284824)
		(width 0.2286)
		(layer "In2.Cu")
		(net "SMB_FAN3_SDA")
	)
	(segment
		(start 33.655 -105.32872)
		(end 33.655 -100.543868)
		(width 0.2286)
		(layer "In2.Cu")
		(net "SMB_FAN3_SDA")
	)
	(segment
		(start 35.052 -28.928314)
		(end 34.912046 -28.78836)
		(width 0.2286)
		(layer "In2.Cu")
		(net "SMB_FAN3_SDA")
	)
	(segment
		(start 29.2608 -82.284824)
		(end 28.9306 -81.954624)
		(width 0.2286)
		(layer "In2.Cu")
		(net "SMB_FAN3_SDA")
	)
	(segment
		(start 31.9405 -110.356396)
		(end 31.9405 -107.04322)
		(width 0.2286)
		(layer "In2.Cu")
		(net "SMB_FAN3_SDA")
	)
	(segment
		(start 38.732714 -130.16992)
		(end 40.43807 -128.464564)
		(width 0.2286)
		(layer "In2.Cu")
		(net "SMB_FAN3_SDA")
	)
	(segment
		(start 35.353244 -25.820624)
		(end 36.068 -25.105868)
		(width 0.2286)
		(layer "In2.Cu")
		(net "SMB_FAN3_SDA")
	)
	(segment
		(start 28.9306 -81.954624)
		(end 28.9306 -63.869824)
		(width 0.2286)
		(layer "In2.Cu")
		(net "SMB_FAN3_SDA")
	)
	(segment
		(start 40.43807 -117.079522)
		(end 34.661602 -111.303054)
		(width 0.2286)
		(layer "In2.Cu")
		(net "SMB_FAN3_SDA")
	)
	(segment
		(start 35.052 -34.417254)
		(end 35.052 -28.928314)
		(width 0.2286)
		(layer "In2.Cu")
		(net "SMB_FAN3_SDA")
	)
	(segment
		(start 34.163 -51.234086)
		(end 34.163 -35.306254)
		(width 0.2286)
		(layer "In2.Cu")
		(net "SMB_FAN3_SDA")
	)
	(segment
		(start 28.9306 -63.869824)
		(end 34.163 -51.234086)
		(width 0.2286)
		(layer "In2.Cu")
		(net "SMB_FAN3_SDA")
	)
	(segment
		(start 32.887158 -111.303054)
		(end 31.9405 -110.356396)
		(width 0.2286)
		(layer "In2.Cu")
		(net "SMB_FAN3_SDA")
	)
	(segment
		(start 33.906714 -142.36446)
		(end 36.703 -139.568174)
		(width 0.2286)
		(layer "In2.Cu")
		(net "SMB_FAN3_SDA")
	)
	(segment
		(start 38.110668 -130.16992)
		(end 38.732714 -130.16992)
		(width 0.2286)
		(layer "In2.Cu")
		(net "SMB_FAN3_SDA")
	)
	(segment
		(start 23.38705 -127.217424)
		(end 23.596854 -127.427228)
		(width 0.2794)
		(layer "F.Cu")
		(net "SMB_PDBV_FAN_R_U330_SCL")
	)
	(segment
		(start 23.596854 -128.2573)
		(end 23.495254 -128.3589)
		(width 0.1016)
		(layer "F.Cu")
		(net "SMB_PDBV_FAN_R_U330_SCL")
	)
	(segment
		(start 25.12695 -122.78995)
		(end 24.048212 -123.868688)
		(width 0.2794)
		(layer "F.Cu")
		(net "SMB_PDBV_FAN_R_U330_SCL")
	)
	(segment
		(start 23.495254 -128.3589)
		(end 22.954996 -128.3589)
		(width 0.1016)
		(layer "F.Cu")
		(net "SMB_PDBV_FAN_R_U330_SCL")
	)
	(segment
		(start 23.38705 -125.465078)
		(end 23.38705 -127.217424)
		(width 0.2794)
		(layer "F.Cu")
		(net "SMB_PDBV_FAN_R_U330_SCL")
	)
	(segment
		(start 23.743158 -124.605034)
		(end 23.38705 -125.465078)
		(width 0.2794)
		(layer "F.Cu")
		(net "SMB_PDBV_FAN_R_U330_SCL")
	)
	(segment
		(start 23.596854 -127.427228)
		(end 23.596854 -128.2573)
		(width 0.1016)
		(layer "F.Cu")
		(net "SMB_PDBV_FAN_R_U330_SCL")
	)
	(segment
		(start 24.048212 -123.868688)
		(end 23.743158 -124.605034)
		(width 0.2794)
		(layer "F.Cu")
		(net "SMB_PDBV_FAN_R_U330_SCL")
	)
	(via
		(at 23.743158 -124.605034)
		(size 0.762)
		(drill 0.381)
		(layers "F.Cu" "B.Cu")
		(net "SMB_PDBV_FAN_R_U330_SCL")
	)
	(segment
		(start 18.30705 -173.99)
		(end 18.30705 -174.04969)
		(width 0.2794)
		(layer "F.Cu")
		(net "FAN_7_PRESENT_R_N")
	)
	(segment
		(start 18.30705 -174.04969)
		(end 17.10944 -175.2473)
		(width 0.2794)
		(layer "F.Cu")
		(net "FAN_7_PRESENT_R_N")
	)
	(segment
		(start 17.10944 -175.2473)
		(end 15.3543 -175.2473)
		(width 0.2794)
		(layer "F.Cu")
		(net "FAN_7_PRESENT_R_N")
	)
	(segment
		(start 15.3543 -175.2473)
		(end 15.10665 -174.99965)
		(width 0.2794)
		(layer "F.Cu")
		(net "FAN_7_PRESENT_R_N")
	)
	(via
		(at 15.10665 -174.99965)
		(size 0.508)
		(drill 0.254)
		(layers "F.Cu" "B.Cu")
		(net "FAN_7_PRESENT_R_N")
	)
	(segment
		(start 13.1064 -180.590952)
		(end 13.1064 -176.9999)
		(width 0.2286)
		(layer "In2.Cu")
		(net "FAN_7_PRESENT_R_N")
	)
	(segment
		(start 13.1064 -176.9999)
		(end 15.10665 -174.99965)
		(width 0.2286)
		(layer "In2.Cu")
		(net "FAN_7_PRESENT_R_N")
	)
	(segment
		(start 14.17828 -247.204738)
		(end 14.17828 -216.03716)
		(width 0.2286)
		(layer "In2.Cu")
		(net "FAN_7_PRESENT_R_N")
	)
	(segment
		(start 11.5824 -288.0106)
		(end 15.668244 -283.924756)
		(width 0.2286)
		(layer "In2.Cu")
		(net "FAN_7_PRESENT_R_N")
	)
	(segment
		(start 20.529042 -278.301958)
		(end 20.529042 -253.5555)
		(width 0.2286)
		(layer "In2.Cu")
		(net "FAN_7_PRESENT_R_N")
	)
	(segment
		(start 15.668244 -283.162756)
		(end 20.529042 -278.301958)
		(width 0.2286)
		(layer "In2.Cu")
		(net "FAN_7_PRESENT_R_N")
	)
	(segment
		(start 10.541 -212.39988)
		(end 10.541 -183.156352)
		(width 0.2286)
		(layer "In2.Cu")
		(net "FAN_7_PRESENT_R_N")
	)
	(segment
		(start 15.668244 -283.924756)
		(end 15.668244 -283.162756)
		(width 0.2286)
		(layer "In2.Cu")
		(net "FAN_7_PRESENT_R_N")
	)
	(segment
		(start 11.5824 -288.427668)
		(end 11.5824 -288.0106)
		(width 0.2286)
		(layer "In2.Cu")
		(net "FAN_7_PRESENT_R_N")
	)
	(segment
		(start 10.541 -183.156352)
		(end 13.1064 -180.590952)
		(width 0.2286)
		(layer "In2.Cu")
		(net "FAN_7_PRESENT_R_N")
	)
	(segment
		(start 20.529042 -253.5555)
		(end 14.17828 -247.204738)
		(width 0.2286)
		(layer "In2.Cu")
		(net "FAN_7_PRESENT_R_N")
	)
	(segment
		(start 14.17828 -216.03716)
		(end 10.541 -212.39988)
		(width 0.2286)
		(layer "In2.Cu")
		(net "FAN_7_PRESENT_R_N")
	)
	(segment
		(start 8.700008 -291.31006)
		(end 11.5824 -288.427668)
		(width 0.2286)
		(layer "In2.Cu")
		(net "FAN_7_PRESENT_R_N")
	)
	(segment
		(start 19.939 -103.124)
		(end 19.06905 -103.124)
		(width 0.2794)
		(layer "F.Cu")
		(net "FAN_5_TACH_IL")
	)
	(segment
		(start 14.45895 -124.587)
		(end 14.45895 -125.222)
		(width 0.2794)
		(layer "F.Cu")
		(net "FAN_5_TACH_IL")
	)
	(via
		(at 19.939 -103.124)
		(size 0.508)
		(drill 0.254)
		(layers "F.Cu" "B.Cu")
		(net "FAN_5_TACH_IL")
	)
	(via
		(at 14.45895 -125.222)
		(size 0.508)
		(drill 0.254)
		(layers "F.Cu" "B.Cu")
		(net "FAN_5_TACH_IL")
	)
	(segment
		(start 16.61795 -127.381)
		(end 14.45895 -125.222)
		(width 0.2794)
		(layer "B.Cu")
		(net "FAN_5_TACH_IL")
	)
	(segment
		(start 17.25295 -127.381)
		(end 16.61795 -127.381)
		(width 0.2794)
		(layer "B.Cu")
		(net "FAN_5_TACH_IL")
	)
	(segment
		(start 19.939 -103.124)
		(end 19.177 -103.886)
		(width 0.2286)
		(layer "In2.Cu")
		(net "FAN_5_TACH_IL")
	)
	(segment
		(start 16.7513 -114.756184)
		(end 16.7513 -118.580916)
		(width 0.2286)
		(layer "In2.Cu")
		(net "FAN_5_TACH_IL")
	)
	(segment
		(start 16.7513 -118.580916)
		(end 17.24914 -119.078756)
		(width 0.2286)
		(layer "In2.Cu")
		(net "FAN_5_TACH_IL")
	)
	(segment
		(start 17.24914 -119.078756)
		(end 17.24914 -122.43181)
		(width 0.2286)
		(layer "In2.Cu")
		(net "FAN_5_TACH_IL")
	)
	(segment
		(start 19.177 -108.331)
		(end 18.522188 -108.985812)
		(width 0.2286)
		(layer "In2.Cu")
		(net "FAN_5_TACH_IL")
	)
	(segment
		(start 18.522188 -108.985812)
		(end 18.522188 -112.985296)
		(width 0.2286)
		(layer "In2.Cu")
		(net "FAN_5_TACH_IL")
	)
	(segment
		(start 19.177 -103.886)
		(end 19.177 -108.331)
		(width 0.2286)
		(layer "In2.Cu")
		(net "FAN_5_TACH_IL")
	)
	(segment
		(start 18.522188 -112.985296)
		(end 16.7513 -114.756184)
		(width 0.2286)
		(layer "In2.Cu")
		(net "FAN_5_TACH_IL")
	)
	(segment
		(start 17.24914 -122.43181)
		(end 14.45895 -125.222)
		(width 0.2286)
		(layer "In2.Cu")
		(net "FAN_5_TACH_IL")
	)
	(segment
		(start 35.32124 -143.62938)
		(end 34.65957 -144.29105)
		(width 0.2794)
		(layer "F.Cu")
		(net "SMB_FAN3_R_SCL")
	)
	(segment
		(start 34.65957 -144.29105)
		(end 34.417 -144.29105)
		(width 0.2794)
		(layer "F.Cu")
		(net "SMB_FAN3_R_SCL")
	)
	(segment
		(start 28.104338 -147.917662)
		(end 27.690064 -148.331936)
		(width 0.2794)
		(layer "F.Cu")
		(net "SMB_FAN3_R_SCL")
	)
	(segment
		(start 34.417 -141.75105)
		(end 35.32124 -142.65529)
		(width 0.2794)
		(layer "F.Cu")
		(net "SMB_FAN3_R_SCL")
	)
	(segment
		(start 27.690064 -148.331936)
		(end 27.690064 -149.098)
		(width 0.2794)
		(layer "F.Cu")
		(net "SMB_FAN3_R_SCL")
	)
	(segment
		(start 34.417 -144.779746)
		(end 31.495746 -147.701)
		(width 0.2794)
		(layer "F.Cu")
		(net "SMB_FAN3_R_SCL")
	)
	(segment
		(start 28.627324 -147.701)
		(end 28.104338 -147.917662)
		(width 0.2794)
		(layer "F.Cu")
		(net "SMB_FAN3_R_SCL")
	)
	(segment
		(start 34.417 -144.29105)
		(end 34.417 -144.779746)
		(width 0.2794)
		(layer "F.Cu")
		(net "SMB_FAN3_R_SCL")
	)
	(segment
		(start 30.48 -147.701)
		(end 28.627324 -147.701)
		(width 0.2794)
		(layer "F.Cu")
		(net "SMB_FAN3_R_SCL")
	)
	(segment
		(start 31.495746 -147.701)
		(end 30.48 -147.701)
		(width 0.2794)
		(layer "F.Cu")
		(net "SMB_FAN3_R_SCL")
	)
	(segment
		(start 35.32124 -142.65529)
		(end 35.32124 -143.62938)
		(width 0.2794)
		(layer "F.Cu")
		(net "SMB_FAN3_R_SCL")
	)
	(via
		(at 30.48 -147.701)
		(size 0.508)
		(drill 0.254)
		(layers "F.Cu" "B.Cu")
		(net "SMB_FAN3_R_SCL")
	)
	(segment
		(start 23.201376 -123.40844)
		(end 22.831806 -125.266704)
		(width 0.2794)
		(layer "F.Cu")
		(net "SMB_PDBV_FAN_R_U330_SDA")
	)
	(segment
		(start 23.369524 -123.002802)
		(end 23.201376 -123.40844)
		(width 0.2794)
		(layer "F.Cu")
		(net "SMB_PDBV_FAN_R_U330_SDA")
	)
	(segment
		(start 22.831806 -126.957328)
		(end 22.831806 -127.347218)
		(width 0.1016)
		(layer "F.Cu")
		(net "SMB_PDBV_FAN_R_U330_SDA")
	)
	(segment
		(start 23.786592 -122.585734)
		(end 23.369524 -123.002802)
		(width 0.2794)
		(layer "F.Cu")
		(net "SMB_PDBV_FAN_R_U330_SDA")
	)
	(segment
		(start 25.12695 -121.539)
		(end 24.833326 -121.539)
		(width 0.2794)
		(layer "F.Cu")
		(net "SMB_PDBV_FAN_R_U330_SDA")
	)
	(segment
		(start 22.954996 -127.470408)
		(end 22.954996 -127.959104)
		(width 0.1016)
		(layer "F.Cu")
		(net "SMB_PDBV_FAN_R_U330_SDA")
	)
	(segment
		(start 22.831806 -125.266704)
		(end 22.831806 -126.957328)
		(width 0.2794)
		(layer "F.Cu")
		(net "SMB_PDBV_FAN_R_U330_SDA")
	)
	(segment
		(start 24.833326 -121.539)
		(end 23.786592 -122.585734)
		(width 0.2794)
		(layer "F.Cu")
		(net "SMB_PDBV_FAN_R_U330_SDA")
	)
	(segment
		(start 22.831806 -127.347218)
		(end 22.954996 -127.470408)
		(width 0.1016)
		(layer "F.Cu")
		(net "SMB_PDBV_FAN_R_U330_SDA")
	)
	(via
		(at 23.786592 -122.585734)
		(size 0.762)
		(drill 0.381)
		(layers "F.Cu" "B.Cu")
		(net "SMB_PDBV_FAN_R_U330_SDA")
	)
	(segment
		(start 14.45895 -131.064)
		(end 14.45895 -131.699)
		(width 0.2794)
		(layer "F.Cu")
		(net "FAN_6_TACH_IL")
	)
	(segment
		(start 17.92605 -195.56095)
		(end 17.526 -195.961)
		(width 0.2794)
		(layer "F.Cu")
		(net "FAN_6_TACH_IL")
	)
	(segment
		(start 18.288 -195.56095)
		(end 17.92605 -195.56095)
		(width 0.2794)
		(layer "F.Cu")
		(net "FAN_6_TACH_IL")
	)
	(via
		(at 14.45895 -131.699)
		(size 0.508)
		(drill 0.254)
		(layers "F.Cu" "B.Cu")
		(net "FAN_6_TACH_IL")
	)
	(via
		(at 17.526 -195.961)
		(size 0.508)
		(drill 0.254)
		(layers "F.Cu" "B.Cu")
		(net "FAN_6_TACH_IL")
	)
	(segment
		(start 17.25295 -130.81)
		(end 15.34795 -130.81)
		(width 0.2794)
		(layer "B.Cu")
		(net "FAN_6_TACH_IL")
	)
	(segment
		(start 15.34795 -130.81)
		(end 14.45895 -131.699)
		(width 0.2794)
		(layer "B.Cu")
		(net "FAN_6_TACH_IL")
	)
	(segment
		(start 18.038064 -182.240936)
		(end 19.5453 -180.7337)
		(width 0.2286)
		(layer "In2.Cu")
		(net "FAN_6_TACH_IL")
	)
	(segment
		(start 16.868902 -140.21054)
		(end 16.868902 -135.926068)
		(width 0.2286)
		(layer "In2.Cu")
		(net "FAN_6_TACH_IL")
	)
	(segment
		(start 15.020036 -131.699)
		(end 14.45895 -131.699)
		(width 0.2286)
		(layer "In2.Cu")
		(net "FAN_6_TACH_IL")
	)
	(segment
		(start 20.921218 -165.86073)
		(end 17.9451 -162.884612)
		(width 0.2286)
		(layer "In2.Cu")
		(net "FAN_6_TACH_IL")
	)
	(segment
		(start 16.60906 -133.288024)
		(end 15.020036 -131.699)
		(width 0.2286)
		(layer "In2.Cu")
		(net "FAN_6_TACH_IL")
	)
	(segment
		(start 20.921218 -179.459382)
		(end 20.921218 -165.86073)
		(width 0.2286)
		(layer "In2.Cu")
		(net "FAN_6_TACH_IL")
	)
	(segment
		(start 16.868902 -135.926068)
		(end 16.60906 -135.666226)
		(width 0.2286)
		(layer "In2.Cu")
		(net "FAN_6_TACH_IL")
	)
	(segment
		(start 16.891 -191.165988)
		(end 17.411192 -190.645796)
		(width 0.2286)
		(layer "In2.Cu")
		(net "FAN_6_TACH_IL")
	)
	(segment
		(start 18.038064 -183.916574)
		(end 18.038064 -182.240936)
		(width 0.2286)
		(layer "In2.Cu")
		(net "FAN_6_TACH_IL")
	)
	(segment
		(start 16.60906 -135.666226)
		(end 16.60906 -133.288024)
		(width 0.2286)
		(layer "In2.Cu")
		(net "FAN_6_TACH_IL")
	)
	(segment
		(start 16.891 -195.326)
		(end 16.891 -191.165988)
		(width 0.2286)
		(layer "In2.Cu")
		(net "FAN_6_TACH_IL")
	)
	(segment
		(start 17.526 -195.961)
		(end 16.891 -195.326)
		(width 0.2286)
		(layer "In2.Cu")
		(net "FAN_6_TACH_IL")
	)
	(segment
		(start 19.5453 -180.7337)
		(end 19.6469 -180.7337)
		(width 0.2286)
		(layer "In2.Cu")
		(net "FAN_6_TACH_IL")
	)
	(segment
		(start 17.9451 -142.808706)
		(end 16.868902 -140.21054)
		(width 0.2286)
		(layer "In2.Cu")
		(net "FAN_6_TACH_IL")
	)
	(segment
		(start 19.6469 -180.7337)
		(end 20.921218 -179.459382)
		(width 0.2286)
		(layer "In2.Cu")
		(net "FAN_6_TACH_IL")
	)
	(segment
		(start 17.9451 -162.884612)
		(end 17.9451 -142.808706)
		(width 0.2286)
		(layer "In2.Cu")
		(net "FAN_6_TACH_IL")
	)
	(segment
		(start 17.411192 -184.543446)
		(end 18.038064 -183.916574)
		(width 0.2286)
		(layer "In2.Cu")
		(net "FAN_6_TACH_IL")
	)
	(segment
		(start 17.411192 -190.645796)
		(end 17.411192 -184.543446)
		(width 0.2286)
		(layer "In2.Cu")
		(net "FAN_6_TACH_IL")
	)
	(segment
		(start 36.93795 -298.196)
		(end 36.703 -298.196)
		(width 0.2794)
		(layer "F.Cu")
		(net "SMB_FAN0_SCL")
	)
	(segment
		(start 23.455376 -143.11122)
		(end 23.606252 -143.475202)
		(width 0.2794)
		(layer "F.Cu")
		(net "SMB_FAN0_SCL")
	)
	(segment
		(start 23.03272 -142.688564)
		(end 23.455376 -143.11122)
		(width 0.2794)
		(layer "F.Cu")
		(net "SMB_FAN0_SCL")
	)
	(segment
		(start 36.703 -298.196)
		(end 36.195 -298.704)
		(width 0.2794)
		(layer "F.Cu")
		(net "SMB_FAN0_SCL")
	)
	(segment
		(start 23.606252 -143.475202)
		(end 23.622 -143.49095)
		(width 0.2794)
		(layer "F.Cu")
		(net "SMB_FAN0_SCL")
	)
	(via
		(at 36.195 -298.704)
		(size 0.508)
		(drill 0.254)
		(layers "F.Cu" "B.Cu")
		(net "SMB_FAN0_SCL")
	)
	(via
		(at 23.03272 -142.688564)
		(size 0.508)
		(drill 0.254)
		(layers "F.Cu" "B.Cu")
		(net "SMB_FAN0_SCL")
	)
	(segment
		(start 31.09214 -213.337394)
		(end 32.076898 -214.322152)
		(width 0.2286)
		(layer "In2.Cu")
		(net "SMB_FAN0_SCL")
	)
	(segment
		(start 23.749 -151.75992)
		(end 23.749 -161.036)
		(width 0.2286)
		(layer "In2.Cu")
		(net "SMB_FAN0_SCL")
	)
	(segment
		(start 22.5298 -148.816314)
		(end 23.749 -151.75992)
		(width 0.2286)
		(layer "In2.Cu")
		(net "SMB_FAN0_SCL")
	)
	(segment
		(start 28.235148 -204.465174)
		(end 28.235148 -211.241894)
		(width 0.2286)
		(layer "In2.Cu")
		(net "SMB_FAN0_SCL")
	)
	(segment
		(start 24.51862 -200.748646)
		(end 28.235148 -204.465174)
		(width 0.2286)
		(layer "In2.Cu")
		(net "SMB_FAN0_SCL")
	)
	(segment
		(start 28.235148 -211.241894)
		(end 30.330648 -213.337394)
		(width 0.2286)
		(layer "In2.Cu")
		(net "SMB_FAN0_SCL")
	)
	(segment
		(start 37.764974 -297.134026)
		(end 36.195 -298.704)
		(width 0.2286)
		(layer "In2.Cu")
		(net "SMB_FAN0_SCL")
	)
	(segment
		(start 27.126692 -164.413692)
		(end 27.126692 -181.937914)
		(width 0.2286)
		(layer "In2.Cu")
		(net "SMB_FAN0_SCL")
	)
	(segment
		(start 27.126692 -181.937914)
		(end 25.0698 -183.994806)
		(width 0.2286)
		(layer "In2.Cu")
		(net "SMB_FAN0_SCL")
	)
	(segment
		(start 28.4988 -280.663142)
		(end 37.764974 -289.929316)
		(width 0.2286)
		(layer "In2.Cu")
		(net "SMB_FAN0_SCL")
	)
	(segment
		(start 32.076898 -241.056668)
		(end 29.384244 -247.557036)
		(width 0.2286)
		(layer "In2.Cu")
		(net "SMB_FAN0_SCL")
	)
	(segment
		(start 22.82444 -142.688564)
		(end 22.5298 -142.983204)
		(width 0.2286)
		(layer "In2.Cu")
		(net "SMB_FAN0_SCL")
	)
	(segment
		(start 23.03272 -142.688564)
		(end 22.82444 -142.688564)
		(width 0.2286)
		(layer "In2.Cu")
		(net "SMB_FAN0_SCL")
	)
	(segment
		(start 30.330648 -213.337394)
		(end 31.09214 -213.337394)
		(width 0.2286)
		(layer "In2.Cu")
		(net "SMB_FAN0_SCL")
	)
	(segment
		(start 23.749 -161.036)
		(end 27.126692 -164.413692)
		(width 0.2286)
		(layer "In2.Cu")
		(net "SMB_FAN0_SCL")
	)
	(segment
		(start 37.764974 -289.929316)
		(end 37.764974 -297.134026)
		(width 0.2286)
		(layer "In2.Cu")
		(net "SMB_FAN0_SCL")
	)
	(segment
		(start 22.5298 -142.983204)
		(end 22.5298 -148.816314)
		(width 0.2286)
		(layer "In2.Cu")
		(net "SMB_FAN0_SCL")
	)
	(segment
		(start 32.076898 -214.322152)
		(end 32.076898 -241.056668)
		(width 0.2286)
		(layer "In2.Cu")
		(net "SMB_FAN0_SCL")
	)
	(segment
		(start 24.51862 -195.847208)
		(end 24.51862 -200.748646)
		(width 0.2286)
		(layer "In2.Cu")
		(net "SMB_FAN0_SCL")
	)
	(segment
		(start 25.0698 -195.296028)
		(end 24.51862 -195.847208)
		(width 0.2286)
		(layer "In2.Cu")
		(net "SMB_FAN0_SCL")
	)
	(segment
		(start 25.0698 -183.994806)
		(end 25.0698 -195.296028)
		(width 0.2286)
		(layer "In2.Cu")
		(net "SMB_FAN0_SCL")
	)
	(segment
		(start 28.4988 -248.44248)
		(end 28.4988 -280.663142)
		(width 0.2286)
		(layer "In2.Cu")
		(net "SMB_FAN0_SCL")
	)
	(segment
		(start 29.384244 -247.557036)
		(end 28.4988 -248.44248)
		(width 0.2286)
		(layer "In2.Cu")
		(net "SMB_FAN0_SCL")
	)
	(segment
		(start 27.051 -132.19684)
		(end 27.051 -134.35965)
		(width 0.2794)
		(layer "F.Cu")
		(net "SMB_PDBV_FAN_R_U317_SCL")
	)
	(segment
		(start 28.702 -130.074416)
		(end 28.702 -130.1623)
		(width 0.2794)
		(layer "F.Cu")
		(net "SMB_PDBV_FAN_R_U317_SCL")
	)
	(segment
		(start 29.496004 -129.9591)
		(end 28.817316 -129.9591)
		(width 0.1016)
		(layer "F.Cu")
		(net "SMB_PDBV_FAN_R_U317_SCL")
	)
	(segment
		(start 27.22118 -131.555236)
		(end 27.22118 -131.95046)
		(width 0.2794)
		(layer "F.Cu")
		(net "SMB_PDBV_FAN_R_U317_SCL")
	)
	(segment
		(start 26.924 -134.48665)
		(end 26.924 -134.98195)
		(width 0.2794)
		(layer "F.Cu")
		(net "SMB_PDBV_FAN_R_U317_SCL")
	)
	(segment
		(start 27.051 -134.35965)
		(end 26.924 -134.48665)
		(width 0.2794)
		(layer "F.Cu")
		(net "SMB_PDBV_FAN_R_U317_SCL")
	)
	(segment
		(start 28.702 -130.1623)
		(end 27.9273 -130.937)
		(width 0.2794)
		(layer "F.Cu")
		(net "SMB_PDBV_FAN_R_U317_SCL")
	)
	(segment
		(start 27.22118 -131.95046)
		(end 27.25928 -131.98856)
		(width 0.2794)
		(layer "F.Cu")
		(net "SMB_PDBV_FAN_R_U317_SCL")
	)
	(segment
		(start 27.839416 -130.937)
		(end 27.22118 -131.555236)
		(width 0.2794)
		(layer "F.Cu")
		(net "SMB_PDBV_FAN_R_U317_SCL")
	)
	(segment
		(start 27.25928 -131.98856)
		(end 27.051 -132.19684)
		(width 0.2794)
		(layer "F.Cu")
		(net "SMB_PDBV_FAN_R_U317_SCL")
	)
	(segment
		(start 27.9273 -130.937)
		(end 27.839416 -130.937)
		(width 0.2794)
		(layer "F.Cu")
		(net "SMB_PDBV_FAN_R_U317_SCL")
	)
	(segment
		(start 28.817316 -129.9591)
		(end 28.702 -130.074416)
		(width 0.1016)
		(layer "F.Cu")
		(net "SMB_PDBV_FAN_R_U317_SCL")
	)
	(via
		(at 27.25928 -131.98856)
		(size 0.762)
		(drill 0.381)
		(layers "F.Cu" "B.Cu")
		(net "SMB_PDBV_FAN_R_U317_SCL")
	)
	(segment
		(start 26.171398 -158.613348)
		(end 25.740106 -158.182056)
		(width 0.2794)
		(layer "F.Cu")
		(net "SMB_FAN6_R_SDA")
	)
	(segment
		(start 27.813 -160.574482)
		(end 27.813 -161.417)
		(width 0.2794)
		(layer "F.Cu")
		(net "SMB_FAN6_R_SDA")
	)
	(segment
		(start 25.740106 -158.182056)
		(end 25.740106 -154.94)
		(width 0.2794)
		(layer "F.Cu")
		(net "SMB_FAN6_R_SDA")
	)
	(segment
		(start 27.813 -161.417)
		(end 27.178 -162.052)
		(width 0.2794)
		(layer "F.Cu")
		(net "SMB_FAN6_R_SDA")
	)
	(segment
		(start 26.171398 -158.613348)
		(end 26.67 -159.11195)
		(width 0.2794)
		(layer "F.Cu")
		(net "SMB_FAN6_R_SDA")
	)
	(segment
		(start 26.67 -159.61995)
		(end 26.858468 -159.61995)
		(width 0.2794)
		(layer "F.Cu")
		(net "SMB_FAN6_R_SDA")
	)
	(segment
		(start 27.178 -162.052)
		(end 27.178 -162.54095)
		(width 0.2794)
		(layer "F.Cu")
		(net "SMB_FAN6_R_SDA")
	)
	(segment
		(start 26.858468 -159.61995)
		(end 27.813 -160.574482)
		(width 0.2794)
		(layer "F.Cu")
		(net "SMB_FAN6_R_SDA")
	)
	(segment
		(start 26.67 -159.11195)
		(end 26.67 -159.61995)
		(width 0.2794)
		(layer "F.Cu")
		(net "SMB_FAN6_R_SDA")
	)
	(via
		(at 26.171398 -158.613348)
		(size 0.508)
		(drill 0.254)
		(layers "F.Cu" "B.Cu")
		(net "SMB_FAN6_R_SDA")
	)
	(segment
		(start 19.06905 -289.179)
		(end 19.689572 -289.179)
		(width 0.2794)
		(layer "F.Cu")
		(net "FAN_7_TACH_IL")
	)
	(segment
		(start 14.45895 -132.334)
		(end 14.45895 -132.969)
		(width 0.2794)
		(layer "F.Cu")
		(net "FAN_7_TACH_IL")
	)
	(via
		(at 19.689572 -289.179)
		(size 0.508)
		(drill 0.254)
		(layers "F.Cu" "B.Cu")
		(net "FAN_7_TACH_IL")
	)
	(via
		(at 14.45895 -132.969)
		(size 0.508)
		(drill 0.254)
		(layers "F.Cu" "B.Cu")
		(net "FAN_7_TACH_IL")
	)
	(segment
		(start 15.143734 -132.969)
		(end 14.45895 -132.969)
		(width 0.2794)
		(layer "B.Cu")
		(net "FAN_7_TACH_IL")
	)
	(segment
		(start 17.25295 -131.953)
		(end 16.159734 -131.953)
		(width 0.2794)
		(layer "B.Cu")
		(net "FAN_7_TACH_IL")
	)
	(segment
		(start 16.159734 -131.953)
		(end 15.143734 -132.969)
		(width 0.2794)
		(layer "B.Cu")
		(net "FAN_7_TACH_IL")
	)
	(segment
		(start 19.689572 -289.179)
		(end 19.600672 -289.179)
		(width 0.2286)
		(layer "In2.Cu")
		(net "FAN_7_TACH_IL")
	)
	(segment
		(start 19.168872 -293.886128)
		(end 17.653 -295.402)
		(width 0.2286)
		(layer "In2.Cu")
		(net "FAN_7_TACH_IL")
	)
	(segment
		(start 16.743172 -143.057372)
		(end 15.748 -140.654532)
		(width 0.2286)
		(layer "In2.Cu")
		(net "FAN_7_TACH_IL")
	)
	(segment
		(start 17.653 -295.402)
		(end 15.367 -295.402)
		(width 0.2286)
		(layer "In2.Cu")
		(net "FAN_7_TACH_IL")
	)
	(segment
		(start 13.687044 -287.476184)
		(end 22.4028 -278.760428)
		(width 0.2286)
		(layer "In2.Cu")
		(net "FAN_7_TACH_IL")
	)
	(segment
		(start 12.8016 -212.21954)
		(end 12.8016 -184.123584)
		(width 0.2286)
		(layer "In2.Cu")
		(net "FAN_7_TACH_IL")
	)
	(segment
		(start 13.687044 -293.722044)
		(end 13.687044 -287.476184)
		(width 0.2286)
		(layer "In2.Cu")
		(net "FAN_7_TACH_IL")
	)
	(segment
		(start 19.7104 -172.9232)
		(end 19.7104 -166.266114)
		(width 0.2286)
		(layer "In2.Cu")
		(net "FAN_7_TACH_IL")
	)
	(segment
		(start 22.4028 -253.158498)
		(end 15.872714 -246.628412)
		(width 0.2286)
		(layer "In2.Cu")
		(net "FAN_7_TACH_IL")
	)
	(segment
		(start 19.168872 -289.6108)
		(end 19.168872 -293.886128)
		(width 0.2286)
		(layer "In2.Cu")
		(net "FAN_7_TACH_IL")
	)
	(segment
		(start 19.600672 -289.179)
		(end 19.168872 -289.6108)
		(width 0.2286)
		(layer "In2.Cu")
		(net "FAN_7_TACH_IL")
	)
	(segment
		(start 15.54226 -134.05231)
		(end 14.45895 -132.969)
		(width 0.2286)
		(layer "In2.Cu")
		(net "FAN_7_TACH_IL")
	)
	(segment
		(start 16.743172 -163.298886)
		(end 16.743172 -143.057372)
		(width 0.2286)
		(layer "In2.Cu")
		(net "FAN_7_TACH_IL")
	)
	(segment
		(start 12.8016 -184.123584)
		(end 19.0246 -177.900584)
		(width 0.2286)
		(layer "In2.Cu")
		(net "FAN_7_TACH_IL")
	)
	(segment
		(start 19.0246 -177.900584)
		(end 19.0246 -173.609)
		(width 0.2286)
		(layer "In2.Cu")
		(net "FAN_7_TACH_IL")
	)
	(segment
		(start 15.54226 -136.20496)
		(end 15.54226 -134.05231)
		(width 0.2286)
		(layer "In2.Cu")
		(net "FAN_7_TACH_IL")
	)
	(segment
		(start 15.748 -136.4107)
		(end 15.54226 -136.20496)
		(width 0.2286)
		(layer "In2.Cu")
		(net "FAN_7_TACH_IL")
	)
	(segment
		(start 15.748 -140.654532)
		(end 15.748 -136.4107)
		(width 0.2286)
		(layer "In2.Cu")
		(net "FAN_7_TACH_IL")
	)
	(segment
		(start 19.0246 -173.609)
		(end 19.7104 -172.9232)
		(width 0.2286)
		(layer "In2.Cu")
		(net "FAN_7_TACH_IL")
	)
	(segment
		(start 15.872714 -215.290654)
		(end 12.8016 -212.21954)
		(width 0.2286)
		(layer "In2.Cu")
		(net "FAN_7_TACH_IL")
	)
	(segment
		(start 15.367 -295.402)
		(end 13.687044 -293.722044)
		(width 0.2286)
		(layer "In2.Cu")
		(net "FAN_7_TACH_IL")
	)
	(segment
		(start 22.4028 -278.760428)
		(end 22.4028 -253.158498)
		(width 0.2286)
		(layer "In2.Cu")
		(net "FAN_7_TACH_IL")
	)
	(segment
		(start 15.872714 -246.628412)
		(end 15.872714 -215.290654)
		(width 0.2286)
		(layer "In2.Cu")
		(net "FAN_7_TACH_IL")
	)
	(segment
		(start 19.7104 -166.266114)
		(end 16.743172 -163.298886)
		(width 0.2286)
		(layer "In2.Cu")
		(net "FAN_7_TACH_IL")
	)
	(segment
		(start 25.654 -143.49095)
		(end 25.551638 -143.49095)
		(width 0.2794)
		(layer "F.Cu")
		(net "SMB_FAN1_SDA")
	)
	(segment
		(start 36.93795 -204.752956)
		(end 36.859718 -204.674724)
		(width 0.2794)
		(layer "F.Cu")
		(net "SMB_FAN1_SDA")
	)
	(segment
		(start 24.638 -144.404588)
		(end 24.638 -144.564862)
		(width 0.2794)
		(layer "F.Cu")
		(net "SMB_FAN1_SDA")
	)
	(segment
		(start 25.551638 -143.49095)
		(end 24.638 -144.404588)
		(width 0.2794)
		(layer "F.Cu")
		(net "SMB_FAN1_SDA")
	)
	(segment
		(start 36.186618 -204.396086)
		(end 35.836352 -204.396086)
		(width 0.2794)
		(layer "F.Cu")
		(net "SMB_FAN1_SDA")
	)
	(segment
		(start 36.859718 -204.674724)
		(end 36.186618 -204.396086)
		(width 0.2794)
		(layer "F.Cu")
		(net "SMB_FAN1_SDA")
	)
	(via
		(at 35.836352 -204.396086)
		(size 0.508)
		(drill 0.254)
		(layers "F.Cu" "B.Cu")
		(net "SMB_FAN1_SDA")
	)
	(via
		(at 24.638 -144.564862)
		(size 0.508)
		(drill 0.254)
		(layers "F.Cu" "B.Cu")
		(net "SMB_FAN1_SDA")
	)
	(segment
		(start 26.67 -196.746876)
		(end 26.67 -201.803)
		(width 0.2286)
		(layer "In2.Cu")
		(net "SMB_FAN1_SDA")
	)
	(segment
		(start 27.178 -184.827926)
		(end 27.178 -196.238876)
		(width 0.2286)
		(layer "In2.Cu")
		(net "SMB_FAN1_SDA")
	)
	(segment
		(start 29.2481 -165.264084)
		(end 29.2481 -182.757826)
		(width 0.2286)
		(layer "In2.Cu")
		(net "SMB_FAN1_SDA")
	)
	(segment
		(start 36.170616 -204.73035)
		(end 35.836352 -204.396086)
		(width 0.2286)
		(layer "In2.Cu")
		(net "SMB_FAN1_SDA")
	)
	(segment
		(start 30.699202 -162.777424)
		(end 30.699202 -163.812982)
		(width 0.2286)
		(layer "In2.Cu")
		(net "SMB_FAN1_SDA")
	)
	(segment
		(start 36.170616 -207.39862)
		(end 36.170616 -204.73035)
		(width 0.2286)
		(layer "In2.Cu")
		(net "SMB_FAN1_SDA")
	)
	(segment
		(start 34.577782 -208.991454)
		(end 36.170616 -207.39862)
		(width 0.2286)
		(layer "In2.Cu")
		(net "SMB_FAN1_SDA")
	)
	(segment
		(start 30.607 -205.74)
		(end 30.607 -208.102454)
		(width 0.2286)
		(layer "In2.Cu")
		(net "SMB_FAN1_SDA")
	)
	(segment
		(start 25.4 -149.564852)
		(end 25.4 -149.691852)
		(width 0.2286)
		(layer "In2.Cu")
		(net "SMB_FAN1_SDA")
	)
	(segment
		(start 30.699202 -163.812982)
		(end 29.2481 -165.264084)
		(width 0.2286)
		(layer "In2.Cu")
		(net "SMB_FAN1_SDA")
	)
	(segment
		(start 27.178 -196.238876)
		(end 26.67 -196.746876)
		(width 0.2286)
		(layer "In2.Cu")
		(net "SMB_FAN1_SDA")
	)
	(segment
		(start 24.638 -147.68576)
		(end 25.4 -149.564852)
		(width 0.2286)
		(layer "In2.Cu")
		(net "SMB_FAN1_SDA")
	)
	(segment
		(start 24.638 -144.564862)
		(end 24.638 -147.68576)
		(width 0.2286)
		(layer "In2.Cu")
		(net "SMB_FAN1_SDA")
	)
	(segment
		(start 31.496 -208.991454)
		(end 34.577782 -208.991454)
		(width 0.2286)
		(layer "In2.Cu")
		(net "SMB_FAN1_SDA")
	)
	(segment
		(start 25.4 -149.691852)
		(end 30.699202 -162.777424)
		(width 0.2286)
		(layer "In2.Cu")
		(net "SMB_FAN1_SDA")
	)
	(segment
		(start 26.67 -201.803)
		(end 30.607 -205.74)
		(width 0.2286)
		(layer "In2.Cu")
		(net "SMB_FAN1_SDA")
	)
	(segment
		(start 30.607 -208.102454)
		(end 31.496 -208.991454)
		(width 0.2286)
		(layer "In2.Cu")
		(net "SMB_FAN1_SDA")
	)
	(segment
		(start 29.2481 -182.757826)
		(end 27.178 -184.827926)
		(width 0.2286)
		(layer "In2.Cu")
		(net "SMB_FAN1_SDA")
	)
	(segment
		(start 27.94 -132.83057)
		(end 28.653486 -131.107942)
		(width 0.2794)
		(layer "F.Cu")
		(net "SMB_PDBV_FAN_R_U317_SDA")
	)
	(segment
		(start 27.94 -133.72846)
		(end 27.94 -132.83057)
		(width 0.2794)
		(layer "F.Cu")
		(net "SMB_PDBV_FAN_R_U317_SDA")
	)
	(segment
		(start 28.956254 -130.59029)
		(end 29.187648 -130.358896)
		(width 0.1016)
		(layer "F.Cu")
		(net "SMB_PDBV_FAN_R_U317_SDA")
	)
	(segment
		(start 27.94 -134.98195)
		(end 27.94 -133.72846)
		(width 0.2794)
		(layer "F.Cu")
		(net "SMB_PDBV_FAN_R_U317_SDA")
	)
	(segment
		(start 28.653486 -131.107942)
		(end 28.956254 -130.805174)
		(width 0.1016)
		(layer "F.Cu")
		(net "SMB_PDBV_FAN_R_U317_SDA")
	)
	(segment
		(start 28.956254 -130.805174)
		(end 28.956254 -130.59029)
		(width 0.1016)
		(layer "F.Cu")
		(net "SMB_PDBV_FAN_R_U317_SDA")
	)
	(segment
		(start 29.187648 -130.358896)
		(end 29.496004 -130.358896)
		(width 0.1016)
		(layer "F.Cu")
		(net "SMB_PDBV_FAN_R_U317_SDA")
	)
	(via
		(at 27.94 -133.72846)
		(size 0.762)
		(drill 0.381)
		(layers "F.Cu" "B.Cu")
		(net "SMB_PDBV_FAN_R_U317_SDA")
	)
	(segment
		(start 25.09012 -159.54883)
		(end 25.09012 -156.718)
		(width 0.2794)
		(layer "F.Cu")
		(net "SMB_FAN6_R_SCL")
	)
	(segment
		(start 25.019 -162.54095)
		(end 25.781 -161.77895)
		(width 0.2794)
		(layer "F.Cu")
		(net "SMB_FAN6_R_SCL")
	)
	(segment
		(start 25.781 -161.77895)
		(end 25.781 -160.061402)
		(width 0.2794)
		(layer "F.Cu")
		(net "SMB_FAN6_R_SCL")
	)
	(segment
		(start 25.09012 -154.94)
		(end 25.09012 -156.718)
		(width 0.2794)
		(layer "F.Cu")
		(net "SMB_FAN6_R_SCL")
	)
	(segment
		(start 25.781 -160.061402)
		(end 25.339548 -159.61995)
		(width 0.2794)
		(layer "F.Cu")
		(net "SMB_FAN6_R_SCL")
	)
	(segment
		(start 25.339548 -159.61995)
		(end 25.019 -159.61995)
		(width 0.2794)
		(layer "F.Cu")
		(net "SMB_FAN6_R_SCL")
	)
	(segment
		(start 25.019 -159.61995)
		(end 25.09012 -159.54883)
		(width 0.2794)
		(layer "F.Cu")
		(net "SMB_FAN6_R_SCL")
	)
	(via
		(at 25.09012 -156.718)
		(size 0.508)
		(drill 0.254)
		(layers "F.Cu" "B.Cu")
		(net "SMB_FAN6_R_SCL")
	)
	(segment
		(start 11.9126 -201.962512)
		(end 7.747508 -201.962512)
		(width 0.2794)
		(layer "F.Cu")
		(net "SMB_FAN6_SDA_R")
	)
	(segment
		(start 12.540234 -201.962512)
		(end 11.9126 -201.962512)
		(width 0.2794)
		(layer "F.Cu")
		(net "SMB_FAN6_SDA_R")
	)
	(segment
		(start 13.17879 -201.323956)
		(end 12.540234 -201.962512)
		(width 0.2794)
		(layer "F.Cu")
		(net "SMB_FAN6_SDA_R")
	)
	(segment
		(start 13.95095 -201.323956)
		(end 13.17879 -201.323956)
		(width 0.2794)
		(layer "F.Cu")
		(net "SMB_FAN6_SDA_R")
	)
	(segment
		(start 7.747508 -201.962512)
		(end 6.700012 -203.010008)
		(width 0.2794)
		(layer "F.Cu")
		(net "SMB_FAN6_SDA_R")
	)
	(via
		(at 11.9126 -201.962512)
		(size 0.762)
		(drill 0.381)
		(layers "F.Cu" "B.Cu")
		(net "SMB_FAN6_SDA_R")
	)
	(segment
		(start 30.861 -141.605)
		(end 29.972 -142.494)
		(width 0.2794)
		(layer "F.Cu")
		(net "SMB_FAN2_SDA")
	)
	(segment
		(start 28.872688 -110.236)
		(end 30.104588 -111.4679)
		(width 0.2794)
		(layer "F.Cu")
		(net "SMB_FAN2_SDA")
	)
	(segment
		(start 23.259034 -110.254034)
		(end 23.277322 -110.236)
		(width 0.2794)
		(layer "F.Cu")
		(net "SMB_FAN2_SDA")
	)
	(segment
		(start 29.972 -143.23695)
		(end 29.718 -143.49095)
		(width 0.2794)
		(layer "F.Cu")
		(net "SMB_FAN2_SDA")
	)
	(segment
		(start 23.241 -110.236)
		(end 23.259034 -110.254034)
		(width 0.2794)
		(layer "F.Cu")
		(net "SMB_FAN2_SDA")
	)
	(segment
		(start 23.277322 -110.236)
		(end 28.872688 -110.236)
		(width 0.2794)
		(layer "F.Cu")
		(net "SMB_FAN2_SDA")
	)
	(segment
		(start 29.972 -142.494)
		(end 29.972 -143.23695)
		(width 0.2794)
		(layer "F.Cu")
		(net "SMB_FAN2_SDA")
	)
	(segment
		(start 30.104588 -111.4679)
		(end 35.952938 -111.4679)
		(width 0.2794)
		(layer "F.Cu")
		(net "SMB_FAN2_SDA")
	)
	(segment
		(start 35.952938 -111.4679)
		(end 36.93795 -112.452912)
		(width 0.2794)
		(layer "F.Cu")
		(net "SMB_FAN2_SDA")
	)
	(via
		(at 30.861 -141.605)
		(size 0.508)
		(drill 0.254)
		(layers "F.Cu" "B.Cu")
		(net "SMB_FAN2_SDA")
	)
	(via
		(at 23.241 -110.236)
		(size 0.508)
		(drill 0.254)
		(layers "F.Cu" "B.Cu")
		(net "SMB_FAN2_SDA")
	)
	(segment
		(start 31.788354 -126.296674)
		(end 31.788354 -139.193016)
		(width 0.2286)
		(layer "In2.Cu")
		(net "SMB_FAN2_SDA")
	)
	(segment
		(start 23.241 -110.236)
		(end 22.518116 -110.958884)
		(width 0.2286)
		(layer "In2.Cu")
		(net "SMB_FAN2_SDA")
	)
	(segment
		(start 22.518116 -115.187476)
		(end 28.067 -120.73636)
		(width 0.2286)
		(layer "In2.Cu")
		(net "SMB_FAN2_SDA")
	)
	(segment
		(start 29.591 -124.09932)
		(end 31.788354 -126.296674)
		(width 0.2286)
		(layer "In2.Cu")
		(net "SMB_FAN2_SDA")
	)
	(segment
		(start 22.518116 -110.958884)
		(end 22.518116 -115.187476)
		(width 0.2286)
		(layer "In2.Cu")
		(net "SMB_FAN2_SDA")
	)
	(segment
		(start 30.988 -139.99337)
		(end 30.988 -141.478)
		(width 0.2286)
		(layer "In2.Cu")
		(net "SMB_FAN2_SDA")
	)
	(segment
		(start 29.591 -122.808746)
		(end 29.591 -124.09932)
		(width 0.2286)
		(layer "In2.Cu")
		(net "SMB_FAN2_SDA")
	)
	(segment
		(start 31.788354 -139.193016)
		(end 30.988 -139.99337)
		(width 0.2286)
		(layer "In2.Cu")
		(net "SMB_FAN2_SDA")
	)
	(segment
		(start 30.988 -141.478)
		(end 30.861 -141.605)
		(width 0.2286)
		(layer "In2.Cu")
		(net "SMB_FAN2_SDA")
	)
	(segment
		(start 28.067 -121.284746)
		(end 29.591 -122.808746)
		(width 0.2286)
		(layer "In2.Cu")
		(net "SMB_FAN2_SDA")
	)
	(segment
		(start 28.067 -120.73636)
		(end 28.067 -121.284746)
		(width 0.2286)
		(layer "In2.Cu")
		(net "SMB_FAN2_SDA")
	)
	(segment
		(start 32.131 -162.54095)
		(end 32.512 -162.15995)
		(width 0.2794)
		(layer "F.Cu")
		(net "SMB_FAN4_R_SCL")
	)
	(segment
		(start 30.49905 -156.845)
		(end 28.702 -156.845)
		(width 0.2794)
		(layer "F.Cu")
		(net "SMB_FAN4_R_SCL")
	)
	(segment
		(start 33.274 -159.61995)
		(end 31.578042 -157.923992)
		(width 0.2794)
		(layer "F.Cu")
		(net "SMB_FAN4_R_SCL")
	)
	(segment
		(start 32.512 -162.15995)
		(end 32.512 -160.06826)
		(width 0.2794)
		(layer "F.Cu")
		(net "SMB_FAN4_R_SCL")
	)
	(segment
		(start 27.690064 -155.833064)
		(end 27.690064 -154.94)
		(width 0.2794)
		(layer "F.Cu")
		(net "SMB_FAN4_R_SCL")
	)
	(segment
		(start 31.578042 -157.923992)
		(end 30.49905 -156.845)
		(width 0.2794)
		(layer "F.Cu")
		(net "SMB_FAN4_R_SCL")
	)
	(segment
		(start 32.512 -160.06826)
		(end 32.96031 -159.61995)
		(width 0.2794)
		(layer "F.Cu")
		(net "SMB_FAN4_R_SCL")
	)
	(segment
		(start 32.96031 -159.61995)
		(end 33.274 -159.61995)
		(width 0.2794)
		(layer "F.Cu")
		(net "SMB_FAN4_R_SCL")
	)
	(segment
		(start 28.702 -156.845)
		(end 27.690064 -155.833064)
		(width 0.2794)
		(layer "F.Cu")
		(net "SMB_FAN4_R_SCL")
	)
	(via
		(at 31.578042 -157.923992)
		(size 0.762)
		(drill 0.381)
		(layers "F.Cu" "B.Cu")
		(net "SMB_FAN4_R_SCL")
	)
	(segment
		(start 28.934156 -146.812)
		(end 27.670506 -147.335494)
		(width 0.2794)
		(layer "F.Cu")
		(net "SMB_FAN3_R_SDA")
	)
	(segment
		(start 30.88005 -146.812)
		(end 28.934156 -146.812)
		(width 0.2794)
		(layer "F.Cu")
		(net "SMB_FAN3_R_SDA")
	)
	(segment
		(start 33.401 -141.75105)
		(end 32.639 -142.51305)
		(width 0.2794)
		(layer "F.Cu")
		(net "SMB_FAN3_R_SDA")
	)
	(segment
		(start 32.639 -142.51305)
		(end 32.639 -143.98625)
		(width 0.2794)
		(layer "F.Cu")
		(net "SMB_FAN3_R_SDA")
	)
	(segment
		(start 27.670506 -147.335494)
		(end 27.267916 -147.738084)
		(width 0.2794)
		(layer "F.Cu")
		(net "SMB_FAN3_R_SDA")
	)
	(segment
		(start 32.9438 -144.29105)
		(end 33.401 -144.29105)
		(width 0.2794)
		(layer "F.Cu")
		(net "SMB_FAN3_R_SDA")
	)
	(segment
		(start 31.395162 -146.296888)
		(end 30.88005 -146.812)
		(width 0.2794)
		(layer "F.Cu")
		(net "SMB_FAN3_R_SDA")
	)
	(segment
		(start 32.639 -143.98625)
		(end 32.9438 -144.29105)
		(width 0.2794)
		(layer "F.Cu")
		(net "SMB_FAN3_R_SDA")
	)
	(segment
		(start 27.040078 -148.287994)
		(end 27.040078 -149.098)
		(width 0.2794)
		(layer "F.Cu")
		(net "SMB_FAN3_R_SDA")
	)
	(segment
		(start 31.395162 -146.296888)
		(end 33.401 -144.29105)
		(width 0.2794)
		(layer "F.Cu")
		(net "SMB_FAN3_R_SDA")
	)
	(segment
		(start 27.267916 -147.738084)
		(end 27.040078 -148.287994)
		(width 0.2794)
		(layer "F.Cu")
		(net "SMB_FAN3_R_SDA")
	)
	(via
		(at 31.395162 -146.296888)
		(size 0.762)
		(drill 0.381)
		(layers "F.Cu" "B.Cu")
		(net "SMB_FAN3_R_SDA")
	)
	(segment
		(start 24.003 -160.401)
		(end 23.22195 -159.61995)
		(width 0.2794)
		(layer "F.Cu")
		(net "SMB_FAN7_R_SDA")
	)
	(segment
		(start 24.315928 -158.016956)
		(end 24.43988 -157.893004)
		(width 0.2794)
		(layer "F.Cu")
		(net "SMB_FAN7_R_SDA")
	)
	(segment
		(start 23.1394 -159.193484)
		(end 23.1394 -159.61995)
		(width 0.2794)
		(layer "F.Cu")
		(net "SMB_FAN7_R_SDA")
	)
	(segment
		(start 24.315928 -158.016956)
		(end 23.1394 -159.193484)
		(width 0.2794)
		(layer "F.Cu")
		(net "SMB_FAN7_R_SDA")
	)
	(segment
		(start 24.43988 -157.893004)
		(end 24.43988 -154.94)
		(width 0.2794)
		(layer "F.Cu")
		(net "SMB_FAN7_R_SDA")
	)
	(segment
		(start 24.003 -162.03295)
		(end 24.003 -160.401)
		(width 0.2794)
		(layer "F.Cu")
		(net "SMB_FAN7_R_SDA")
	)
	(segment
		(start 23.22195 -159.61995)
		(end 23.1394 -159.61995)
		(width 0.2794)
		(layer "F.Cu")
		(net "SMB_FAN7_R_SDA")
	)
	(segment
		(start 23.1394 -159.61995)
		(end 23.114 -159.61995)
		(width 0.2794)
		(layer "F.Cu")
		(net "SMB_FAN7_R_SDA")
	)
	(segment
		(start 23.495 -162.54095)
		(end 24.003 -162.03295)
		(width 0.2794)
		(layer "F.Cu")
		(net "SMB_FAN7_R_SDA")
	)
	(via
		(at 24.315928 -158.016956)
		(size 0.762)
		(drill 0.381)
		(layers "F.Cu" "B.Cu")
		(net "SMB_FAN7_R_SDA")
	)
	(via
		(at 2.187448 -245.698518)
		(size 0.6604)
		(drill 0.3302)
		(layers "F.Cu" "B.Cu")
		(net "FAN_6_CS")
	)
	(segment
		(start 1.651 -248.617486)
		(end 1.43256 -248.399046)
		(width 0.2794)
		(layer "B.Cu")
		(net "FAN_6_CS")
	)
	(segment
		(start 3.435604 -245.698518)
		(end 2.187448 -245.698518)
		(width 0.2794)
		(layer "B.Cu")
		(net "FAN_6_CS")
	)
	(segment
		(start 3.700272 -245.945152)
		(end 3.466338 -245.711218)
		(width 0.1016)
		(layer "B.Cu")
		(net "FAN_6_CS")
	)
	(segment
		(start 3.466338 -245.711218)
		(end 3.435604 -245.698518)
		(width 0.1016)
		(layer "B.Cu")
		(net "FAN_6_CS")
	)
	(segment
		(start 2.050796 -245.83517)
		(end 2.187448 -245.698518)
		(width 0.2794)
		(layer "B.Cu")
		(net "FAN_6_CS")
	)
	(segment
		(start 1.43256 -247.325896)
		(end 2.050796 -245.83517)
		(width 0.2794)
		(layer "B.Cu")
		(net "FAN_6_CS")
	)
	(segment
		(start 1.43256 -248.399046)
		(end 1.43256 -247.325896)
		(width 0.2794)
		(layer "B.Cu")
		(net "FAN_6_CS")
	)
	(segment
		(start 1.651 -249.02795)
		(end 1.651 -248.617486)
		(width 0.2794)
		(layer "B.Cu")
		(net "FAN_6_CS")
	)
	(segment
		(start 36.21278 -205.440788)
		(end 36.667948 -205.895956)
		(width 0.2794)
		(layer "F.Cu")
		(net "SMB_FAN1_SCL")
	)
	(segment
		(start 35.160712 -204.953362)
		(end 35.648138 -205.440788)
		(width 0.2794)
		(layer "F.Cu")
		(net "SMB_FAN1_SCL")
	)
	(segment
		(start 27.305 -143.0274)
		(end 27.305 -143.49095)
		(width 0.2794)
		(layer "F.Cu")
		(net "SMB_FAN1_SCL")
	)
	(segment
		(start 35.648138 -205.440788)
		(end 36.21278 -205.440788)
		(width 0.2794)
		(layer "F.Cu")
		(net "SMB_FAN1_SCL")
	)
	(segment
		(start 27.172158 -142.727426)
		(end 27.172158 -142.894558)
		(width 0.2794)
		(layer "F.Cu")
		(net "SMB_FAN1_SCL")
	)
	(segment
		(start 27.172158 -142.894558)
		(end 27.305 -143.0274)
		(width 0.2794)
		(layer "F.Cu")
		(net "SMB_FAN1_SCL")
	)
	(segment
		(start 36.667948 -205.895956)
		(end 36.93795 -205.895956)
		(width 0.2794)
		(layer "F.Cu")
		(net "SMB_FAN1_SCL")
	)
	(via
		(at 35.160712 -204.953362)
		(size 0.508)
		(drill 0.254)
		(layers "F.Cu" "B.Cu")
		(net "SMB_FAN1_SCL")
	)
	(via
		(at 27.172158 -142.727426)
		(size 0.508)
		(drill 0.254)
		(layers "F.Cu" "B.Cu")
		(net "SMB_FAN1_SCL")
	)
	(segment
		(start 32.528002 -170.642026)
		(end 33.06572 -170.642026)
		(width 0.2286)
		(layer "In2.Cu")
		(net "SMB_FAN1_SCL")
	)
	(segment
		(start 27.305 -149.319488)
		(end 27.305 -142.860268)
		(width 0.2286)
		(layer "In2.Cu")
		(net "SMB_FAN1_SCL")
	)
	(segment
		(start 32.319722 -171.144946)
		(end 32.319722 -170.850306)
		(width 0.2286)
		(layer "In2.Cu")
		(net "SMB_FAN1_SCL")
	)
	(segment
		(start 27.949144 -185.100976)
		(end 30.9626 -182.08752)
		(width 0.2286)
		(layer "In2.Cu")
		(net "SMB_FAN1_SCL")
	)
	(segment
		(start 32.656526 -169.722546)
		(end 32.656526 -162.533838)
		(width 0.2286)
		(layer "In2.Cu")
		(net "SMB_FAN1_SCL")
	)
	(segment
		(start 35.160712 -204.953362)
		(end 35.237166 -205.029816)
		(width 0.2286)
		(layer "In2.Cu")
		(net "SMB_FAN1_SCL")
	)
	(segment
		(start 34.625534 -207.648556)
		(end 33.658556 -207.648556)
		(width 0.2286)
		(layer "In2.Cu")
		(net "SMB_FAN1_SCL")
	)
	(segment
		(start 33.06572 -169.930826)
		(end 32.864806 -169.930826)
		(width 0.2286)
		(layer "In2.Cu")
		(net "SMB_FAN1_SCL")
	)
	(segment
		(start 35.237166 -205.029816)
		(end 35.237166 -207.036924)
		(width 0.2286)
		(layer "In2.Cu")
		(net "SMB_FAN1_SCL")
	)
	(segment
		(start 31.45536 -176.31664)
		(end 31.45536 -174.45482)
		(width 0.2286)
		(layer "In2.Cu")
		(net "SMB_FAN1_SCL")
	)
	(segment
		(start 32.864806 -169.930826)
		(end 32.656526 -169.722546)
		(width 0.2286)
		(layer "In2.Cu")
		(net "SMB_FAN1_SCL")
	)
	(segment
		(start 33.274 -171.856146)
		(end 33.274 -171.561506)
		(width 0.2286)
		(layer "In2.Cu")
		(net "SMB_FAN1_SCL")
	)
	(segment
		(start 33.06572 -170.642026)
		(end 33.274 -170.433746)
		(width 0.2286)
		(layer "In2.Cu")
		(net "SMB_FAN1_SCL")
	)
	(segment
		(start 30.9626 -176.8094)
		(end 31.45536 -176.31664)
		(width 0.2286)
		(layer "In2.Cu")
		(net "SMB_FAN1_SCL")
	)
	(segment
		(start 33.658556 -207.648556)
		(end 27.949144 -201.939144)
		(width 0.2286)
		(layer "In2.Cu")
		(net "SMB_FAN1_SCL")
	)
	(segment
		(start 32.528002 -172.064426)
		(end 33.06572 -172.064426)
		(width 0.2286)
		(layer "In2.Cu")
		(net "SMB_FAN1_SCL")
	)
	(segment
		(start 32.319722 -170.850306)
		(end 32.528002 -170.642026)
		(width 0.2286)
		(layer "In2.Cu")
		(net "SMB_FAN1_SCL")
	)
	(segment
		(start 33.06572 -171.353226)
		(end 32.528002 -171.353226)
		(width 0.2286)
		(layer "In2.Cu")
		(net "SMB_FAN1_SCL")
	)
	(segment
		(start 33.274 -171.561506)
		(end 33.06572 -171.353226)
		(width 0.2286)
		(layer "In2.Cu")
		(net "SMB_FAN1_SCL")
	)
	(segment
		(start 35.237166 -207.036924)
		(end 34.625534 -207.648556)
		(width 0.2286)
		(layer "In2.Cu")
		(net "SMB_FAN1_SCL")
	)
	(segment
		(start 32.656526 -162.533838)
		(end 27.305 -149.319488)
		(width 0.2286)
		(layer "In2.Cu")
		(net "SMB_FAN1_SCL")
	)
	(segment
		(start 27.949144 -201.939144)
		(end 27.949144 -185.100976)
		(width 0.2286)
		(layer "In2.Cu")
		(net "SMB_FAN1_SCL")
	)
	(segment
		(start 32.319722 -173.590458)
		(end 32.319722 -172.272706)
		(width 0.2286)
		(layer "In2.Cu")
		(net "SMB_FAN1_SCL")
	)
	(segment
		(start 32.528002 -171.353226)
		(end 32.319722 -171.144946)
		(width 0.2286)
		(layer "In2.Cu")
		(net "SMB_FAN1_SCL")
	)
	(segment
		(start 32.319722 -172.272706)
		(end 32.528002 -172.064426)
		(width 0.2286)
		(layer "In2.Cu")
		(net "SMB_FAN1_SCL")
	)
	(segment
		(start 27.305 -142.860268)
		(end 27.172158 -142.727426)
		(width 0.2286)
		(layer "In2.Cu")
		(net "SMB_FAN1_SCL")
	)
	(segment
		(start 30.9626 -182.08752)
		(end 30.9626 -176.8094)
		(width 0.2286)
		(layer "In2.Cu")
		(net "SMB_FAN1_SCL")
	)
	(segment
		(start 33.274 -170.139106)
		(end 33.06572 -169.930826)
		(width 0.2286)
		(layer "In2.Cu")
		(net "SMB_FAN1_SCL")
	)
	(segment
		(start 33.274 -170.433746)
		(end 33.274 -170.139106)
		(width 0.2286)
		(layer "In2.Cu")
		(net "SMB_FAN1_SCL")
	)
	(segment
		(start 33.06572 -172.064426)
		(end 33.274 -171.856146)
		(width 0.2286)
		(layer "In2.Cu")
		(net "SMB_FAN1_SCL")
	)
	(segment
		(start 31.45536 -174.45482)
		(end 32.319722 -173.590458)
		(width 0.2286)
		(layer "In2.Cu")
		(net "SMB_FAN1_SCL")
	)
	(segment
		(start 31.623 -160.05175)
		(end 31.496 -159.92475)
		(width 0.2794)
		(layer "F.Cu")
		(net "SMB_FAN5_R_SDA")
	)
	(segment
		(start 27.040078 -154.94)
		(end 27.040078 -156.325824)
		(width 0.2794)
		(layer "F.Cu")
		(net "SMB_FAN5_R_SDA")
	)
	(segment
		(start 30.734 -162.54095)
		(end 31.623 -161.65195)
		(width 0.2794)
		(layer "F.Cu")
		(net "SMB_FAN5_R_SDA")
	)
	(segment
		(start 31.623 -161.65195)
		(end 31.623 -160.05175)
		(width 0.2794)
		(layer "F.Cu")
		(net "SMB_FAN5_R_SDA")
	)
	(segment
		(start 30.734 -159.09925)
		(end 29.62275 -157.988)
		(width 0.2794)
		(layer "F.Cu")
		(net "SMB_FAN5_R_SDA")
	)
	(segment
		(start 28.702254 -157.988)
		(end 29.337 -157.988)
		(width 0.2794)
		(layer "F.Cu")
		(net "SMB_FAN5_R_SDA")
	)
	(segment
		(start 31.2166 -159.61995)
		(end 30.734 -159.61995)
		(width 0.2794)
		(layer "F.Cu")
		(net "SMB_FAN5_R_SDA")
	)
	(segment
		(start 29.62275 -157.988)
		(end 29.337 -157.988)
		(width 0.2794)
		(layer "F.Cu")
		(net "SMB_FAN5_R_SDA")
	)
	(segment
		(start 27.040078 -156.325824)
		(end 28.702254 -157.988)
		(width 0.2794)
		(layer "F.Cu")
		(net "SMB_FAN5_R_SDA")
	)
	(segment
		(start 31.496 -159.89935)
		(end 31.2166 -159.61995)
		(width 0.2794)
		(layer "F.Cu")
		(net "SMB_FAN5_R_SDA")
	)
	(segment
		(start 30.734 -159.61995)
		(end 30.734 -159.09925)
		(width 0.2794)
		(layer "F.Cu")
		(net "SMB_FAN5_R_SDA")
	)
	(segment
		(start 31.496 -159.92475)
		(end 31.496 -159.89935)
		(width 0.2794)
		(layer "F.Cu")
		(net "SMB_FAN5_R_SDA")
	)
	(via
		(at 29.337 -157.988)
		(size 0.762)
		(drill 0.381)
		(layers "F.Cu" "B.Cu")
		(net "SMB_FAN5_R_SDA")
	)
	(via
		(at 8.074914 -247.777)
		(size 0.6604)
		(drill 0.3302)
		(layers "F.Cu" "B.Cu")
		(net "FAN_6_P5V")
	)
	(segment
		(start 8.763 -249.02795)
		(end 8.763 -248.465086)
		(width 0.2794)
		(layer "B.Cu")
		(net "FAN_6_P5V")
	)
	(segment
		(start 7.300214 -246.32793)
		(end 7.300214 -245.945152)
		(width 0.1016)
		(layer "B.Cu")
		(net "FAN_6_P5V")
	)
	(segment
		(start 8.074914 -247.777)
		(end 7.300214 -246.32793)
		(width 0.1016)
		(layer "B.Cu")
		(net "FAN_6_P5V")
	)
	(segment
		(start 8.763 -248.465086)
		(end 8.074914 -247.777)
		(width 0.2794)
		(layer "B.Cu")
		(net "FAN_6_P5V")
	)
	(segment
		(start 24.384 -147.3073)
		(end 24.43988 -147.36318)
		(width 0.2794)
		(layer "F.Cu")
		(net "SMB_FAN1_R_SDA")
	)
	(segment
		(start 25.654 -144.492726)
		(end 24.9682 -145.178526)
		(width 0.2794)
		(layer "F.Cu")
		(net "SMB_FAN1_R_SDA")
	)
	(segment
		(start 25.88895 -144.29105)
		(end 25.654 -144.29105)
		(width 0.2794)
		(layer "F.Cu")
		(net "SMB_FAN1_R_SDA")
	)
	(segment
		(start 25.52827 -142.13078)
		(end 25.52827 -142.727426)
		(width 0.2794)
		(layer "F.Cu")
		(net "SMB_FAN1_R_SDA")
	)
	(segment
		(start 25.52827 -142.727426)
		(end 25.920954 -142.727426)
		(width 0.2794)
		(layer "F.Cu")
		(net "SMB_FAN1_R_SDA")
	)
	(segment
		(start 26.289 -143.095472)
		(end 26.289 -143.891)
		(width 0.2794)
		(layer "F.Cu")
		(net "SMB_FAN1_R_SDA")
	)
	(segment
		(start 25.920954 -142.727426)
		(end 26.289 -143.095472)
		(width 0.2794)
		(layer "F.Cu")
		(net "SMB_FAN1_R_SDA")
	)
	(segment
		(start 24.9682 -145.178526)
		(end 24.384 -146.58848)
		(width 0.2794)
		(layer "F.Cu")
		(net "SMB_FAN1_R_SDA")
	)
	(segment
		(start 25.654 -142.00505)
		(end 25.52827 -142.13078)
		(width 0.2794)
		(layer "F.Cu")
		(net "SMB_FAN1_R_SDA")
	)
	(segment
		(start 24.384 -146.58848)
		(end 24.384 -147.3073)
		(width 0.2794)
		(layer "F.Cu")
		(net "SMB_FAN1_R_SDA")
	)
	(segment
		(start 25.654 -144.29105)
		(end 25.654 -144.492726)
		(width 0.2794)
		(layer "F.Cu")
		(net "SMB_FAN1_R_SDA")
	)
	(segment
		(start 26.289 -143.891)
		(end 25.88895 -144.29105)
		(width 0.2794)
		(layer "F.Cu")
		(net "SMB_FAN1_R_SDA")
	)
	(segment
		(start 24.43988 -147.36318)
		(end 24.43988 -149.098)
		(width 0.2794)
		(layer "F.Cu")
		(net "SMB_FAN1_R_SDA")
	)
	(via
		(at 25.52827 -142.727426)
		(size 0.508)
		(drill 0.254)
		(layers "F.Cu" "B.Cu")
		(net "SMB_FAN1_R_SDA")
	)
	(via
		(at 5.74802 -247.831356)
		(size 0.6604)
		(drill 0.3302)
		(layers "F.Cu" "B.Cu")
		(net "FAN_6_CLREF")
	)
	(segment
		(start 5.74802 -247.12803)
		(end 5.700268 -246.963438)
		(width 0.1016)
		(layer "B.Cu")
		(net "FAN_6_CLREF")
	)
	(segment
		(start 5.74802 -247.831356)
		(end 5.74802 -248.476516)
		(width 0.1016)
		(layer "B.Cu")
		(net "FAN_6_CLREF")
	)
	(segment
		(start 5.700268 -246.963438)
		(end 5.700268 -245.945152)
		(width 0.1016)
		(layer "B.Cu")
		(net "FAN_6_CLREF")
	)
	(segment
		(start 5.74802 -248.476516)
		(end 5.82295 -248.551446)
		(width 0.2794)
		(layer "B.Cu")
		(net "FAN_6_CLREF")
	)
	(segment
		(start 5.74802 -247.831356)
		(end 5.74802 -247.12803)
		(width 0.1016)
		(layer "B.Cu")
		(net "FAN_6_CLREF")
	)
	(segment
		(start 5.82295 -248.551446)
		(end 5.82295 -249.047)
		(width 0.2794)
		(layer "B.Cu")
		(net "FAN_6_CLREF")
	)
	(segment
		(start 5.82295 -249.047)
		(end 5.82295 -250.063)
		(width 0.2794)
		(layer "B.Cu")
		(net "FAN_6_CLREF")
	)
	(segment
		(start 34.417 -143.49095)
		(end 34.417 -142.875)
		(width 0.2794)
		(layer "F.Cu")
		(net "SMB_FAN3_SCL")
	)
	(segment
		(start 36.93795 -26.248868)
		(end 36.195 -26.248868)
		(width 0.2794)
		(layer "F.Cu")
		(net "SMB_FAN3_SCL")
	)
	(via
		(at 36.195 -26.248868)
		(size 0.508)
		(drill 0.254)
		(layers "F.Cu" "B.Cu")
		(net "SMB_FAN3_SCL")
	)
	(via
		(at 34.417 -142.875)
		(size 0.508)
		(drill 0.254)
		(layers "F.Cu" "B.Cu")
		(net "SMB_FAN3_SCL")
	)
	(segment
		(start 34.925 -105.028746)
		(end 34.925 -100.843842)
		(width 0.2286)
		(layer "In2.Cu")
		(net "SMB_FAN3_SCL")
	)
	(segment
		(start 29.9466 -95.865442)
		(end 29.9466 -82.000598)
		(width 0.2286)
		(layer "In2.Cu")
		(net "SMB_FAN3_SCL")
	)
	(segment
		(start 36.83 -26.750518)
		(end 36.32835 -26.248868)
		(width 0.2286)
		(layer "In2.Cu")
		(net "SMB_FAN3_SCL")
	)
	(segment
		(start 34.8488 -35.69335)
		(end 36.83 -33.71215)
		(width 0.2286)
		(layer "In2.Cu")
		(net "SMB_FAN3_SCL")
	)
	(segment
		(start 29.6164 -64.006222)
		(end 34.8488 -51.370992)
		(width 0.2286)
		(layer "In2.Cu")
		(net "SMB_FAN3_SCL")
	)
	(segment
		(start 38.006274 -131.24434)
		(end 39.41064 -131.24434)
		(width 0.2286)
		(layer "In2.Cu")
		(net "SMB_FAN3_SCL")
	)
	(segment
		(start 34.945828 -110.617254)
		(end 33.171384 -110.617254)
		(width 0.2286)
		(layer "In2.Cu")
		(net "SMB_FAN3_SCL")
	)
	(segment
		(start 36.32835 -26.248868)
		(end 36.195 -26.248868)
		(width 0.2286)
		(layer "In2.Cu")
		(net "SMB_FAN3_SCL")
	)
	(segment
		(start 32.6263 -110.07217)
		(end 32.6263 -107.327446)
		(width 0.2286)
		(layer "In2.Cu")
		(net "SMB_FAN3_SCL")
	)
	(segment
		(start 37.424614 -139.867386)
		(end 37.424614 -131.826)
		(width 0.2286)
		(layer "In2.Cu")
		(net "SMB_FAN3_SCL")
	)
	(segment
		(start 29.9466 -82.000598)
		(end 29.6164 -81.670398)
		(width 0.2286)
		(layer "In2.Cu")
		(net "SMB_FAN3_SCL")
	)
	(segment
		(start 36.83 -33.71215)
		(end 36.83 -26.750518)
		(width 0.2286)
		(layer "In2.Cu")
		(net "SMB_FAN3_SCL")
	)
	(segment
		(start 29.6164 -81.670398)
		(end 29.6164 -64.006222)
		(width 0.2286)
		(layer "In2.Cu")
		(net "SMB_FAN3_SCL")
	)
	(segment
		(start 34.417 -142.875)
		(end 37.424614 -139.867386)
		(width 0.2286)
		(layer "In2.Cu")
		(net "SMB_FAN3_SCL")
	)
	(segment
		(start 32.6263 -107.327446)
		(end 34.925 -105.028746)
		(width 0.2286)
		(layer "In2.Cu")
		(net "SMB_FAN3_SCL")
	)
	(segment
		(start 41.12387 -116.795296)
		(end 34.945828 -110.617254)
		(width 0.2286)
		(layer "In2.Cu")
		(net "SMB_FAN3_SCL")
	)
	(segment
		(start 34.8488 -51.370992)
		(end 34.8488 -35.69335)
		(width 0.2286)
		(layer "In2.Cu")
		(net "SMB_FAN3_SCL")
	)
	(segment
		(start 39.41064 -131.24434)
		(end 41.12387 -129.53111)
		(width 0.2286)
		(layer "In2.Cu")
		(net "SMB_FAN3_SCL")
	)
	(segment
		(start 41.12387 -129.53111)
		(end 41.12387 -116.795296)
		(width 0.2286)
		(layer "In2.Cu")
		(net "SMB_FAN3_SCL")
	)
	(segment
		(start 37.424614 -131.826)
		(end 38.006274 -131.24434)
		(width 0.2286)
		(layer "In2.Cu")
		(net "SMB_FAN3_SCL")
	)
	(segment
		(start 33.171384 -110.617254)
		(end 32.6263 -110.07217)
		(width 0.2286)
		(layer "In2.Cu")
		(net "SMB_FAN3_SCL")
	)
	(segment
		(start 34.925 -100.843842)
		(end 29.9466 -95.865442)
		(width 0.2286)
		(layer "In2.Cu")
		(net "SMB_FAN3_SCL")
	)
	(segment
		(start 7.366 -248.190512)
		(end 7.366 -249.936)
		(width 0.2794)
		(layer "F.Cu")
		(net "FAN_6_P3V_R")
	)
	(segment
		(start 7.312914 -248.137426)
		(end 7.366 -248.190512)
		(width 0.2794)
		(layer "F.Cu")
		(net "FAN_6_P3V_R")
	)
	(segment
		(start 6.985 -250.317)
		(end 6.36905 -250.317)
		(width 0.2794)
		(layer "F.Cu")
		(net "FAN_6_P3V_R")
	)
	(segment
		(start 7.366 -249.936)
		(end 6.985 -250.317)
		(width 0.2794)
		(layer "F.Cu")
		(net "FAN_6_P3V_R")
	)
	(segment
		(start 6.462014 -246.922036)
		(end 7.083044 -246.922036)
		(width 0.2794)
		(layer "F.Cu")
		(net "FAN_6_P3V_R")
	)
	(segment
		(start 5.86105 -247.523)
		(end 6.462014 -246.922036)
		(width 0.2794)
		(layer "F.Cu")
		(net "FAN_6_P3V_R")
	)
	(via
		(at 7.312914 -248.137426)
		(size 0.508)
		(drill 0.254)
		(layers "F.Cu" "B.Cu")
		(net "FAN_6_P3V_R")
	)
	(via
		(at 7.083044 -246.922036)
		(size 0.762)
		(drill 0.254)
		(layers "F.Cu" "B.Cu")
		(net "FAN_6_P3V_R")
	)
	(segment
		(start 6.900164 -245.945152)
		(end 6.900164 -246.480584)
		(width 0.1016)
		(layer "B.Cu")
		(net "FAN_6_P3V_R")
	)
	(segment
		(start 7.747 -249.02795)
		(end 7.747 -248.571512)
		(width 0.2794)
		(layer "B.Cu")
		(net "FAN_6_P3V_R")
	)
	(segment
		(start 6.900164 -246.480584)
		(end 7.083044 -246.922036)
		(width 0.1016)
		(layer "B.Cu")
		(net "FAN_6_P3V_R")
	)
	(segment
		(start 7.312914 -248.137426)
		(end 7.312914 -247.477788)
		(width 0.1016)
		(layer "B.Cu")
		(net "FAN_6_P3V_R")
	)
	(segment
		(start 7.747 -248.571512)
		(end 7.312914 -248.137426)
		(width 0.2794)
		(layer "B.Cu")
		(net "FAN_6_P3V_R")
	)
	(segment
		(start 7.312914 -247.477788)
		(end 7.083044 -246.922036)
		(width 0.1016)
		(layer "B.Cu")
		(net "FAN_6_P3V_R")
	)
	(segment
		(start 23.264622 -111.506)
		(end 23.645622 -111.125)
		(width 0.2794)
		(layer "F.Cu")
		(net "SMB_FAN2_SCL")
	)
	(segment
		(start 31.75 -142.875)
		(end 31.75 -143.36395)
		(width 0.2794)
		(layer "F.Cu")
		(net "SMB_FAN2_SCL")
	)
	(segment
		(start 28.504388 -111.125)
		(end 29.736288 -112.3569)
		(width 0.2794)
		(layer "F.Cu")
		(net "SMB_FAN2_SCL")
	)
	(segment
		(start 35.3949 -112.3569)
		(end 36.633912 -113.595912)
		(width 0.2794)
		(layer "F.Cu")
		(net "SMB_FAN2_SCL")
	)
	(segment
		(start 29.736288 -112.3569)
		(end 35.3949 -112.3569)
		(width 0.2794)
		(layer "F.Cu")
		(net "SMB_FAN2_SCL")
	)
	(segment
		(start 31.75 -143.36395)
		(end 31.623 -143.49095)
		(width 0.2794)
		(layer "F.Cu")
		(net "SMB_FAN2_SCL")
	)
	(segment
		(start 36.633912 -113.595912)
		(end 36.93795 -113.595912)
		(width 0.2794)
		(layer "F.Cu")
		(net "SMB_FAN2_SCL")
	)
	(segment
		(start 23.645622 -111.125)
		(end 28.504388 -111.125)
		(width 0.2794)
		(layer "F.Cu")
		(net "SMB_FAN2_SCL")
	)
	(via
		(at 23.264622 -111.506)
		(size 0.508)
		(drill 0.254)
		(layers "F.Cu" "B.Cu")
		(net "SMB_FAN2_SCL")
	)
	(via
		(at 31.75 -142.875)
		(size 0.508)
		(drill 0.254)
		(layers "F.Cu" "B.Cu")
		(net "SMB_FAN2_SCL")
	)
	(segment
		(start 23.801578 -114.687858)
		(end 30.988 -121.87428)
		(width 0.2286)
		(layer "In2.Cu")
		(net "SMB_FAN2_SCL")
	)
	(segment
		(start 33.248854 -139.16787)
		(end 31.75 -140.666724)
		(width 0.2286)
		(layer "In2.Cu")
		(net "SMB_FAN2_SCL")
	)
	(segment
		(start 33.248854 -125.705108)
		(end 33.248854 -139.16787)
		(width 0.2286)
		(layer "In2.Cu")
		(net "SMB_FAN2_SCL")
	)
	(segment
		(start 30.988 -123.444254)
		(end 33.248854 -125.705108)
		(width 0.2286)
		(layer "In2.Cu")
		(net "SMB_FAN2_SCL")
	)
	(segment
		(start 30.988 -121.87428)
		(end 30.988 -123.444254)
		(width 0.2286)
		(layer "In2.Cu")
		(net "SMB_FAN2_SCL")
	)
	(segment
		(start 31.75 -140.666724)
		(end 31.75 -142.875)
		(width 0.2286)
		(layer "In2.Cu")
		(net "SMB_FAN2_SCL")
	)
	(segment
		(start 23.264622 -112.568228)
		(end 23.801578 -113.105184)
		(width 0.2286)
		(layer "In2.Cu")
		(net "SMB_FAN2_SCL")
	)
	(segment
		(start 23.264622 -111.506)
		(end 23.264622 -112.568228)
		(width 0.2286)
		(layer "In2.Cu")
		(net "SMB_FAN2_SCL")
	)
	(segment
		(start 23.801578 -113.105184)
		(end 23.801578 -114.687858)
		(width 0.2286)
		(layer "In2.Cu")
		(net "SMB_FAN2_SCL")
	)
	(via
		(at 9.779 -248.208546)
		(size 0.762)
		(drill 0.254)
		(layers "F.Cu" "B.Cu")
		(net "FAN_6_TEMP")
	)
	(segment
		(start 8.328914 -247.142)
		(end 8.856218 -247.669304)
		(width 0.2794)
		(layer "B.Cu")
		(net "FAN_6_TEMP")
	)
	(segment
		(start 8.856218 -247.669304)
		(end 9.504934 -247.798336)
		(width 0.2794)
		(layer "B.Cu")
		(net "FAN_6_TEMP")
	)
	(segment
		(start 7.700264 -245.945152)
		(end 7.700264 -246.357648)
		(width 0.1016)
		(layer "B.Cu")
		(net "FAN_6_TEMP")
	)
	(segment
		(start 7.700264 -246.357648)
		(end 7.810246 -246.623332)
		(width 0.1016)
		(layer "B.Cu")
		(net "FAN_6_TEMP")
	)
	(segment
		(start 9.504934 -247.798336)
		(end 9.779 -248.208546)
		(width 0.2794)
		(layer "B.Cu")
		(net "FAN_6_TEMP")
	)
	(segment
		(start 10.795 -249.02795)
		(end 9.779 -249.02795)
		(width 0.2794)
		(layer "B.Cu")
		(net "FAN_6_TEMP")
	)
	(segment
		(start 9.779 -248.208546)
		(end 9.779 -249.02795)
		(width 0.2794)
		(layer "B.Cu")
		(net "FAN_6_TEMP")
	)
	(segment
		(start 7.810246 -246.623332)
		(end 8.328914 -247.142)
		(width 0.1016)
		(layer "B.Cu")
		(net "FAN_6_TEMP")
	)
	(segment
		(start 28.687014 -287.532064)
		(end 28.687014 -288.61004)
		(width 0.2794)
		(layer "F.Cu")
		(net "FAN_7_PWM_BUF")
	)
	(segment
		(start 28.63596 -288.61004)
		(end 28.687014 -288.61004)
		(width 0.2794)
		(layer "F.Cu")
		(net "FAN_7_PWM_BUF")
	)
	(segment
		(start 26.73096 -289.433)
		(end 27.813 -289.433)
		(width 0.2794)
		(layer "F.Cu")
		(net "FAN_7_PWM_BUF")
	)
	(segment
		(start 27.813 -289.433)
		(end 28.63596 -288.61004)
		(width 0.2794)
		(layer "F.Cu")
		(net "FAN_7_PWM_BUF")
	)
	(segment
		(start 28.575 -287.42005)
		(end 28.687014 -287.532064)
		(width 0.2794)
		(layer "F.Cu")
		(net "FAN_7_PWM_BUF")
	)
	(via
		(at 27.813 -289.433)
		(size 0.508)
		(drill 0.254)
		(layers "F.Cu" "B.Cu")
		(net "FAN_7_PWM_BUF")
	)
	(segment
		(start 36.449 -294.767)
		(end 36.93795 -294.767)
		(width 0.2794)
		(layer "F.Cu")
		(net "SMB_FAN0_SDA")
	)
	(segment
		(start 21.59 -143.49095)
		(end 21.59 -142.785592)
		(width 0.2794)
		(layer "F.Cu")
		(net "SMB_FAN0_SDA")
	)
	(segment
		(start 36.195 -295.021)
		(end 36.449 -294.767)
		(width 0.2794)
		(layer "F.Cu")
		(net "SMB_FAN0_SDA")
	)
	(via
		(at 21.59 -142.785592)
		(size 0.508)
		(drill 0.254)
		(layers "F.Cu" "B.Cu")
		(net "SMB_FAN0_SDA")
	)
	(via
		(at 36.195 -295.021)
		(size 0.508)
		(drill 0.254)
		(layers "F.Cu" "B.Cu")
		(net "SMB_FAN0_SDA")
	)
	(segment
		(start 31.369 -214.63)
		(end 31.369 -240.895886)
		(width 0.2286)
		(layer "In2.Cu")
		(net "SMB_FAN0_SDA")
	)
	(segment
		(start 23.0505 -161.226754)
		(end 23.0632 -161.239454)
		(width 0.2286)
		(layer "In2.Cu")
		(net "SMB_FAN0_SDA")
	)
	(segment
		(start 36.957 -290.132516)
		(end 36.957 -294.259)
		(width 0.2286)
		(layer "In2.Cu")
		(net "SMB_FAN0_SDA")
	)
	(segment
		(start 23.83282 -201.032872)
		(end 27.329638 -204.52969)
		(width 0.2286)
		(layer "In2.Cu")
		(net "SMB_FAN0_SDA")
	)
	(segment
		(start 21.59 -148.643594)
		(end 23.0505 -152.169622)
		(width 0.2286)
		(layer "In2.Cu")
		(net "SMB_FAN0_SDA")
	)
	(segment
		(start 30.024832 -214.047832)
		(end 30.786832 -214.047832)
		(width 0.2286)
		(layer "In2.Cu")
		(net "SMB_FAN0_SDA")
	)
	(segment
		(start 23.0632 -161.320226)
		(end 26.415492 -164.672518)
		(width 0.2286)
		(layer "In2.Cu")
		(net "SMB_FAN0_SDA")
	)
	(segment
		(start 24.384 -183.61914)
		(end 24.384 -195.011802)
		(width 0.2286)
		(layer "In2.Cu")
		(net "SMB_FAN0_SDA")
	)
	(segment
		(start 26.41854 -171.293028)
		(end 26.41854 -171.860972)
		(width 0.2286)
		(layer "In2.Cu")
		(net "SMB_FAN0_SDA")
	)
	(segment
		(start 23.0632 -161.239454)
		(end 23.0632 -161.320226)
		(width 0.2286)
		(layer "In2.Cu")
		(net "SMB_FAN0_SDA")
	)
	(segment
		(start 36.957 -294.259)
		(end 36.195 -295.021)
		(width 0.2286)
		(layer "In2.Cu")
		(net "SMB_FAN0_SDA")
	)
	(segment
		(start 23.83282 -195.562982)
		(end 23.83282 -201.032872)
		(width 0.2286)
		(layer "In2.Cu")
		(net "SMB_FAN0_SDA")
	)
	(segment
		(start 31.369 -240.895886)
		(end 28.74772 -247.22328)
		(width 0.2286)
		(layer "In2.Cu")
		(net "SMB_FAN0_SDA")
	)
	(segment
		(start 26.415492 -164.672518)
		(end 26.415492 -171.28998)
		(width 0.2286)
		(layer "In2.Cu")
		(net "SMB_FAN0_SDA")
	)
	(segment
		(start 28.74772 -247.22328)
		(end 27.813 -248.158)
		(width 0.2286)
		(layer "In2.Cu")
		(net "SMB_FAN0_SDA")
	)
	(segment
		(start 27.813 -248.158)
		(end 27.813 -280.988516)
		(width 0.2286)
		(layer "In2.Cu")
		(net "SMB_FAN0_SDA")
	)
	(segment
		(start 27.813 -280.988516)
		(end 36.957 -290.132516)
		(width 0.2286)
		(layer "In2.Cu")
		(net "SMB_FAN0_SDA")
	)
	(segment
		(start 27.329638 -211.352638)
		(end 30.024832 -214.047832)
		(width 0.2286)
		(layer "In2.Cu")
		(net "SMB_FAN0_SDA")
	)
	(segment
		(start 23.0505 -152.169622)
		(end 23.0505 -161.226754)
		(width 0.2286)
		(layer "In2.Cu")
		(net "SMB_FAN0_SDA")
	)
	(segment
		(start 21.59 -142.785592)
		(end 21.59 -148.643594)
		(width 0.2286)
		(layer "In2.Cu")
		(net "SMB_FAN0_SDA")
	)
	(segment
		(start 24.384 -195.011802)
		(end 23.83282 -195.562982)
		(width 0.2286)
		(layer "In2.Cu")
		(net "SMB_FAN0_SDA")
	)
	(segment
		(start 26.415492 -171.86402)
		(end 26.415492 -181.587648)
		(width 0.2286)
		(layer "In2.Cu")
		(net "SMB_FAN0_SDA")
	)
	(segment
		(start 27.329638 -204.52969)
		(end 27.329638 -211.352638)
		(width 0.2286)
		(layer "In2.Cu")
		(net "SMB_FAN0_SDA")
	)
	(segment
		(start 30.786832 -214.047832)
		(end 31.369 -214.63)
		(width 0.2286)
		(layer "In2.Cu")
		(net "SMB_FAN0_SDA")
	)
	(segment
		(start 26.415492 -181.587648)
		(end 24.384 -183.61914)
		(width 0.2286)
		(layer "In2.Cu")
		(net "SMB_FAN0_SDA")
	)
	(segment
		(start 26.415492 -171.28998)
		(end 26.41854 -171.293028)
		(width 0.2286)
		(layer "In2.Cu")
		(net "SMB_FAN0_SDA")
	)
	(segment
		(start 26.41854 -171.860972)
		(end 26.415492 -171.86402)
		(width 0.2286)
		(layer "In2.Cu")
		(net "SMB_FAN0_SDA")
	)
	(segment
		(start 23.789894 -154.94)
		(end 23.789894 -156.809694)
		(width 0.2794)
		(layer "F.Cu")
		(net "SMB_FAN7_R_SCL")
	)
	(segment
		(start 21.794216 -159.61995)
		(end 22.098 -159.61995)
		(width 0.2794)
		(layer "F.Cu")
		(net "SMB_FAN7_R_SCL")
	)
	(segment
		(start 23.789894 -156.809694)
		(end 22.346158 -158.25343)
		(width 0.2794)
		(layer "F.Cu")
		(net "SMB_FAN7_R_SCL")
	)
	(segment
		(start 22.346158 -158.25343)
		(end 22.098 -158.501588)
		(width 0.2794)
		(layer "F.Cu")
		(net "SMB_FAN7_R_SCL")
	)
	(segment
		(start 21.5138 -162.54095)
		(end 21.5138 -159.900366)
		(width 0.2794)
		(layer "F.Cu")
		(net "SMB_FAN7_R_SCL")
	)
	(segment
		(start 22.098 -158.501588)
		(end 22.098 -159.61995)
		(width 0.2794)
		(layer "F.Cu")
		(net "SMB_FAN7_R_SCL")
	)
	(segment
		(start 21.5138 -159.900366)
		(end 21.794216 -159.61995)
		(width 0.2794)
		(layer "F.Cu")
		(net "SMB_FAN7_R_SCL")
	)
	(via
		(at 22.346158 -158.25343)
		(size 0.762)
		(drill 0.381)
		(layers "F.Cu" "B.Cu")
		(net "SMB_FAN7_R_SCL")
	)
	(via
		(at 2.199386 -247.601232)
		(size 0.6604)
		(drill 0.3302)
		(layers "F.Cu" "B.Cu")
		(net "FAN_6_IMON")
	)
	(segment
		(start 2.199386 -248.095008)
		(end 2.199386 -247.601232)
		(width 0.2794)
		(layer "B.Cu")
		(net "FAN_6_IMON")
	)
	(segment
		(start 2.667 -249.02795)
		(end 2.667 -248.562622)
		(width 0.2794)
		(layer "B.Cu")
		(net "FAN_6_IMON")
	)
	(segment
		(start 3.034538 -246.76608)
		(end 3.736086 -246.76608)
		(width 0.2794)
		(layer "B.Cu")
		(net "FAN_6_IMON")
	)
	(segment
		(start 2.667 -248.562622)
		(end 2.199386 -248.095008)
		(width 0.2794)
		(layer "B.Cu")
		(net "FAN_6_IMON")
	)
	(segment
		(start 2.199386 -247.601232)
		(end 3.034538 -246.76608)
		(width 0.2794)
		(layer "B.Cu")
		(net "FAN_6_IMON")
	)
	(segment
		(start 3.736086 -246.76608)
		(end 4.100068 -246.402098)
		(width 0.1016)
		(layer "B.Cu")
		(net "FAN_6_IMON")
	)
	(segment
		(start 4.100068 -246.402098)
		(end 4.100068 -245.945152)
		(width 0.1016)
		(layer "B.Cu")
		(net "FAN_6_IMON")
	)
	(segment
		(start 27.967686 -196.40804)
		(end 28.433014 -196.40804)
		(width 0.2794)
		(layer "F.Cu")
		(net "FAN_6_PWM_BUF")
	)
	(segment
		(start 28.433014 -195.330064)
		(end 28.433014 -196.40804)
		(width 0.2794)
		(layer "F.Cu")
		(net "FAN_6_PWM_BUF")
	)
	(segment
		(start 26.22296 -197.104)
		(end 27.269694 -197.104)
		(width 0.2794)
		(layer "F.Cu")
		(net "FAN_6_PWM_BUF")
	)
	(segment
		(start 27.27071 -197.105016)
		(end 27.967686 -196.40804)
		(width 0.2794)
		(layer "F.Cu")
		(net "FAN_6_PWM_BUF")
	)
	(segment
		(start 27.269694 -197.104)
		(end 27.27071 -197.105016)
		(width 0.2794)
		(layer "F.Cu")
		(net "FAN_6_PWM_BUF")
	)
	(segment
		(start 28.321 -195.21805)
		(end 28.433014 -195.330064)
		(width 0.2794)
		(layer "F.Cu")
		(net "FAN_6_PWM_BUF")
	)
	(via
		(at 27.27071 -197.105016)
		(size 0.508)
		(drill 0.254)
		(layers "F.Cu" "B.Cu")
		(net "FAN_6_PWM_BUF")
	)
	(segment
		(start 27.634692 -142.00505)
		(end 28.194 -142.564358)
		(width 0.2794)
		(layer "F.Cu")
		(net "SMB_FAN1_R_SCL")
	)
	(segment
		(start 25.273 -146.939)
		(end 25.798526 -145.670524)
		(width 0.2794)
		(layer "F.Cu")
		(net "SMB_FAN1_R_SCL")
	)
	(segment
		(start 27.305 -142.00505)
		(end 27.634692 -142.00505)
		(width 0.2794)
		(layer "F.Cu")
		(net "SMB_FAN1_R_SCL")
	)
	(segment
		(start 28.194 -142.564358)
		(end 28.194 -143.637254)
		(width 0.2794)
		(layer "F.Cu")
		(net "SMB_FAN1_R_SCL")
	)
	(segment
		(start 25.09012 -147.12188)
		(end 25.09012 -149.098)
		(width 0.2794)
		(layer "F.Cu")
		(net "SMB_FAN1_R_SCL")
	)
	(segment
		(start 25.798526 -145.670524)
		(end 27.178 -144.29105)
		(width 0.2794)
		(layer "F.Cu")
		(net "SMB_FAN1_R_SCL")
	)
	(segment
		(start 25.273 -146.939)
		(end 25.09012 -147.12188)
		(width 0.2794)
		(layer "F.Cu")
		(net "SMB_FAN1_R_SCL")
	)
	(segment
		(start 27.540204 -144.29105)
		(end 27.305 -144.29105)
		(width 0.2794)
		(layer "F.Cu")
		(net "SMB_FAN1_R_SCL")
	)
	(segment
		(start 27.178 -144.29105)
		(end 27.305 -144.29105)
		(width 0.2794)
		(layer "F.Cu")
		(net "SMB_FAN1_R_SCL")
	)
	(segment
		(start 28.194 -143.637254)
		(end 27.540204 -144.29105)
		(width 0.2794)
		(layer "F.Cu")
		(net "SMB_FAN1_R_SCL")
	)
	(via
		(at 25.273 -146.939)
		(size 0.762)
		(drill 0.381)
		(layers "F.Cu" "B.Cu")
		(net "SMB_FAN1_R_SCL")
	)
	(segment
		(start 22.489922 -155.890722)
		(end 21.510244 -156.8704)
		(width 0.2794)
		(layer "F.Cu")
		(net "SMB_PDBV_FAN_R_U321_SCL")
	)
	(segment
		(start 21.510244 -156.8704)
		(end 19.8374 -156.8704)
		(width 0.2794)
		(layer "F.Cu")
		(net "SMB_PDBV_FAN_R_U321_SCL")
	)
	(segment
		(start 18.288 -158.4198)
		(end 18.288 -159.61995)
		(width 0.2794)
		(layer "F.Cu")
		(net "SMB_PDBV_FAN_R_U321_SCL")
	)
	(segment
		(start 19.8374 -156.8704)
		(end 18.288 -158.4198)
		(width 0.2794)
		(layer "F.Cu")
		(net "SMB_PDBV_FAN_R_U321_SCL")
	)
	(segment
		(start 22.489922 -154.94)
		(end 22.489922 -155.890722)
		(width 0.2794)
		(layer "F.Cu")
		(net "SMB_PDBV_FAN_R_U321_SCL")
	)
	(via
		(at 18.288 -158.4198)
		(size 0.762)
		(drill 0.381)
		(layers "F.Cu" "B.Cu")
		(net "SMB_PDBV_FAN_R_U321_SCL")
	)
	(segment
		(start 18.30705 -172.35805)
		(end 18.30705 -172.466)
		(width 0.2794)
		(layer "F.Cu")
		(net "FAN_6_PRESENT_R_N")
	)
	(segment
		(start 17.78 -171.831)
		(end 18.30705 -172.35805)
		(width 0.2794)
		(layer "F.Cu")
		(net "FAN_6_PRESENT_R_N")
	)
	(segment
		(start 17.272 -171.831)
		(end 17.78 -171.831)
		(width 0.2794)
		(layer "F.Cu")
		(net "FAN_6_PRESENT_R_N")
	)
	(via
		(at 17.272 -171.831)
		(size 0.508)
		(drill 0.254)
		(layers "F.Cu" "B.Cu")
		(net "FAN_6_PRESENT_R_N")
	)
	(segment
		(start 15.748 -171.831)
		(end 12.573 -175.006)
		(width 0.2286)
		(layer "In2.Cu")
		(net "FAN_6_PRESENT_R_N")
	)
	(segment
		(start 10.0076 -182.935372)
		(end 10.0076 -197.702424)
		(width 0.2286)
		(layer "In2.Cu")
		(net "FAN_6_PRESENT_R_N")
	)
	(segment
		(start 17.272 -171.831)
		(end 15.748 -171.831)
		(width 0.2286)
		(layer "In2.Cu")
		(net "FAN_6_PRESENT_R_N")
	)
	(segment
		(start 12.573 -180.369972)
		(end 10.0076 -182.935372)
		(width 0.2286)
		(layer "In2.Cu")
		(net "FAN_6_PRESENT_R_N")
	)
	(segment
		(start 10.0076 -197.702424)
		(end 8.700008 -199.010016)
		(width 0.2286)
		(layer "In2.Cu")
		(net "FAN_6_PRESENT_R_N")
	)
	(segment
		(start 12.573 -175.006)
		(end 12.573 -180.369972)
		(width 0.2286)
		(layer "In2.Cu")
		(net "FAN_6_PRESENT_R_N")
	)
	(segment
		(start 42.991024 -291.31895)
		(end 42.999914 -291.31006)
		(width 0.2794)
		(layer "F.Cu")
		(net "FAN_0_OK_R_LED_N")
	)
	(segment
		(start 39.2303 -291.31895)
		(end 39.12235 -291.211)
		(width 0.2794)
		(layer "F.Cu")
		(net "FAN_0_OK_R_LED_N")
	)
	(segment
		(start 37.762942 -290.5125)
		(end 37.762942 -289.941)
		(width 0.2794)
		(layer "F.Cu")
		(net "FAN_0_OK_R_LED_N")
	)
	(segment
		(start 39.878 -291.31895)
		(end 39.2303 -291.31895)
		(width 0.2794)
		(layer "F.Cu")
		(net "FAN_0_OK_R_LED_N")
	)
	(segment
		(start 37.73805 -290.537392)
		(end 37.762942 -290.5125)
		(width 0.2794)
		(layer "F.Cu")
		(net "FAN_0_OK_R_LED_N")
	)
	(segment
		(start 38.23335 -291.1856)
		(end 37.73805 -291.1856)
		(width 0.2794)
		(layer "F.Cu")
		(net "FAN_0_OK_R_LED_N")
	)
	(segment
		(start 39.878 -291.31895)
		(end 42.991024 -291.31895)
		(width 0.2794)
		(layer "F.Cu")
		(net "FAN_0_OK_R_LED_N")
	)
	(segment
		(start 38.25875 -291.211)
		(end 38.23335 -291.1856)
		(width 0.2794)
		(layer "F.Cu")
		(net "FAN_0_OK_R_LED_N")
	)
	(segment
		(start 39.12235 -291.211)
		(end 38.25875 -291.211)
		(width 0.2794)
		(layer "F.Cu")
		(net "FAN_0_OK_R_LED_N")
	)
	(segment
		(start 37.73805 -291.1856)
		(end 37.73805 -290.537392)
		(width 0.2794)
		(layer "F.Cu")
		(net "FAN_0_OK_R_LED_N")
	)
	(via
		(at 39.878 -291.31895)
		(size 0.762)
		(drill 0.381)
		(layers "F.Cu" "B.Cu")
		(net "FAN_0_OK_R_LED_N")
	)
	(segment
		(start 5.300218 -245.945152)
		(end 5.300218 -247.37949)
		(width 0.1016)
		(layer "B.Cu")
		(net "FAN_6_TIMER")
	)
	(segment
		(start 5.085334 -247.898412)
		(end 4.699 -248.284746)
		(width 0.2794)
		(layer "B.Cu")
		(net "FAN_6_TIMER")
	)
	(segment
		(start 5.300218 -247.37949)
		(end 5.085334 -247.898412)
		(width 0.1016)
		(layer "B.Cu")
		(net "FAN_6_TIMER")
	)
	(segment
		(start 4.699 -248.284746)
		(end 4.699 -249.02795)
		(width 0.2794)
		(layer "B.Cu")
		(net "FAN_6_TIMER")
	)
	(segment
		(start 28.560014 -103.255064)
		(end 28.560014 -103.69804)
		(width 0.2794)
		(layer "F.Cu")
		(net "FAN_5_PWM_BUF")
	)
	(segment
		(start 27.04592 -103.69804)
		(end 26.34996 -104.394)
		(width 0.2794)
		(layer "F.Cu")
		(net "FAN_5_PWM_BUF")
	)
	(segment
		(start 27.423364 -103.69804)
		(end 27.04592 -103.69804)
		(width 0.2794)
		(layer "F.Cu")
		(net "FAN_5_PWM_BUF")
	)
	(segment
		(start 27.813 -102.50805)
		(end 28.560014 -103.255064)
		(width 0.2794)
		(layer "F.Cu")
		(net "FAN_5_PWM_BUF")
	)
	(segment
		(start 28.560014 -103.69804)
		(end 27.423364 -103.69804)
		(width 0.2794)
		(layer "F.Cu")
		(net "FAN_5_PWM_BUF")
	)
	(via
		(at 27.423364 -103.69804)
		(size 0.508)
		(drill 0.254)
		(layers "F.Cu" "B.Cu")
		(net "FAN_5_PWM_BUF")
	)
	(segment
		(start 29.042106 -144.852644)
		(end 29.492702 -144.852644)
		(width 0.2794)
		(layer "F.Cu")
		(net "SMB_FAN2_R_SDA")
	)
	(segment
		(start 27.686 -145.669)
		(end 28.502102 -144.852898)
		(width 0.2794)
		(layer "F.Cu")
		(net "SMB_FAN2_R_SDA")
	)
	(segment
		(start 29.492702 -144.852644)
		(end 29.718 -144.627346)
		(width 0.2794)
		(layer "F.Cu")
		(net "SMB_FAN2_R_SDA")
	)
	(segment
		(start 26.518616 -146.152362)
		(end 25.740106 -148.031962)
		(width 0.2794)
		(layer "F.Cu")
		(net "SMB_FAN2_R_SDA")
	)
	(segment
		(start 27.686 -145.669)
		(end 26.518616 -146.152362)
		(width 0.2794)
		(layer "F.Cu")
		(net "SMB_FAN2_R_SDA")
	)
	(segment
		(start 29.615638 -144.29105)
		(end 29.083 -143.758412)
		(width 0.2794)
		(layer "F.Cu")
		(net "SMB_FAN2_R_SDA")
	)
	(segment
		(start 28.502102 -144.852898)
		(end 29.041852 -144.852898)
		(width 0.2794)
		(layer "F.Cu")
		(net "SMB_FAN2_R_SDA")
	)
	(segment
		(start 29.718 -144.29105)
		(end 29.615638 -144.29105)
		(width 0.2794)
		(layer "F.Cu")
		(net "SMB_FAN2_R_SDA")
	)
	(segment
		(start 29.718 -144.627346)
		(end 29.718 -144.29105)
		(width 0.2794)
		(layer "F.Cu")
		(net "SMB_FAN2_R_SDA")
	)
	(segment
		(start 29.083 -143.758412)
		(end 29.083 -142.00505)
		(width 0.2794)
		(layer "F.Cu")
		(net "SMB_FAN2_R_SDA")
	)
	(segment
		(start 29.041852 -144.852898)
		(end 29.042106 -144.852644)
		(width 0.2794)
		(layer "F.Cu")
		(net "SMB_FAN2_R_SDA")
	)
	(segment
		(start 25.740106 -148.031962)
		(end 25.740106 -149.098)
		(width 0.2794)
		(layer "F.Cu")
		(net "SMB_FAN2_R_SDA")
	)
	(via
		(at 27.686 -145.669)
		(size 0.762)
		(drill 0.381)
		(layers "F.Cu" "B.Cu")
		(net "SMB_FAN2_R_SDA")
	)
	(segment
		(start 19.087846 -156.1846)
		(end 21.355558 -156.1846)
		(width 0.2794)
		(layer "F.Cu")
		(net "SMB_PDBV_FAN_R_U321_SDA")
	)
	(segment
		(start 21.355558 -156.1846)
		(end 21.839936 -155.700222)
		(width 0.2794)
		(layer "F.Cu")
		(net "SMB_PDBV_FAN_R_U321_SDA")
	)
	(segment
		(start 18.61439 -156.658056)
		(end 19.087846 -156.1846)
		(width 0.2794)
		(layer "F.Cu")
		(net "SMB_PDBV_FAN_R_U321_SDA")
	)
	(segment
		(start 17.272 -158.000446)
		(end 18.61439 -156.658056)
		(width 0.2794)
		(layer "F.Cu")
		(net "SMB_PDBV_FAN_R_U321_SDA")
	)
	(segment
		(start 17.272 -159.61995)
		(end 17.272 -158.000446)
		(width 0.2794)
		(layer "F.Cu")
		(net "SMB_PDBV_FAN_R_U321_SDA")
	)
	(segment
		(start 21.839936 -155.700222)
		(end 21.839936 -154.94)
		(width 0.2794)
		(layer "F.Cu")
		(net "SMB_PDBV_FAN_R_U321_SDA")
	)
	(via
		(at 18.61439 -156.658056)
		(size 0.762)
		(drill 0.381)
		(layers "F.Cu" "B.Cu")
		(net "SMB_PDBV_FAN_R_U321_SDA")
	)
	(segment
		(start 8.955786 -246.074692)
		(end 8.781542 -246.248936)
		(width 0.2794)
		(layer "F.Cu")
		(net "FAN_6_MODE")
	)
	(segment
		(start 6.227064 -246.248936)
		(end 5.06095 -247.41505)
		(width 0.2794)
		(layer "F.Cu")
		(net "FAN_6_MODE")
	)
	(segment
		(start 5.06095 -247.523)
		(end 5.06095 -248.793)
		(width 0.2794)
		(layer "F.Cu")
		(net "FAN_6_MODE")
	)
	(segment
		(start 8.781542 -246.248936)
		(end 6.227064 -246.248936)
		(width 0.2794)
		(layer "F.Cu")
		(net "FAN_6_MODE")
	)
	(segment
		(start 5.06095 -247.41505)
		(end 5.06095 -247.523)
		(width 0.2794)
		(layer "F.Cu")
		(net "FAN_6_MODE")
	)
	(segment
		(start 5.06095 -248.793)
		(end 5.56895 -249.301)
		(width 0.2794)
		(layer "F.Cu")
		(net "FAN_6_MODE")
	)
	(via
		(at 8.955786 -246.074692)
		(size 0.762)
		(drill 0.254)
		(layers "F.Cu" "B.Cu")
		(net "FAN_6_MODE")
	)
	(segment
		(start 8.10006 -246.024146)
		(end 8.10006 -245.945152)
		(width 0.1016)
		(layer "B.Cu")
		(net "FAN_6_MODE")
	)
	(segment
		(start 8.955786 -246.074692)
		(end 8.781542 -246.248936)
		(width 0.2794)
		(layer "B.Cu")
		(net "FAN_6_MODE")
	)
	(segment
		(start 8.201914 -246.126)
		(end 8.10006 -246.024146)
		(width 0.1016)
		(layer "B.Cu")
		(net "FAN_6_MODE")
	)
	(segment
		(start 8.32485 -246.248936)
		(end 8.201914 -246.126)
		(width 0.2794)
		(layer "B.Cu")
		(net "FAN_6_MODE")
	)
	(segment
		(start 8.781542 -246.248936)
		(end 8.32485 -246.248936)
		(width 0.2794)
		(layer "B.Cu")
		(net "FAN_6_MODE")
	)
	(segment
		(start 27.11196 -17.59204)
		(end 28.067 -16.637)
		(width 0.2794)
		(layer "F.Cu")
		(net "FAN_4_PWM_BUF")
	)
	(segment
		(start 26.545286 -20.41144)
		(end 27.11196 -19.844766)
		(width 0.2794)
		(layer "F.Cu")
		(net "FAN_4_PWM_BUF")
	)
	(segment
		(start 26.545286 -20.713954)
		(end 26.545286 -20.41144)
		(width 0.2794)
		(layer "F.Cu")
		(net "FAN_4_PWM_BUF")
	)
	(segment
		(start 27.11196 -18.796)
		(end 27.11196 -17.59204)
		(width 0.2794)
		(layer "F.Cu")
		(net "FAN_4_PWM_BUF")
	)
	(segment
		(start 28.575 -16.637)
		(end 28.814014 -16.876014)
		(width 0.2794)
		(layer "F.Cu")
		(net "FAN_4_PWM_BUF")
	)
	(segment
		(start 28.814014 -16.876014)
		(end 28.814014 -18.10004)
		(width 0.2794)
		(layer "F.Cu")
		(net "FAN_4_PWM_BUF")
	)
	(segment
		(start 28.067 -16.637)
		(end 28.575 -16.637)
		(width 0.2794)
		(layer "F.Cu")
		(net "FAN_4_PWM_BUF")
	)
	(segment
		(start 27.11196 -19.844766)
		(end 27.11196 -18.796)
		(width 0.2794)
		(layer "F.Cu")
		(net "FAN_4_PWM_BUF")
	)
	(via
		(at 28.575 -16.637)
		(size 0.762)
		(drill 0.381)
		(layers "F.Cu" "B.Cu")
		(net "FAN_4_PWM_BUF")
	)
	(segment
		(start 26.390092 -148.249132)
		(end 26.390092 -149.098)
		(width 0.2794)
		(layer "F.Cu")
		(net "SMB_FAN2_R_SCL")
	)
	(segment
		(start 30.150816 -145.741898)
		(end 31.601664 -144.29105)
		(width 0.2794)
		(layer "F.Cu")
		(net "SMB_FAN2_R_SCL")
	)
	(segment
		(start 30.861 -142.874746)
		(end 30.861 -143.764)
		(width 0.2794)
		(layer "F.Cu")
		(net "SMB_FAN2_R_SCL")
	)
	(segment
		(start 31.601664 -144.29105)
		(end 31.623 -144.29105)
		(width 0.2794)
		(layer "F.Cu")
		(net "SMB_FAN2_R_SCL")
	)
	(segment
		(start 31.38805 -144.29105)
		(end 31.601664 -144.29105)
		(width 0.2794)
		(layer "F.Cu")
		(net "SMB_FAN2_R_SCL")
	)
	(segment
		(start 26.939494 -146.923506)
		(end 26.390092 -148.249132)
		(width 0.2794)
		(layer "F.Cu")
		(net "SMB_FAN2_R_SCL")
	)
	(segment
		(start 30.861 -143.764)
		(end 31.38805 -144.29105)
		(width 0.2794)
		(layer "F.Cu")
		(net "SMB_FAN2_R_SCL")
	)
	(segment
		(start 31.623 -141.75105)
		(end 31.623 -142.112746)
		(width 0.2794)
		(layer "F.Cu")
		(net "SMB_FAN2_R_SCL")
	)
	(segment
		(start 29.410152 -145.741898)
		(end 30.150816 -145.741898)
		(width 0.2794)
		(layer "F.Cu")
		(net "SMB_FAN2_R_SCL")
	)
	(segment
		(start 27.028394 -146.834606)
		(end 26.939494 -146.923506)
		(width 0.2794)
		(layer "F.Cu")
		(net "SMB_FAN2_R_SCL")
	)
	(segment
		(start 29.22905 -145.923)
		(end 27.028394 -146.834606)
		(width 0.2794)
		(layer "F.Cu")
		(net "SMB_FAN2_R_SCL")
	)
	(segment
		(start 29.410152 -145.741898)
		(end 29.22905 -145.923)
		(width 0.2794)
		(layer "F.Cu")
		(net "SMB_FAN2_R_SCL")
	)
	(segment
		(start 31.623 -142.112746)
		(end 30.861 -142.874746)
		(width 0.2794)
		(layer "F.Cu")
		(net "SMB_FAN2_R_SCL")
	)
	(via
		(at 29.410152 -145.741898)
		(size 0.508)
		(drill 0.254)
		(layers "F.Cu" "B.Cu")
		(net "SMB_FAN2_R_SCL")
	)
	(segment
		(start 23.241 -145.316702)
		(end 23.241 -144.67205)
		(width 0.2794)
		(layer "F.Cu")
		(net "SMB_FAN0_R_SCL")
	)
	(segment
		(start 24.257 -142.00505)
		(end 24.257 -143.623284)
		(width 0.2794)
		(layer "F.Cu")
		(net "SMB_FAN0_R_SCL")
	)
	(segment
		(start 23.417276 -145.492978)
		(end 23.241 -145.316702)
		(width 0.2794)
		(layer "F.Cu")
		(net "SMB_FAN0_R_SCL")
	)
	(segment
		(start 23.72995 -144.29105)
		(end 23.622 -144.29105)
		(width 0.2794)
		(layer "F.Cu")
		(net "SMB_FAN0_R_SCL")
	)
	(segment
		(start 23.789894 -149.098)
		(end 23.789894 -146.392646)
		(width 0.2794)
		(layer "F.Cu")
		(net "SMB_FAN0_R_SCL")
	)
	(segment
		(start 24.157432 -143.863568)
		(end 23.72995 -144.29105)
		(width 0.2794)
		(layer "F.Cu")
		(net "SMB_FAN0_R_SCL")
	)
	(segment
		(start 23.789894 -146.392646)
		(end 23.417276 -145.492978)
		(width 0.2794)
		(layer "F.Cu")
		(net "SMB_FAN0_R_SCL")
	)
	(segment
		(start 24.257 -143.623284)
		(end 24.157432 -143.863568)
		(width 0.2794)
		(layer "F.Cu")
		(net "SMB_FAN0_R_SCL")
	)
	(segment
		(start 23.241 -144.67205)
		(end 23.622 -144.29105)
		(width 0.2794)
		(layer "F.Cu")
		(net "SMB_FAN0_R_SCL")
	)
	(via
		(at 23.417276 -145.492978)
		(size 0.762)
		(drill 0.381)
		(layers "F.Cu" "B.Cu")
		(net "SMB_FAN0_R_SCL")
	)
	(segment
		(start 3.57251 -249.694192)
		(end 2.903982 -249.694192)
		(width 0.2794)
		(layer "F.Cu")
		(net "FAN_6_FAULT")
	)
	(segment
		(start 2.547112 -247.506998)
		(end 2.896362 -247.157748)
		(width 0.2794)
		(layer "F.Cu")
		(net "FAN_6_FAULT")
	)
	(segment
		(start 2.547112 -249.337322)
		(end 2.547112 -247.506998)
		(width 0.2794)
		(layer "F.Cu")
		(net "FAN_6_FAULT")
	)
	(segment
		(start 4.079748 -247.157748)
		(end 4.445 -247.523)
		(width 0.2794)
		(layer "F.Cu")
		(net "FAN_6_FAULT")
	)
	(segment
		(start 2.903982 -249.694192)
		(end 2.547112 -249.337322)
		(width 0.2794)
		(layer "F.Cu")
		(net "FAN_6_FAULT")
	)
	(segment
		(start 4.111752 -249.15495)
		(end 3.57251 -249.694192)
		(width 0.2794)
		(layer "F.Cu")
		(net "FAN_6_FAULT")
	)
	(segment
		(start 2.896362 -247.157748)
		(end 4.079748 -247.157748)
		(width 0.2794)
		(layer "F.Cu")
		(net "FAN_6_FAULT")
	)
	(segment
		(start 4.445 -249.15495)
		(end 4.111752 -249.15495)
		(width 0.2794)
		(layer "F.Cu")
		(net "FAN_6_FAULT")
	)
	(via
		(at 2.903982 -249.694192)
		(size 0.762)
		(drill 0.381)
		(layers "F.Cu" "B.Cu")
		(net "FAN_6_FAULT")
	)
	(via
		(at 4.445 -247.523)
		(size 0.508)
		(drill 0.254)
		(layers "F.Cu" "B.Cu")
		(net "FAN_6_FAULT")
	)
	(segment
		(start 4.645914 -247.142508)
		(end 4.900168 -246.528336)
		(width 0.1016)
		(layer "B.Cu")
		(net "FAN_6_FAULT")
	)
	(segment
		(start 4.900168 -246.528336)
		(end 4.900168 -245.945152)
		(width 0.1016)
		(layer "B.Cu")
		(net "FAN_6_FAULT")
	)
	(segment
		(start 4.645914 -247.322086)
		(end 4.645914 -247.142508)
		(width 0.2794)
		(layer "B.Cu")
		(net "FAN_6_FAULT")
	)
	(segment
		(start 4.445 -247.523)
		(end 4.645914 -247.322086)
		(width 0.2794)
		(layer "B.Cu")
		(net "FAN_6_FAULT")
	)
	(segment
		(start 33.2486 -302.895)
		(end 33.42005 -302.72355)
		(width 0.2794)
		(layer "F.Cu")
		(net "FAN_0_TACH_IL_R")
	)
	(segment
		(start 33.42005 -302.72355)
		(end 33.42005 -301.752)
		(width 0.2794)
		(layer "F.Cu")
		(net "FAN_0_TACH_IL_R")
	)
	(segment
		(start 33.42005 -300.609)
		(end 33.42005 -301.752)
		(width 0.2794)
		(layer "F.Cu")
		(net "FAN_0_TACH_IL_R")
	)
	(segment
		(start 35.2298 -303.1998)
		(end 34.9504 -303.4792)
		(width 0.2794)
		(layer "F.Cu")
		(net "FAN_0_TACH_IL_R")
	)
	(segment
		(start 35.2298 -302.26)
		(end 35.2298 -303.1998)
		(width 0.2794)
		(layer "F.Cu")
		(net "FAN_0_TACH_IL_R")
	)
	(segment
		(start 33.2486 -302.895)
		(end 33.8328 -303.4792)
		(width 0.2794)
		(layer "F.Cu")
		(net "FAN_0_TACH_IL_R")
	)
	(segment
		(start 33.8328 -303.4792)
		(end 34.7472 -303.4792)
		(width 0.2794)
		(layer "F.Cu")
		(net "FAN_0_TACH_IL_R")
	)
	(segment
		(start 34.9504 -303.4792)
		(end 34.7472 -303.4792)
		(width 0.2794)
		(layer "F.Cu")
		(net "FAN_0_TACH_IL_R")
	)
	(via
		(at 34.7472 -303.4792)
		(size 0.508)
		(drill 0.254)
		(layers "F.Cu" "B.Cu")
		(net "FAN_0_TACH_IL_R")
	)
	(via
		(at 3.756914 -247.904)
		(size 0.762)
		(drill 0.254)
		(layers "F.Cu" "B.Cu")
		(net "FAN_6_SS")
	)
	(segment
		(start 3.756914 -248.458736)
		(end 3.683 -248.53265)
		(width 0.2794)
		(layer "B.Cu")
		(net "FAN_6_SS")
	)
	(segment
		(start 3.756914 -247.904)
		(end 3.756914 -248.458736)
		(width 0.2794)
		(layer "B.Cu")
		(net "FAN_6_SS")
	)
	(segment
		(start 3.683 -248.53265)
		(end 3.683 -249.02795)
		(width 0.2794)
		(layer "B.Cu")
		(net "FAN_6_SS")
	)
	(segment
		(start 3.756914 -247.396)
		(end 3.756914 -247.904)
		(width 0.1016)
		(layer "B.Cu")
		(net "FAN_6_SS")
	)
	(segment
		(start 4.500118 -246.652796)
		(end 3.756914 -247.396)
		(width 0.1016)
		(layer "B.Cu")
		(net "FAN_6_SS")
	)
	(segment
		(start 4.500118 -245.945152)
		(end 4.500118 -246.652796)
		(width 0.1016)
		(layer "B.Cu")
		(net "FAN_6_SS")
	)
	(segment
		(start 29.21 -105.59796)
		(end 29.2354 -105.62336)
		(width 0.2794)
		(layer "F.Cu")
		(net "FAN_5_PWM")
	)
	(segment
		(start 14.859 -112.014)
		(end 14.943836 -111.929164)
		(width 0.2794)
		(layer "F.Cu")
		(net "FAN_5_PWM")
	)
	(segment
		(start 26.47188 -109.347)
		(end 29.03093 -106.78795)
		(width 0.2794)
		(layer "F.Cu")
		(net "FAN_5_PWM")
	)
	(segment
		(start 20.190714 -111.929164)
		(end 22.772878 -109.347)
		(width 0.2794)
		(layer "F.Cu")
		(net "FAN_5_PWM")
	)
	(segment
		(start 29.2354 -106.76255)
		(end 29.21 -106.78795)
		(width 0.2794)
		(layer "F.Cu")
		(net "FAN_5_PWM")
	)
	(segment
		(start 29.03093 -106.78795)
		(end 29.21 -106.78795)
		(width 0.2794)
		(layer "F.Cu")
		(net "FAN_5_PWM")
	)
	(segment
		(start 29.2354 -105.62336)
		(end 29.2354 -106.76255)
		(width 0.2794)
		(layer "F.Cu")
		(net "FAN_5_PWM")
	)
	(segment
		(start 14.45895 -127.127)
		(end 14.45895 -127.762)
		(width 0.2794)
		(layer "F.Cu")
		(net "FAN_5_PWM")
	)
	(segment
		(start 14.943836 -111.929164)
		(end 20.190714 -111.929164)
		(width 0.2794)
		(layer "F.Cu")
		(net "FAN_5_PWM")
	)
	(segment
		(start 22.772878 -109.347)
		(end 26.47188 -109.347)
		(width 0.2794)
		(layer "F.Cu")
		(net "FAN_5_PWM")
	)
	(via
		(at 14.45895 -127.762)
		(size 0.508)
		(drill 0.254)
		(layers "F.Cu" "B.Cu")
		(net "FAN_5_PWM")
	)
	(via
		(at 14.859 -112.014)
		(size 0.508)
		(drill 0.254)
		(layers "F.Cu" "B.Cu")
		(net "FAN_5_PWM")
	)
	(segment
		(start 14.0843 -115.85194)
		(end 14.23416 -116.0018)
		(width 0.2286)
		(layer "In2.Cu")
		(net "FAN_5_PWM")
	)
	(segment
		(start 14.23416 -116.0018)
		(end 14.23416 -121.73204)
		(width 0.2286)
		(layer "In2.Cu")
		(net "FAN_5_PWM")
	)
	(segment
		(start 14.23416 -121.73204)
		(end 13.8938 -122.0724)
		(width 0.2286)
		(layer "In2.Cu")
		(net "FAN_5_PWM")
	)
	(segment
		(start 14.859 -112.014)
		(end 14.0843 -112.7887)
		(width 0.2286)
		(layer "In2.Cu")
		(net "FAN_5_PWM")
	)
	(segment
		(start 13.8938 -122.0724)
		(end 13.8938 -127.19685)
		(width 0.2286)
		(layer "In2.Cu")
		(net "FAN_5_PWM")
	)
	(segment
		(start 14.0843 -112.7887)
		(end 14.0843 -115.85194)
		(width 0.2286)
		(layer "In2.Cu")
		(net "FAN_5_PWM")
	)
	(segment
		(start 13.8938 -127.19685)
		(end 14.45895 -127.762)
		(width 0.2286)
		(layer "In2.Cu")
		(net "FAN_5_PWM")
	)
	(segment
		(start 37.4142 -288.2646)
		(end 37.4142 -288.29)
		(width 0.2794)
		(layer "F.Cu")
		(net "FAN_0_TACH_OL_D")
	)
	(segment
		(start 38.7604 -288.29)
		(end 40.77462 -290.30422)
		(width 0.2794)
		(layer "F.Cu")
		(net "FAN_0_TACH_OL_D")
	)
	(segment
		(start 36.746942 -286.639)
		(end 36.746942 -287.597342)
		(width 0.2794)
		(layer "F.Cu")
		(net "FAN_0_TACH_OL_D")
	)
	(segment
		(start 38.7604 -288.29)
		(end 37.4142 -288.29)
		(width 0.2794)
		(layer "F.Cu")
		(net "FAN_0_TACH_OL_D")
	)
	(segment
		(start 40.77462 -290.30422)
		(end 43.99407 -290.30422)
		(width 0.2794)
		(layer "F.Cu")
		(net "FAN_0_TACH_OL_D")
	)
	(segment
		(start 36.746942 -287.597342)
		(end 37.4142 -288.2646)
		(width 0.2794)
		(layer "F.Cu")
		(net "FAN_0_TACH_OL_D")
	)
	(segment
		(start 43.99407 -290.30422)
		(end 44.99991 -291.31006)
		(width 0.2794)
		(layer "F.Cu")
		(net "FAN_0_TACH_OL_D")
	)
	(via
		(at 38.7604 -288.29)
		(size 0.762)
		(drill 0.381)
		(layers "F.Cu" "B.Cu")
		(net "FAN_0_TACH_OL_D")
	)
	(segment
		(start 4.445 -249.95505)
		(end 4.80695 -250.317)
		(width 0.2794)
		(layer "F.Cu")
		(net "FAN_6_FAULT_R")
	)
	(segment
		(start 4.80695 -250.317)
		(end 5.56895 -250.317)
		(width 0.2794)
		(layer "F.Cu")
		(net "FAN_6_FAULT_R")
	)
	(segment
		(start 37.73805 -294.767)
		(end 38.862 -294.767)
		(width 0.2794)
		(layer "F.Cu")
		(net "SMB_FAN0_SDA_R")
	)
	(segment
		(start 38.862 -294.767)
		(end 39.878 -295.783)
		(width 0.2794)
		(layer "F.Cu")
		(net "SMB_FAN0_SDA_R")
	)
	(segment
		(start 41.656 -297.561)
		(end 39.878 -295.783)
		(width 0.2794)
		(layer "F.Cu")
		(net "SMB_FAN0_SDA_R")
	)
	(via
		(at 39.878 -295.783)
		(size 0.762)
		(drill 0.381)
		(layers "F.Cu" "B.Cu")
		(net "SMB_FAN0_SDA_R")
	)
	(via
		(at 41.656 -297.561)
		(size 0.508)
		(drill 0.254)
		(layers "F.Cu" "B.Cu")
		(net "SMB_FAN0_SDA_R")
	)
	(segment
		(start 41.656 -297.561)
		(end 42.3926 -298.2976)
		(width 0.2286)
		(layer "In2.Cu")
		(net "SMB_FAN0_SDA_R")
	)
	(segment
		(start 42.3926 -298.2976)
		(end 44.012358 -298.2976)
		(width 0.2286)
		(layer "In2.Cu")
		(net "SMB_FAN0_SDA_R")
	)
	(segment
		(start 44.012358 -298.2976)
		(end 44.99991 -297.310048)
		(width 0.2286)
		(layer "In2.Cu")
		(net "SMB_FAN0_SDA_R")
	)
	(segment
		(start 37.762942 -301.199804)
		(end 37.762942 -300.609)
		(width 0.2794)
		(layer "F.Cu")
		(net "FAN_0_TACH_IL_D")
	)
	(segment
		(start 37.4142 -302.26)
		(end 37.511736 -302.357536)
		(width 0.2794)
		(layer "F.Cu")
		(net "FAN_0_TACH_IL_D")
	)
	(segment
		(start 38.7604 -302.357536)
		(end 44.04741 -302.357536)
		(width 0.2794)
		(layer "F.Cu")
		(net "FAN_0_TACH_IL_D")
	)
	(segment
		(start 37.4142 -301.548546)
		(end 37.762942 -301.199804)
		(width 0.2794)
		(layer "F.Cu")
		(net "FAN_0_TACH_IL_D")
	)
	(segment
		(start 37.4142 -302.26)
		(end 37.4142 -301.548546)
		(width 0.2794)
		(layer "F.Cu")
		(net "FAN_0_TACH_IL_D")
	)
	(segment
		(start 37.511736 -302.357536)
		(end 38.7604 -302.357536)
		(width 0.2794)
		(layer "F.Cu")
		(net "FAN_0_TACH_IL_D")
	)
	(segment
		(start 44.04741 -302.357536)
		(end 44.99991 -303.310036)
		(width 0.2794)
		(layer "F.Cu")
		(net "FAN_0_TACH_IL_D")
	)
	(via
		(at 38.7604 -302.357536)
		(size 0.762)
		(drill 0.381)
		(layers "F.Cu" "B.Cu")
		(net "FAN_0_TACH_IL_D")
	)
	(segment
		(start 33.7566 -289.052)
		(end 33.6296 -288.925)
		(width 0.2794)
		(layer "F.Cu")
		(net "FAN_0_TACH_OL_R")
	)
	(segment
		(start 34.4932 -289.052)
		(end 33.7566 -289.052)
		(width 0.2794)
		(layer "F.Cu")
		(net "FAN_0_TACH_OL_R")
	)
	(segment
		(start 33.6296 -288.925)
		(end 33.782 -288.7726)
		(width 0.2794)
		(layer "F.Cu")
		(net "FAN_0_TACH_OL_R")
	)
	(segment
		(start 33.782 -288.7726)
		(end 33.782 -287.54705)
		(width 0.2794)
		(layer "F.Cu")
		(net "FAN_0_TACH_OL_R")
	)
	(segment
		(start 33.782 -287.54705)
		(end 32.766 -287.54705)
		(width 0.2794)
		(layer "F.Cu")
		(net "FAN_0_TACH_OL_R")
	)
	(segment
		(start 35.2298 -288.3154)
		(end 34.4932 -289.052)
		(width 0.2794)
		(layer "F.Cu")
		(net "FAN_0_TACH_OL_R")
	)
	(segment
		(start 35.2298 -288.29)
		(end 35.2298 -288.3154)
		(width 0.2794)
		(layer "F.Cu")
		(net "FAN_0_TACH_OL_R")
	)
	(via
		(at 34.4932 -289.052)
		(size 0.508)
		(drill 0.254)
		(layers "F.Cu" "B.Cu")
		(net "FAN_0_TACH_OL_R")
	)
	(via
		(at 34.92373 -63.21425)
		(size 0.762)
		(drill 0.254)
		(layers "F.Cu" "B.Cu")
		(net "FAN_3_SS")
	)
	(segment
		(start 34.92373 -63.21425)
		(end 34.973514 -63.164466)
		(width 0.1016)
		(layer "B.Cu")
		(net "FAN_3_SS")
	)
	(segment
		(start 34.973514 -63.164466)
		(end 34.973514 -62.996826)
		(width 0.1016)
		(layer "B.Cu")
		(net "FAN_3_SS")
	)
	(segment
		(start 34.417 -64.437006)
		(end 34.92373 -63.21425)
		(width 0.2794)
		(layer "B.Cu")
		(net "FAN_3_SS")
	)
	(segment
		(start 35.917632 -62.052708)
		(end 35.917632 -61.345064)
		(width 0.1016)
		(layer "B.Cu")
		(net "FAN_3_SS")
	)
	(segment
		(start 34.973514 -62.996826)
		(end 35.917632 -62.052708)
		(width 0.1016)
		(layer "B.Cu")
		(net "FAN_3_SS")
	)
	(segment
		(start 32.61995 -193.548)
		(end 32.61995 -193.5734)
		(width 0.2794)
		(layer "F.Cu")
		(net "FAN_1_TACH_OL")
	)
	(segment
		(start 31.916116 -194.277234)
		(end 31.916116 -196.159374)
		(width 0.2794)
		(layer "F.Cu")
		(net "FAN_1_TACH_OL")
	)
	(segment
		(start 32.61995 -193.5734)
		(end 31.916116 -194.277234)
		(width 0.2794)
		(layer "F.Cu")
		(net "FAN_1_TACH_OL")
	)
	(segment
		(start 38.24605 -131.318)
		(end 38.24605 -131.953)
		(width 0.2794)
		(layer "F.Cu")
		(net "FAN_1_TACH_OL")
	)
	(via
		(at 38.24605 -131.953)
		(size 0.508)
		(drill 0.254)
		(layers "F.Cu" "B.Cu")
		(net "FAN_1_TACH_OL")
	)
	(via
		(at 31.916116 -196.159374)
		(size 0.508)
		(drill 0.254)
		(layers "F.Cu" "B.Cu")
		(net "FAN_1_TACH_OL")
	)
	(segment
		(start 39.73195 -131.953)
		(end 38.24605 -131.953)
		(width 0.2794)
		(layer "B.Cu")
		(net "FAN_1_TACH_OL")
	)
	(segment
		(start 40.49395 -131.191)
		(end 39.73195 -131.953)
		(width 0.2794)
		(layer "B.Cu")
		(net "FAN_1_TACH_OL")
	)
	(segment
		(start 38.24605 -131.953)
		(end 38.575234 -131.953)
		(width 0.2286)
		(layer "In2.Cu")
		(net "FAN_1_TACH_OL")
	)
	(segment
		(start 39.834566 -174.606966)
		(end 40.513 -175.2854)
		(width 0.2286)
		(layer "In2.Cu")
		(net "FAN_1_TACH_OL")
	)
	(segment
		(start 46.99 -143.682466)
		(end 46.99 -160.102042)
		(width 0.2286)
		(layer "In2.Cu")
		(net "FAN_1_TACH_OL")
	)
	(segment
		(start 40.513 -187.579)
		(end 31.932626 -196.159374)
		(width 0.2286)
		(layer "In2.Cu")
		(net "FAN_1_TACH_OL")
	)
	(segment
		(start 41.115996 -134.493762)
		(end 41.115996 -137.808462)
		(width 0.2286)
		(layer "In2.Cu")
		(net "FAN_1_TACH_OL")
	)
	(segment
		(start 31.932626 -196.159374)
		(end 31.916116 -196.159374)
		(width 0.2286)
		(layer "In2.Cu")
		(net "FAN_1_TACH_OL")
	)
	(segment
		(start 46.99 -160.102042)
		(end 39.834566 -167.257476)
		(width 0.2286)
		(layer "In2.Cu")
		(net "FAN_1_TACH_OL")
	)
	(segment
		(start 39.834566 -167.257476)
		(end 39.834566 -174.606966)
		(width 0.2286)
		(layer "In2.Cu")
		(net "FAN_1_TACH_OL")
	)
	(segment
		(start 40.513 -175.2854)
		(end 40.513 -187.579)
		(width 0.2286)
		(layer "In2.Cu")
		(net "FAN_1_TACH_OL")
	)
	(segment
		(start 38.575234 -131.953)
		(end 41.115996 -134.493762)
		(width 0.2286)
		(layer "In2.Cu")
		(net "FAN_1_TACH_OL")
	)
	(segment
		(start 41.115996 -137.808462)
		(end 46.99 -143.682466)
		(width 0.2286)
		(layer "In2.Cu")
		(net "FAN_1_TACH_OL")
	)
	(segment
		(start 18.30705 -170.58005)
		(end 18.30705 -170.815)
		(width 0.2794)
		(layer "F.Cu")
		(net "FAN_5_PRESENT_R_N")
	)
	(segment
		(start 17.84223 -170.11523)
		(end 18.30705 -170.58005)
		(width 0.2794)
		(layer "F.Cu")
		(net "FAN_5_PRESENT_R_N")
	)
	(segment
		(start 17.526 -170.11523)
		(end 17.84223 -170.11523)
		(width 0.2794)
		(layer "F.Cu")
		(net "FAN_5_PRESENT_R_N")
	)
	(via
		(at 17.526 -170.11523)
		(size 0.508)
		(drill 0.254)
		(layers "F.Cu" "B.Cu")
		(net "FAN_5_PRESENT_R_N")
	)
	(segment
		(start 9.49198 -164.595302)
		(end 4.5212 -159.624522)
		(width 0.2286)
		(layer "In2.Cu")
		(net "FAN_5_PRESENT_R_N")
	)
	(segment
		(start 15.767558 -169.82186)
		(end 10.541 -164.595302)
		(width 0.2286)
		(layer "In2.Cu")
		(net "FAN_5_PRESENT_R_N")
	)
	(segment
		(start 17.523206 -170.11523)
		(end 17.229836 -169.82186)
		(width 0.2286)
		(layer "In2.Cu")
		(net "FAN_5_PRESENT_R_N")
	)
	(segment
		(start 10.1854 -129.9464)
		(end 10.08126 -129.84226)
		(width 0.2286)
		(layer "In2.Cu")
		(net "FAN_5_PRESENT_R_N")
	)
	(segment
		(start 10.1854 -136.8806)
		(end 10.1854 -129.9464)
		(width 0.2286)
		(layer "In2.Cu")
		(net "FAN_5_PRESENT_R_N")
	)
	(segment
		(start 10.08126 -129.84226)
		(end 10.08126 -119.45366)
		(width 0.2286)
		(layer "In2.Cu")
		(net "FAN_5_PRESENT_R_N")
	)
	(segment
		(start 10.9601 -118.57482)
		(end 10.9601 -108.6231)
		(width 0.2286)
		(layer "In2.Cu")
		(net "FAN_5_PRESENT_R_N")
	)
	(segment
		(start 10.9601 -108.6231)
		(end 9.046972 -106.709972)
		(width 0.2286)
		(layer "In2.Cu")
		(net "FAN_5_PRESENT_R_N")
	)
	(segment
		(start 17.526 -170.11523)
		(end 17.523206 -170.11523)
		(width 0.2286)
		(layer "In2.Cu")
		(net "FAN_5_PRESENT_R_N")
	)
	(segment
		(start 10.08126 -119.45366)
		(end 10.9601 -118.57482)
		(width 0.2286)
		(layer "In2.Cu")
		(net "FAN_5_PRESENT_R_N")
	)
	(segment
		(start 10.541 -164.595302)
		(end 9.49198 -164.595302)
		(width 0.2286)
		(layer "In2.Cu")
		(net "FAN_5_PRESENT_R_N")
	)
	(segment
		(start 17.229836 -169.82186)
		(end 15.767558 -169.82186)
		(width 0.2286)
		(layer "In2.Cu")
		(net "FAN_5_PRESENT_R_N")
	)
	(segment
		(start 9.046972 -106.709972)
		(end 8.700008 -106.709972)
		(width 0.2286)
		(layer "In2.Cu")
		(net "FAN_5_PRESENT_R_N")
	)
	(segment
		(start 4.5212 -142.5448)
		(end 10.1854 -136.8806)
		(width 0.2286)
		(layer "In2.Cu")
		(net "FAN_5_PRESENT_R_N")
	)
	(segment
		(start 4.5212 -159.624522)
		(end 4.5212 -142.5448)
		(width 0.2286)
		(layer "In2.Cu")
		(net "FAN_5_PRESENT_R_N")
	)
	(via
		(at 32.512 -63.754)
		(size 0.762)
		(drill 0.254)
		(layers "F.Cu" "B.Cu")
		(net "FAN_3_CS")
	)
	(segment
		(start 32.380428 -64.427862)
		(end 32.380428 -63.885572)
		(width 0.2794)
		(layer "B.Cu")
		(net "FAN_3_CS")
	)
	(segment
		(start 35.117786 -61.455554)
		(end 35.117786 -61.345064)
		(width 0.1016)
		(layer "B.Cu")
		(net "FAN_3_CS")
	)
	(segment
		(start 34.035238 -62.230762)
		(end 34.960814 -61.612526)
		(width 0.1016)
		(layer "B.Cu")
		(net "FAN_3_CS")
	)
	(segment
		(start 32.380428 -63.885572)
		(end 32.512 -63.754)
		(width 0.2794)
		(layer "B.Cu")
		(net "FAN_3_CS")
	)
	(segment
		(start 32.512 -63.754)
		(end 34.035238 -62.230762)
		(width 0.2794)
		(layer "B.Cu")
		(net "FAN_3_CS")
	)
	(segment
		(start 34.960814 -61.612526)
		(end 35.117786 -61.455554)
		(width 0.1016)
		(layer "B.Cu")
		(net "FAN_3_CS")
	)
	(segment
		(start 37.253926 -62.18682)
		(end 36.30295 -63.137796)
		(width 0.2794)
		(layer "F.Cu")
		(net "FAN_3_MODE")
	)
	(segment
		(start 36.30295 -64.262)
		(end 36.30295 -63.246)
		(width 0.2794)
		(layer "F.Cu")
		(net "FAN_3_MODE")
	)
	(segment
		(start 40.49522 -62.18682)
		(end 37.253926 -62.18682)
		(width 0.2794)
		(layer "F.Cu")
		(net "FAN_3_MODE")
	)
	(segment
		(start 36.30295 -63.137796)
		(end 36.30295 -63.246)
		(width 0.2794)
		(layer "F.Cu")
		(net "FAN_3_MODE")
	)
	(via
		(at 40.49522 -62.18682)
		(size 0.762)
		(drill 0.254)
		(layers "F.Cu" "B.Cu")
		(net "FAN_3_MODE")
	)
	(segment
		(start 39.517574 -61.424058)
		(end 39.517574 -61.345064)
		(width 0.1016)
		(layer "B.Cu")
		(net "FAN_3_MODE")
	)
	(segment
		(start 40.49522 -62.18682)
		(end 39.896796 -61.588396)
		(width 0.2794)
		(layer "B.Cu")
		(net "FAN_3_MODE")
	)
	(segment
		(start 39.681912 -61.588396)
		(end 39.619428 -61.525912)
		(width 0.2794)
		(layer "B.Cu")
		(net "FAN_3_MODE")
	)
	(segment
		(start 39.896796 -61.588396)
		(end 39.681912 -61.588396)
		(width 0.2794)
		(layer "B.Cu")
		(net "FAN_3_MODE")
	)
	(segment
		(start 39.619428 -61.525912)
		(end 39.517574 -61.424058)
		(width 0.1016)
		(layer "B.Cu")
		(net "FAN_3_MODE")
	)
	(via
		(at 40.9448 -63.8048)
		(size 0.762)
		(drill 0.254)
		(layers "F.Cu" "B.Cu")
		(net "FAN_3_TEMP")
	)
	(segment
		(start 39.746428 -62.541912)
		(end 40.075866 -62.87135)
		(width 0.2794)
		(layer "B.Cu")
		(net "FAN_3_TEMP")
	)
	(segment
		(start 40.9448 -63.8048)
		(end 41.25468 -64.11468)
		(width 0.2794)
		(layer "B.Cu")
		(net "FAN_3_TEMP")
	)
	(segment
		(start 40.156892 -62.992508)
		(end 40.439086 -63.048388)
		(width 0.2794)
		(layer "B.Cu")
		(net "FAN_3_TEMP")
	)
	(segment
		(start 40.439086 -63.048388)
		(end 40.9448 -63.8048)
		(width 0.2794)
		(layer "B.Cu")
		(net "FAN_3_TEMP")
	)
	(segment
		(start 40.075866 -62.87135)
		(end 40.156892 -62.992508)
		(width 0.2794)
		(layer "B.Cu")
		(net "FAN_3_TEMP")
	)
	(segment
		(start 39.117778 -61.913262)
		(end 39.746428 -62.541912)
		(width 0.1016)
		(layer "B.Cu")
		(net "FAN_3_TEMP")
	)
	(segment
		(start 41.25468 -64.437006)
		(end 42.27068 -64.437006)
		(width 0.2794)
		(layer "B.Cu")
		(net "FAN_3_TEMP")
	)
	(segment
		(start 39.117778 -61.345064)
		(end 39.117778 -61.913262)
		(width 0.1016)
		(layer "B.Cu")
		(net "FAN_3_TEMP")
	)
	(segment
		(start 41.25468 -64.11468)
		(end 41.25468 -64.437006)
		(width 0.2794)
		(layer "B.Cu")
		(net "FAN_3_TEMP")
	)
	(segment
		(start 2.01295 -176.778412)
		(end 2.01295 -170.072304)
		(width 0.2794)
		(layer "F.Cu")
		(net "FAN_4_PRSNT_BUF_N")
	)
	(segment
		(start 5.987542 -178.983894)
		(end 5.679186 -178.675538)
		(width 0.2794)
		(layer "F.Cu")
		(net "FAN_4_PRSNT_BUF_N")
	)
	(segment
		(start 2.01295 -170.072304)
		(end 2.794254 -169.291)
		(width 0.2794)
		(layer "F.Cu")
		(net "FAN_4_PRSNT_BUF_N")
	)
	(segment
		(start 3.79095 -169.291)
		(end 3.79095 -168.402)
		(width 0.2794)
		(layer "F.Cu")
		(net "FAN_4_PRSNT_BUF_N")
	)
	(segment
		(start 3.910076 -178.675538)
		(end 2.01295 -176.778412)
		(width 0.2794)
		(layer "F.Cu")
		(net "FAN_4_PRSNT_BUF_N")
	)
	(segment
		(start 7.366 -178.983894)
		(end 5.987542 -178.983894)
		(width 0.2794)
		(layer "F.Cu")
		(net "FAN_4_PRSNT_BUF_N")
	)
	(segment
		(start 2.794254 -169.291)
		(end 3.79095 -169.291)
		(width 0.2794)
		(layer "F.Cu")
		(net "FAN_4_PRSNT_BUF_N")
	)
	(segment
		(start 5.679186 -178.675538)
		(end 3.910076 -178.675538)
		(width 0.2794)
		(layer "F.Cu")
		(net "FAN_4_PRSNT_BUF_N")
	)
	(via
		(at 2.667 -69.723)
		(size 0.762)
		(drill 0.254)
		(layers "F.Cu" "B.Cu")
		(net "FAN_4_PRSNT_BUF_N")
	)
	(via
		(at 3.79095 -168.402)
		(size 0.508)
		(drill 0.254)
		(layers "F.Cu" "B.Cu")
		(net "FAN_4_PRSNT_BUF_N")
	)
	(segment
		(start 3.81 -69.342)
		(end 3.81 -68.844922)
		(width 0.2794)
		(layer "B.Cu")
		(net "FAN_4_PRSNT_BUF_N")
	)
	(segment
		(start 2.667 -69.723)
		(end 3.429 -69.723)
		(width 0.2794)
		(layer "B.Cu")
		(net "FAN_4_PRSNT_BUF_N")
	)
	(segment
		(start 3.429 -69.723)
		(end 3.81 -69.342)
		(width 0.2794)
		(layer "B.Cu")
		(net "FAN_4_PRSNT_BUF_N")
	)
	(segment
		(start 1.397 -70.993)
		(end 1.397 -160.401)
		(width 0.2286)
		(layer "In2.Cu")
		(net "FAN_4_PRSNT_BUF_N")
	)
	(segment
		(start 3.83286 -162.83686)
		(end 3.83286 -168.36009)
		(width 0.2286)
		(layer "In2.Cu")
		(net "FAN_4_PRSNT_BUF_N")
	)
	(segment
		(start 1.397 -160.401)
		(end 3.83286 -162.83686)
		(width 0.2286)
		(layer "In2.Cu")
		(net "FAN_4_PRSNT_BUF_N")
	)
	(segment
		(start 3.83286 -168.36009)
		(end 3.79095 -168.402)
		(width 0.2286)
		(layer "In2.Cu")
		(net "FAN_4_PRSNT_BUF_N")
	)
	(segment
		(start 2.667 -69.723)
		(end 1.397 -70.993)
		(width 0.2286)
		(layer "In2.Cu")
		(net "FAN_4_PRSNT_BUF_N")
	)
	(via
		(at 37.117782 -63.14694)
		(size 0.6604)
		(drill 0.3302)
		(layers "F.Cu" "B.Cu")
		(net "FAN_3_CLREF")
	)
	(segment
		(start 37.117782 -63.14694)
		(end 37.117782 -62.60084)
		(width 0.2794)
		(layer "B.Cu")
		(net "FAN_3_CLREF")
	)
	(segment
		(start 37.465 -64.437006)
		(end 36.449 -64.437006)
		(width 0.2794)
		(layer "B.Cu")
		(net "FAN_3_CLREF")
	)
	(segment
		(start 37.1348 -63.77686)
		(end 37.1348 -63.163958)
		(width 0.2794)
		(layer "B.Cu")
		(net "FAN_3_CLREF")
	)
	(segment
		(start 37.465 -64.437006)
		(end 37.465 -64.10706)
		(width 0.2794)
		(layer "B.Cu")
		(net "FAN_3_CLREF")
	)
	(segment
		(start 37.1348 -63.163958)
		(end 37.117782 -63.14694)
		(width 0.2794)
		(layer "B.Cu")
		(net "FAN_3_CLREF")
	)
	(segment
		(start 37.117782 -62.60084)
		(end 37.117782 -61.345064)
		(width 0.1016)
		(layer "B.Cu")
		(net "FAN_3_CLREF")
	)
	(segment
		(start 37.465 -64.10706)
		(end 37.1348 -63.77686)
		(width 0.2794)
		(layer "B.Cu")
		(net "FAN_3_CLREF")
	)
	(via
		(at 35.78098 -63.26886)
		(size 0.6604)
		(drill 0.3302)
		(layers "F.Cu" "B.Cu")
		(net "FAN_3_TIMER")
	)
	(segment
		(start 36.542472 -62.873128)
		(end 36.20008 -63.21552)
		(width 0.2794)
		(layer "B.Cu")
		(net "FAN_3_TIMER")
	)
	(segment
		(start 36.20008 -63.21552)
		(end 35.83432 -63.21552)
		(width 0.2794)
		(layer "B.Cu")
		(net "FAN_3_TIMER")
	)
	(segment
		(start 36.717732 -61.345064)
		(end 36.717732 -62.450218)
		(width 0.1016)
		(layer "B.Cu")
		(net "FAN_3_TIMER")
	)
	(segment
		(start 35.78098 -63.942214)
		(end 35.78098 -63.26886)
		(width 0.2794)
		(layer "B.Cu")
		(net "FAN_3_TIMER")
	)
	(segment
		(start 35.433 -64.290194)
		(end 35.78098 -63.942214)
		(width 0.2794)
		(layer "B.Cu")
		(net "FAN_3_TIMER")
	)
	(segment
		(start 36.717732 -62.450218)
		(end 36.542472 -62.873128)
		(width 0.1016)
		(layer "B.Cu")
		(net "FAN_3_TIMER")
	)
	(segment
		(start 35.83432 -63.21552)
		(end 35.78098 -63.26886)
		(width 0.2794)
		(layer "B.Cu")
		(net "FAN_3_TIMER")
	)
	(segment
		(start 35.433 -64.437006)
		(end 35.433 -64.290194)
		(width 0.2794)
		(layer "B.Cu")
		(net "FAN_3_TIMER")
	)
	(segment
		(start 4.837938 -176.922938)
		(end 6.405372 -176.922938)
		(width 0.2794)
		(layer "F.Cu")
		(net "FAN_7_PRSNT_BUF_N")
	)
	(segment
		(start 6.405372 -176.922938)
		(end 6.51637 -177.033936)
		(width 0.2794)
		(layer "F.Cu")
		(net "FAN_7_PRSNT_BUF_N")
	)
	(segment
		(start 3.79095 -174.244)
		(end 3.79095 -175.26)
		(width 0.2794)
		(layer "F.Cu")
		(net "FAN_7_PRSNT_BUF_N")
	)
	(segment
		(start 3.79095 -175.26)
		(end 3.79095 -175.87595)
		(width 0.2794)
		(layer "F.Cu")
		(net "FAN_7_PRSNT_BUF_N")
	)
	(segment
		(start 6.51637 -177.033936)
		(end 7.366 -177.033936)
		(width 0.2794)
		(layer "F.Cu")
		(net "FAN_7_PRSNT_BUF_N")
	)
	(segment
		(start 3.79095 -175.87595)
		(end 4.837938 -176.922938)
		(width 0.2794)
		(layer "F.Cu")
		(net "FAN_7_PRSNT_BUF_N")
	)
	(via
		(at 17.729708 -255.574292)
		(size 0.508)
		(drill 0.254)
		(layers "F.Cu" "B.Cu")
		(net "FAN_7_PRSNT_BUF_N")
	)
	(via
		(at 3.79095 -175.26)
		(size 0.508)
		(drill 0.254)
		(layers "F.Cu" "B.Cu")
		(net "FAN_7_PRSNT_BUF_N")
	)
	(segment
		(start 17.033494 -255.294892)
		(end 17.312894 -255.574292)
		(width 0.2794)
		(layer "B.Cu")
		(net "FAN_7_PRSNT_BUF_N")
	)
	(segment
		(start 17.312894 -255.574292)
		(end 17.729708 -255.574292)
		(width 0.2794)
		(layer "B.Cu")
		(net "FAN_7_PRSNT_BUF_N")
	)
	(segment
		(start 17.033494 -254.878078)
		(end 17.033494 -255.294892)
		(width 0.2794)
		(layer "B.Cu")
		(net "FAN_7_PRSNT_BUF_N")
	)
	(segment
		(start 4.318 -250.05538)
		(end 4.318 -251.661422)
		(width 0.2286)
		(layer "In2.Cu")
		(net "FAN_7_PRSNT_BUF_N")
	)
	(segment
		(start 1.917446 -247.654826)
		(end 4.318 -250.05538)
		(width 0.2286)
		(layer "In2.Cu")
		(net "FAN_7_PRSNT_BUF_N")
	)
	(segment
		(start 16.620236 -254.46482)
		(end 17.729708 -255.574292)
		(width 0.2286)
		(layer "In2.Cu")
		(net "FAN_7_PRSNT_BUF_N")
	)
	(segment
		(start 8.755634 -254.798322)
		(end 9.089136 -254.46482)
		(width 0.2286)
		(layer "In2.Cu")
		(net "FAN_7_PRSNT_BUF_N")
	)
	(segment
		(start 3.79095 -175.26)
		(end 3.40995 -175.26)
		(width 0.2286)
		(layer "In2.Cu")
		(net "FAN_7_PRSNT_BUF_N")
	)
	(segment
		(start 3.40995 -175.26)
		(end 2.032 -176.63795)
		(width 0.2286)
		(layer "In2.Cu")
		(net "FAN_7_PRSNT_BUF_N")
	)
	(segment
		(start 9.089136 -254.46482)
		(end 16.620236 -254.46482)
		(width 0.2286)
		(layer "In2.Cu")
		(net "FAN_7_PRSNT_BUF_N")
	)
	(segment
		(start 2.722626 -190.59398)
		(end 1.917446 -191.39916)
		(width 0.2286)
		(layer "In2.Cu")
		(net "FAN_7_PRSNT_BUF_N")
	)
	(segment
		(start 2.032 -176.63795)
		(end 2.032 -183.522874)
		(width 0.2286)
		(layer "In2.Cu")
		(net "FAN_7_PRSNT_BUF_N")
	)
	(segment
		(start 2.032 -183.522874)
		(end 2.722626 -184.2135)
		(width 0.2286)
		(layer "In2.Cu")
		(net "FAN_7_PRSNT_BUF_N")
	)
	(segment
		(start 2.722626 -184.2135)
		(end 2.722626 -190.59398)
		(width 0.2286)
		(layer "In2.Cu")
		(net "FAN_7_PRSNT_BUF_N")
	)
	(segment
		(start 4.714494 -252.618494)
		(end 6.894322 -254.798322)
		(width 0.2286)
		(layer "In2.Cu")
		(net "FAN_7_PRSNT_BUF_N")
	)
	(segment
		(start 6.894322 -254.798322)
		(end 8.755634 -254.798322)
		(width 0.2286)
		(layer "In2.Cu")
		(net "FAN_7_PRSNT_BUF_N")
	)
	(segment
		(start 4.318 -251.661422)
		(end 4.714494 -252.618494)
		(width 0.2286)
		(layer "In2.Cu")
		(net "FAN_7_PRSNT_BUF_N")
	)
	(segment
		(start 1.917446 -191.39916)
		(end 1.917446 -247.654826)
		(width 0.2286)
		(layer "In2.Cu")
		(net "FAN_7_PRSNT_BUF_N")
	)
	(via
		(at 39.492428 -63.176912)
		(size 0.6604)
		(drill 0.3302)
		(layers "F.Cu" "B.Cu")
		(net "FAN_3_P5V")
	)
	(segment
		(start 39.402766 -63.149734)
		(end 38.717728 -61.868304)
		(width 0.1016)
		(layer "B.Cu")
		(net "FAN_3_P5V")
	)
	(segment
		(start 38.717728 -61.868304)
		(end 38.717728 -61.345064)
		(width 0.1016)
		(layer "B.Cu")
		(net "FAN_3_P5V")
	)
	(segment
		(start 40.23868 -63.923164)
		(end 40.23868 -64.437006)
		(width 0.2794)
		(layer "B.Cu")
		(net "FAN_3_P5V")
	)
	(segment
		(start 39.492428 -63.176912)
		(end 40.23868 -63.923164)
		(width 0.2794)
		(layer "B.Cu")
		(net "FAN_3_P5V")
	)
	(segment
		(start 39.492428 -63.176912)
		(end 39.402766 -63.149734)
		(width 0.1016)
		(layer "B.Cu")
		(net "FAN_3_P5V")
	)
	(segment
		(start 38.100254 -64.262)
		(end 37.10305 -64.262)
		(width 0.2794)
		(layer "F.Cu")
		(net "FAN_3_P3V_R")
	)
	(segment
		(start 37.10305 -65.278)
		(end 37.10305 -64.262)
		(width 0.2794)
		(layer "F.Cu")
		(net "FAN_3_P3V_R")
	)
	(segment
		(start 38.735 -63.627254)
		(end 38.100254 -64.262)
		(width 0.2794)
		(layer "F.Cu")
		(net "FAN_3_P3V_R")
	)
	(segment
		(start 38.735 -63.373254)
		(end 38.735 -63.627254)
		(width 0.2794)
		(layer "F.Cu")
		(net "FAN_3_P3V_R")
	)
	(via
		(at 38.735 -63.373254)
		(size 0.762)
		(drill 0.254)
		(layers "F.Cu" "B.Cu")
		(net "FAN_3_P3V_R")
	)
	(segment
		(start 38.735 -63.373254)
		(end 38.735 -62.744604)
		(width 0.1016)
		(layer "B.Cu")
		(net "FAN_3_P3V_R")
	)
	(segment
		(start 39.116 -64.437006)
		(end 39.116 -63.754254)
		(width 0.2794)
		(layer "B.Cu")
		(net "FAN_3_P3V_R")
	)
	(segment
		(start 39.116 -63.754254)
		(end 38.735 -63.373254)
		(width 0.2794)
		(layer "B.Cu")
		(net "FAN_3_P3V_R")
	)
	(segment
		(start 38.317678 -61.736732)
		(end 38.317678 -61.345064)
		(width 0.1016)
		(layer "B.Cu")
		(net "FAN_3_P3V_R")
	)
	(segment
		(start 38.735 -62.744604)
		(end 38.317678 -61.736732)
		(width 0.1016)
		(layer "B.Cu")
		(net "FAN_3_P3V_R")
	)
	(segment
		(start 36.2839 -65.29705)
		(end 36.30295 -65.278)
		(width 0.2794)
		(layer "F.Cu")
		(net "FAN_3_FAULT_R")
	)
	(segment
		(start 35.306 -65.29705)
		(end 36.2839 -65.29705)
		(width 0.2794)
		(layer "F.Cu")
		(net "FAN_3_FAULT_R")
	)
	(segment
		(start 2.59715 -176.53635)
		(end 4.152138 -178.091338)
		(width 0.2794)
		(layer "F.Cu")
		(net "FAN_5_PRSNT_BUF_N")
	)
	(segment
		(start 2.59715 -172.0088)
		(end 2.59715 -176.53635)
		(width 0.2794)
		(layer "F.Cu")
		(net "FAN_5_PRSNT_BUF_N")
	)
	(segment
		(start 5.921248 -178.091338)
		(end 6.163818 -178.333908)
		(width 0.2794)
		(layer "F.Cu")
		(net "FAN_5_PRSNT_BUF_N")
	)
	(segment
		(start 3.79095 -169.926)
		(end 3.79095 -170.815)
		(width 0.2794)
		(layer "F.Cu")
		(net "FAN_5_PRSNT_BUF_N")
	)
	(segment
		(start 4.152138 -178.091338)
		(end 5.921248 -178.091338)
		(width 0.2794)
		(layer "F.Cu")
		(net "FAN_5_PRSNT_BUF_N")
	)
	(segment
		(start 6.163818 -178.333908)
		(end 7.366 -178.333908)
		(width 0.2794)
		(layer "F.Cu")
		(net "FAN_5_PRSNT_BUF_N")
	)
	(segment
		(start 3.79095 -170.815)
		(end 2.59715 -172.0088)
		(width 0.2794)
		(layer "F.Cu")
		(net "FAN_5_PRSNT_BUF_N")
	)
	(via
		(at 3.79095 -169.926)
		(size 0.508)
		(drill 0.254)
		(layers "F.Cu" "B.Cu")
		(net "FAN_5_PRSNT_BUF_N")
	)
	(via
		(at 16.906494 -69.59219)
		(size 0.508)
		(drill 0.254)
		(layers "F.Cu" "B.Cu")
		(net "FAN_5_PRSNT_BUF_N")
	)
	(segment
		(start 16.906494 -70.27799)
		(end 16.906494 -69.59219)
		(width 0.2794)
		(layer "B.Cu")
		(net "FAN_5_PRSNT_BUF_N")
	)
	(segment
		(start 7.994142 -70.097142)
		(end 8.769858 -70.097142)
		(width 0.2286)
		(layer "In2.Cu")
		(net "FAN_5_PRSNT_BUF_N")
	)
	(segment
		(start 10.762488 -68.104512)
		(end 12.109704 -68.104512)
		(width 0.2286)
		(layer "In2.Cu")
		(net "FAN_5_PRSNT_BUF_N")
	)
	(segment
		(start 4.36626 -162.60064)
		(end 1.9304 -160.16478)
		(width 0.2286)
		(layer "In2.Cu")
		(net "FAN_5_PRSNT_BUF_N")
	)
	(segment
		(start 3.741928 -69.469)
		(end 7.366 -69.469)
		(width 0.2286)
		(layer "In2.Cu")
		(net "FAN_5_PRSNT_BUF_N")
	)
	(segment
		(start 1.9304 -160.16478)
		(end 1.9304 -71.280528)
		(width 0.2286)
		(layer "In2.Cu")
		(net "FAN_5_PRSNT_BUF_N")
	)
	(segment
		(start 12.109704 -68.104512)
		(end 13.855192 -69.85)
		(width 0.2286)
		(layer "In2.Cu")
		(net "FAN_5_PRSNT_BUF_N")
	)
	(segment
		(start 4.36626 -169.35069)
		(end 4.36626 -162.60064)
		(width 0.2286)
		(layer "In2.Cu")
		(net "FAN_5_PRSNT_BUF_N")
	)
	(segment
		(start 13.855192 -69.85)
		(end 16.648684 -69.85)
		(width 0.2286)
		(layer "In2.Cu")
		(net "FAN_5_PRSNT_BUF_N")
	)
	(segment
		(start 7.366 -69.469)
		(end 7.994142 -70.097142)
		(width 0.2286)
		(layer "In2.Cu")
		(net "FAN_5_PRSNT_BUF_N")
	)
	(segment
		(start 3.79095 -169.926)
		(end 4.36626 -169.35069)
		(width 0.2286)
		(layer "In2.Cu")
		(net "FAN_5_PRSNT_BUF_N")
	)
	(segment
		(start 8.769858 -70.097142)
		(end 10.762488 -68.104512)
		(width 0.2286)
		(layer "In2.Cu")
		(net "FAN_5_PRSNT_BUF_N")
	)
	(segment
		(start 1.9304 -71.280528)
		(end 3.741928 -69.469)
		(width 0.2286)
		(layer "In2.Cu")
		(net "FAN_5_PRSNT_BUF_N")
	)
	(segment
		(start 16.648684 -69.85)
		(end 16.906494 -69.59219)
		(width 0.2286)
		(layer "In2.Cu")
		(net "FAN_5_PRSNT_BUF_N")
	)
	(segment
		(start 35.17646 -63.93688)
		(end 34.306002 -63.93688)
		(width 0.2794)
		(layer "F.Cu")
		(net "FAN_3_FAULT")
	)
	(segment
		(start 34.026602 -64.21628)
		(end 34.026602 -64.996568)
		(width 0.2794)
		(layer "F.Cu")
		(net "FAN_3_FAULT")
	)
	(segment
		(start 35.23996 -64.49695)
		(end 34.740342 -64.996568)
		(width 0.2794)
		(layer "F.Cu")
		(net "FAN_3_FAULT")
	)
	(segment
		(start 35.6997 -62.906148)
		(end 35.6997 -63.41364)
		(width 0.2794)
		(layer "F.Cu")
		(net "FAN_3_FAULT")
	)
	(segment
		(start 35.306 -64.49695)
		(end 35.23996 -64.49695)
		(width 0.2794)
		(layer "F.Cu")
		(net "FAN_3_FAULT")
	)
	(segment
		(start 34.740342 -64.996568)
		(end 34.026602 -64.996568)
		(width 0.2794)
		(layer "F.Cu")
		(net "FAN_3_FAULT")
	)
	(segment
		(start 36.007294 -62.598554)
		(end 35.6997 -62.906148)
		(width 0.2794)
		(layer "F.Cu")
		(net "FAN_3_FAULT")
	)
	(segment
		(start 34.306002 -63.93688)
		(end 34.026602 -64.21628)
		(width 0.2794)
		(layer "F.Cu")
		(net "FAN_3_FAULT")
	)
	(segment
		(start 35.6997 -63.41364)
		(end 35.17646 -63.93688)
		(width 0.2794)
		(layer "F.Cu")
		(net "FAN_3_FAULT")
	)
	(segment
		(start 36.04006 -62.598554)
		(end 36.007294 -62.598554)
		(width 0.2794)
		(layer "F.Cu")
		(net "FAN_3_FAULT")
	)
	(via
		(at 34.026602 -64.996568)
		(size 0.762)
		(drill 0.381)
		(layers "F.Cu" "B.Cu")
		(net "FAN_3_FAULT")
	)
	(via
		(at 36.04006 -62.598554)
		(size 0.508)
		(drill 0.254)
		(layers "F.Cu" "B.Cu")
		(net "FAN_3_FAULT")
	)
	(segment
		(start 36.317682 -61.928248)
		(end 36.317682 -61.345064)
		(width 0.1016)
		(layer "B.Cu")
		(net "FAN_3_FAULT")
	)
	(segment
		(start 36.04006 -62.598554)
		(end 36.317682 -61.928248)
		(width 0.1016)
		(layer "B.Cu")
		(net "FAN_3_FAULT")
	)
	(segment
		(start 3.18135 -176.282096)
		(end 4.406392 -177.507138)
		(width 0.2794)
		(layer "F.Cu")
		(net "FAN_6_PRSNT_BUF_N")
	)
	(segment
		(start 3.18135 -173.482)
		(end 3.18135 -176.282096)
		(width 0.2794)
		(layer "F.Cu")
		(net "FAN_6_PRSNT_BUF_N")
	)
	(segment
		(start 3.79095 -172.847)
		(end 3.79095 -172.8724)
		(width 0.2794)
		(layer "F.Cu")
		(net "FAN_6_PRSNT_BUF_N")
	)
	(segment
		(start 3.175 -172.466)
		(end 3.38455 -172.466)
		(width 0.2794)
		(layer "F.Cu")
		(net "FAN_6_PRSNT_BUF_N")
	)
	(segment
		(start 4.406392 -177.507138)
		(end 6.16331 -177.507138)
		(width 0.2794)
		(layer "F.Cu")
		(net "FAN_6_PRSNT_BUF_N")
	)
	(segment
		(start 6.16331 -177.507138)
		(end 6.340094 -177.683922)
		(width 0.2794)
		(layer "F.Cu")
		(net "FAN_6_PRSNT_BUF_N")
	)
	(segment
		(start 3.38455 -172.466)
		(end 3.79095 -172.8724)
		(width 0.2794)
		(layer "F.Cu")
		(net "FAN_6_PRSNT_BUF_N")
	)
	(segment
		(start 6.340094 -177.683922)
		(end 7.366 -177.683922)
		(width 0.2794)
		(layer "F.Cu")
		(net "FAN_6_PRSNT_BUF_N")
	)
	(segment
		(start 3.79095 -172.8724)
		(end 3.18135 -173.482)
		(width 0.2794)
		(layer "F.Cu")
		(net "FAN_6_PRSNT_BUF_N")
	)
	(via
		(at 3.175 -172.466)
		(size 0.508)
		(drill 0.254)
		(layers "F.Cu" "B.Cu")
		(net "FAN_6_PRSNT_BUF_N")
	)
	(via
		(at 3.81 -254.3302)
		(size 0.508)
		(drill 0.254)
		(layers "F.Cu" "B.Cu")
		(net "FAN_6_PRSNT_BUF_N")
	)
	(segment
		(start 3.81 -253.629922)
		(end 3.81 -254.3302)
		(width 0.2794)
		(layer "B.Cu")
		(net "FAN_6_PRSNT_BUF_N")
	)
	(segment
		(start 1.384046 -247.891046)
		(end 1.384046 -191.17818)
		(width 0.2286)
		(layer "In2.Cu")
		(net "FAN_6_PRSNT_BUF_N")
	)
	(segment
		(start 2.189226 -184.43448)
		(end 1.397 -183.642254)
		(width 0.2286)
		(layer "In2.Cu")
		(net "FAN_6_PRSNT_BUF_N")
	)
	(segment
		(start 2.189226 -190.373)
		(end 2.189226 -184.43448)
		(width 0.2286)
		(layer "In2.Cu")
		(net "FAN_6_PRSNT_BUF_N")
	)
	(segment
		(start 3.236214 -253.121414)
		(end 3.236214 -249.743214)
		(width 0.2286)
		(layer "In2.Cu")
		(net "FAN_6_PRSNT_BUF_N")
	)
	(segment
		(start 3.236214 -249.743214)
		(end 1.384046 -247.891046)
		(width 0.2286)
		(layer "In2.Cu")
		(net "FAN_6_PRSNT_BUF_N")
	)
	(segment
		(start 3.81 -254.3302)
		(end 3.81 -253.6952)
		(width 0.2286)
		(layer "In2.Cu")
		(net "FAN_6_PRSNT_BUF_N")
	)
	(segment
		(start 3.175 -173.8249)
		(end 3.175 -172.466)
		(width 0.2286)
		(layer "In2.Cu")
		(net "FAN_6_PRSNT_BUF_N")
	)
	(segment
		(start 3.81 -253.6952)
		(end 3.236214 -253.121414)
		(width 0.2286)
		(layer "In2.Cu")
		(net "FAN_6_PRSNT_BUF_N")
	)
	(segment
		(start 1.384046 -191.17818)
		(end 2.189226 -190.373)
		(width 0.2286)
		(layer "In2.Cu")
		(net "FAN_6_PRSNT_BUF_N")
	)
	(segment
		(start 1.397 -175.6029)
		(end 3.175 -173.8249)
		(width 0.2286)
		(layer "In2.Cu")
		(net "FAN_6_PRSNT_BUF_N")
	)
	(segment
		(start 1.397 -183.642254)
		(end 1.397 -175.6029)
		(width 0.2286)
		(layer "In2.Cu")
		(net "FAN_6_PRSNT_BUF_N")
	)
	(segment
		(start 32.897064 -199.15505)
		(end 33.1978 -199.455786)
		(width 0.2794)
		(layer "F.Cu")
		(net "FAN_1_OK_R_LED")
	)
	(segment
		(start 33.1978 -199.455786)
		(end 33.8709 -199.455786)
		(width 0.2794)
		(layer "F.Cu")
		(net "FAN_1_OK_R_LED")
	)
	(segment
		(start 32.258 -199.15505)
		(end 32.897064 -199.15505)
		(width 0.2794)
		(layer "F.Cu")
		(net "FAN_1_OK_R_LED")
	)
	(segment
		(start 32.258 -199.39)
		(end 32.258 -199.15505)
		(width 0.2794)
		(layer "F.Cu")
		(net "FAN_1_OK_R_LED")
	)
	(segment
		(start 43.96105 -171.831)
		(end 45.466 -171.831)
		(width 0.2794)
		(layer "F.Cu")
		(net "FAN_1_OK_R_LED")
	)
	(segment
		(start 32.639 -199.771)
		(end 32.258 -199.39)
		(width 0.2794)
		(layer "F.Cu")
		(net "FAN_1_OK_R_LED")
	)
	(via
		(at 32.639 -199.771)
		(size 0.508)
		(drill 0.254)
		(layers "F.Cu" "B.Cu")
		(net "FAN_1_OK_R_LED")
	)
	(via
		(at 45.466 -171.831)
		(size 0.762)
		(drill 0.254)
		(layers "F.Cu" "B.Cu")
		(net "FAN_1_OK_R_LED")
	)
	(segment
		(start 45.466 -171.831)
		(end 46.3804 -170.9166)
		(width 0.2286)
		(layer "In2.Cu")
		(net "FAN_1_OK_R_LED")
	)
	(segment
		(start 46.3804 -170.9166)
		(end 46.3804 -165.5064)
		(width 0.2286)
		(layer "In2.Cu")
		(net "FAN_1_OK_R_LED")
	)
	(segment
		(start 43.598084 -164.248338)
		(end 41.012618 -166.833804)
		(width 0.2286)
		(layer "In2.Cu")
		(net "FAN_1_OK_R_LED")
	)
	(segment
		(start 41.148 -187.71108)
		(end 31.132018 -197.727062)
		(width 0.2286)
		(layer "In2.Cu")
		(net "FAN_1_OK_R_LED")
	)
	(segment
		(start 45.122338 -164.248338)
		(end 43.598084 -164.248338)
		(width 0.2286)
		(layer "In2.Cu")
		(net "FAN_1_OK_R_LED")
	)
	(segment
		(start 41.012618 -174.997618)
		(end 41.148 -175.133)
		(width 0.2286)
		(layer "In2.Cu")
		(net "FAN_1_OK_R_LED")
	)
	(segment
		(start 31.132018 -199.259952)
		(end 31.643066 -199.771)
		(width 0.2286)
		(layer "In2.Cu")
		(net "FAN_1_OK_R_LED")
	)
	(segment
		(start 31.643066 -199.771)
		(end 32.639 -199.771)
		(width 0.2286)
		(layer "In2.Cu")
		(net "FAN_1_OK_R_LED")
	)
	(segment
		(start 41.148 -175.133)
		(end 41.148 -187.71108)
		(width 0.2286)
		(layer "In2.Cu")
		(net "FAN_1_OK_R_LED")
	)
	(segment
		(start 46.3804 -165.5064)
		(end 45.122338 -164.248338)
		(width 0.2286)
		(layer "In2.Cu")
		(net "FAN_1_OK_R_LED")
	)
	(segment
		(start 31.132018 -197.727062)
		(end 31.132018 -199.259952)
		(width 0.2286)
		(layer "In2.Cu")
		(net "FAN_1_OK_R_LED")
	)
	(segment
		(start 41.012618 -166.833804)
		(end 41.012618 -174.997618)
		(width 0.2286)
		(layer "In2.Cu")
		(net "FAN_1_OK_R_LED")
	)
	(via
		(at 34.031428 -63.288164)
		(size 0.6604)
		(drill 0.3302)
		(layers "F.Cu" "B.Cu")
		(net "FAN_3_IMON")
	)
	(segment
		(start 34.031428 -63.133732)
		(end 34.877248 -62.287912)
		(width 0.2794)
		(layer "B.Cu")
		(net "FAN_3_IMON")
	)
	(segment
		(start 33.7439 -64.005714)
		(end 33.83026 -63.79718)
		(width 0.2794)
		(layer "B.Cu")
		(net "FAN_3_IMON")
	)
	(segment
		(start 33.83026 -63.489332)
		(end 34.031428 -63.288164)
		(width 0.2794)
		(layer "B.Cu")
		(net "FAN_3_IMON")
	)
	(segment
		(start 35.517582 -61.80201)
		(end 35.517582 -61.345064)
		(width 0.1016)
		(layer "B.Cu")
		(net "FAN_3_IMON")
	)
	(segment
		(start 33.83026 -63.79718)
		(end 33.83026 -63.489332)
		(width 0.2794)
		(layer "B.Cu")
		(net "FAN_3_IMON")
	)
	(segment
		(start 33.463738 -64.285876)
		(end 33.7439 -64.005714)
		(width 0.2794)
		(layer "B.Cu")
		(net "FAN_3_IMON")
	)
	(segment
		(start 33.401 -64.437006)
		(end 33.463738 -64.285876)
		(width 0.2794)
		(layer "B.Cu")
		(net "FAN_3_IMON")
	)
	(segment
		(start 35.03168 -62.287912)
		(end 35.517582 -61.80201)
		(width 0.1016)
		(layer "B.Cu")
		(net "FAN_3_IMON")
	)
	(segment
		(start 34.877248 -62.287912)
		(end 35.03168 -62.287912)
		(width 0.2794)
		(layer "B.Cu")
		(net "FAN_3_IMON")
	)
	(segment
		(start 34.031428 -63.288164)
		(end 34.031428 -63.133732)
		(width 0.2794)
		(layer "B.Cu")
		(net "FAN_3_IMON")
	)
	(segment
		(start 32.939736 -291.73805)
		(end 32.9438 -291.733986)
		(width 0.2794)
		(layer "F.Cu")
		(net "FAN_0_OK_R_LED")
	)
	(segment
		(start 36.9824 -214.184992)
		(end 36.9824 -212.8774)
		(width 0.2794)
		(layer "F.Cu")
		(net "FAN_0_OK_R_LED")
	)
	(segment
		(start 43.96105 -169.799)
		(end 44.57065 -169.799)
		(width 0.2794)
		(layer "F.Cu")
		(net "FAN_0_OK_R_LED")
	)
	(segment
		(start 30.607 -214.63)
		(end 36.537392 -214.63)
		(width 0.2794)
		(layer "F.Cu")
		(net "FAN_0_OK_R_LED")
	)
	(segment
		(start 31.623 -291.73805)
		(end 32.258 -291.73805)
		(width 0.2794)
		(layer "F.Cu")
		(net "FAN_0_OK_R_LED")
	)
	(segment
		(start 32.258 -291.73805)
		(end 32.939736 -291.73805)
		(width 0.2794)
		(layer "F.Cu")
		(net "FAN_0_OK_R_LED")
	)
	(segment
		(start 36.537392 -214.63)
		(end 36.9824 -214.184992)
		(width 0.2794)
		(layer "F.Cu")
		(net "FAN_0_OK_R_LED")
	)
	(segment
		(start 32.9438 -291.733986)
		(end 33.6169 -291.733986)
		(width 0.2794)
		(layer "F.Cu")
		(net "FAN_0_OK_R_LED")
	)
	(via
		(at 44.57065 -169.799)
		(size 0.508)
		(drill 0.254)
		(layers "F.Cu" "B.Cu")
		(net "FAN_0_OK_R_LED")
	)
	(via
		(at 31.623 -291.73805)
		(size 0.508)
		(drill 0.254)
		(layers "F.Cu" "B.Cu")
		(net "FAN_0_OK_R_LED")
	)
	(via
		(at 36.9824 -212.8774)
		(size 0.508)
		(drill 0.254)
		(layers "F.Cu" "B.Cu")
		(net "FAN_0_OK_R_LED")
	)
	(via
		(at 30.607 -214.63)
		(size 0.508)
		(drill 0.254)
		(layers "F.Cu" "B.Cu")
		(net "FAN_0_OK_R_LED")
	)
	(segment
		(start 20.805648 -244.640862)
		(end 27.1272 -250.962414)
		(width 0.2286)
		(layer "In2.Cu")
		(net "FAN_0_OK_R_LED")
	)
	(segment
		(start 27.77998 -219.075)
		(end 20.805648 -226.049332)
		(width 0.2286)
		(layer "In2.Cu")
		(net "FAN_0_OK_R_LED")
	)
	(segment
		(start 30.607 -218.059)
		(end 29.591 -219.075)
		(width 0.2286)
		(layer "In2.Cu")
		(net "FAN_0_OK_R_LED")
	)
	(segment
		(start 44.577 -190.754)
		(end 44.577 -179.197)
		(width 0.2286)
		(layer "In2.Cu")
		(net "FAN_0_OK_R_LED")
	)
	(segment
		(start 39.402004 -210.523328)
		(end 39.402004 -195.928996)
		(width 0.2286)
		(layer "In2.Cu")
		(net "FAN_0_OK_R_LED")
	)
	(segment
		(start 36.9824 -212.8774)
		(end 37.047932 -212.8774)
		(width 0.2286)
		(layer "In2.Cu")
		(net "FAN_0_OK_R_LED")
	)
	(segment
		(start 29.718 -288.998152)
		(end 31.623 -290.903152)
		(width 0.2286)
		(layer "In2.Cu")
		(net "FAN_0_OK_R_LED")
	)
	(segment
		(start 43.4086 -178.0286)
		(end 43.4086 -170.96105)
		(width 0.2286)
		(layer "In2.Cu")
		(net "FAN_0_OK_R_LED")
	)
	(segment
		(start 29.718 -284.164278)
		(end 29.718 -288.998152)
		(width 0.2286)
		(layer "In2.Cu")
		(net "FAN_0_OK_R_LED")
	)
	(segment
		(start 29.591 -219.075)
		(end 27.77998 -219.075)
		(width 0.2286)
		(layer "In2.Cu")
		(net "FAN_0_OK_R_LED")
	)
	(segment
		(start 37.047932 -212.8774)
		(end 39.402004 -210.523328)
		(width 0.2286)
		(layer "In2.Cu")
		(net "FAN_0_OK_R_LED")
	)
	(segment
		(start 44.577 -179.197)
		(end 43.4086 -178.0286)
		(width 0.2286)
		(layer "In2.Cu")
		(net "FAN_0_OK_R_LED")
	)
	(segment
		(start 43.4086 -170.96105)
		(end 44.57065 -169.799)
		(width 0.2286)
		(layer "In2.Cu")
		(net "FAN_0_OK_R_LED")
	)
	(segment
		(start 27.1272 -281.573478)
		(end 29.718 -284.164278)
		(width 0.2286)
		(layer "In2.Cu")
		(net "FAN_0_OK_R_LED")
	)
	(segment
		(start 39.402004 -195.928996)
		(end 44.577 -190.754)
		(width 0.2286)
		(layer "In2.Cu")
		(net "FAN_0_OK_R_LED")
	)
	(segment
		(start 31.623 -290.903152)
		(end 31.623 -291.73805)
		(width 0.2286)
		(layer "In2.Cu")
		(net "FAN_0_OK_R_LED")
	)
	(segment
		(start 27.1272 -250.962414)
		(end 27.1272 -281.573478)
		(width 0.2286)
		(layer "In2.Cu")
		(net "FAN_0_OK_R_LED")
	)
	(segment
		(start 20.805648 -226.049332)
		(end 20.805648 -244.640862)
		(width 0.2286)
		(layer "In2.Cu")
		(net "FAN_0_OK_R_LED")
	)
	(segment
		(start 30.607 -214.63)
		(end 30.607 -218.059)
		(width 0.2286)
		(layer "In2.Cu")
		(net "FAN_0_OK_R_LED")
	)
	(segment
		(start 17.272 -168.656)
		(end 17.779746 -168.656)
		(width 0.2794)
		(layer "F.Cu")
		(net "FAN_4_PRESENT_R_N")
	)
	(segment
		(start 18.30705 -169.183304)
		(end 18.30705 -169.291)
		(width 0.2794)
		(layer "F.Cu")
		(net "FAN_4_PRESENT_R_N")
	)
	(segment
		(start 17.779746 -168.656)
		(end 18.30705 -169.183304)
		(width 0.2794)
		(layer "F.Cu")
		(net "FAN_4_PRESENT_R_N")
	)
	(via
		(at 17.272 -168.656)
		(size 0.508)
		(drill 0.254)
		(layers "F.Cu" "B.Cu")
		(net "FAN_4_PRESENT_R_N")
	)
	(segment
		(start 19.812 -97.5614)
		(end 11.4935 -105.8799)
		(width 0.2286)
		(layer "In2.Cu")
		(net "FAN_4_PRESENT_R_N")
	)
	(segment
		(start 12.606528 -163.558728)
		(end 13.210794 -164.162994)
		(width 0.2286)
		(layer "In2.Cu")
		(net "FAN_4_PRESENT_R_N")
	)
	(segment
		(start 14.148816 -167.000428)
		(end 14.702028 -167.000428)
		(width 0.2286)
		(layer "In2.Cu")
		(net "FAN_4_PRESENT_R_N")
	)
	(segment
		(start 13.210794 -166.062406)
		(end 14.148816 -167.000428)
		(width 0.2286)
		(layer "In2.Cu")
		(net "FAN_4_PRESENT_R_N")
	)
	(segment
		(start 9.228328 -163.558728)
		(end 12.606528 -163.558728)
		(width 0.2286)
		(layer "In2.Cu")
		(net "FAN_4_PRESENT_R_N")
	)
	(segment
		(start 18.9357 -85.128354)
		(end 19.812 -86.004654)
		(width 0.2286)
		(layer "In2.Cu")
		(net "FAN_4_PRESENT_R_N")
	)
	(segment
		(start 14.823694 -53.144166)
		(end 18.9357 -63.071248)
		(width 0.2286)
		(layer "In2.Cu")
		(net "FAN_4_PRESENT_R_N")
	)
	(segment
		(start 8.821928 -14.409928)
		(end 12.827 -18.415)
		(width 0.2286)
		(layer "In2.Cu")
		(net "FAN_4_PRESENT_R_N")
	)
	(segment
		(start 12.827 -28.846272)
		(end 14.823694 -30.842966)
		(width 0.2286)
		(layer "In2.Cu")
		(net "FAN_4_PRESENT_R_N")
	)
	(segment
		(start 16.3576 -168.656)
		(end 17.272 -168.656)
		(width 0.2286)
		(layer "In2.Cu")
		(net "FAN_4_PRESENT_R_N")
	)
	(segment
		(start 10.61466 -129.5273)
		(end 10.8204 -129.73304)
		(width 0.2286)
		(layer "In2.Cu")
		(net "FAN_4_PRESENT_R_N")
	)
	(segment
		(start 14.823694 -30.842966)
		(end 14.823694 -53.144166)
		(width 0.2286)
		(layer "In2.Cu")
		(net "FAN_4_PRESENT_R_N")
	)
	(segment
		(start 11.4935 -105.8799)
		(end 11.4935 -118.7958)
		(width 0.2286)
		(layer "In2.Cu")
		(net "FAN_4_PRESENT_R_N")
	)
	(segment
		(start 13.210794 -164.162994)
		(end 13.210794 -166.062406)
		(width 0.2286)
		(layer "In2.Cu")
		(net "FAN_4_PRESENT_R_N")
	)
	(segment
		(start 10.8204 -129.73304)
		(end 10.8204 -137.1346)
		(width 0.2286)
		(layer "In2.Cu")
		(net "FAN_4_PRESENT_R_N")
	)
	(segment
		(start 19.812 -86.004654)
		(end 19.812 -97.5614)
		(width 0.2286)
		(layer "In2.Cu")
		(net "FAN_4_PRESENT_R_N")
	)
	(segment
		(start 11.4935 -118.7958)
		(end 10.61466 -119.67464)
		(width 0.2286)
		(layer "In2.Cu")
		(net "FAN_4_PRESENT_R_N")
	)
	(segment
		(start 5.1562 -159.4866)
		(end 9.228328 -163.558728)
		(width 0.2286)
		(layer "In2.Cu")
		(net "FAN_4_PRESENT_R_N")
	)
	(segment
		(start 18.9357 -63.071248)
		(end 18.9357 -85.128354)
		(width 0.2286)
		(layer "In2.Cu")
		(net "FAN_4_PRESENT_R_N")
	)
	(segment
		(start 8.700008 -14.409928)
		(end 8.821928 -14.409928)
		(width 0.2286)
		(layer "In2.Cu")
		(net "FAN_4_PRESENT_R_N")
	)
	(segment
		(start 5.1562 -142.7988)
		(end 5.1562 -159.4866)
		(width 0.2286)
		(layer "In2.Cu")
		(net "FAN_4_PRESENT_R_N")
	)
	(segment
		(start 10.61466 -119.67464)
		(end 10.61466 -129.5273)
		(width 0.2286)
		(layer "In2.Cu")
		(net "FAN_4_PRESENT_R_N")
	)
	(segment
		(start 12.827 -18.415)
		(end 12.827 -28.846272)
		(width 0.2286)
		(layer "In2.Cu")
		(net "FAN_4_PRESENT_R_N")
	)
	(segment
		(start 14.702028 -167.000428)
		(end 16.3576 -168.656)
		(width 0.2286)
		(layer "In2.Cu")
		(net "FAN_4_PRESENT_R_N")
	)
	(segment
		(start 10.8204 -137.1346)
		(end 5.1562 -142.7988)
		(width 0.2286)
		(layer "In2.Cu")
		(net "FAN_4_PRESENT_R_N")
	)
	(segment
		(start 28.55595 -173.609)
		(end 27.686 -173.609)
		(width 0.2794)
		(layer "F.Cu")
		(net "FAN_6_OK_R_LED")
	)
	(segment
		(start 24.033226 -184.225946)
		(end 22.37105 -185.888122)
		(width 0.2794)
		(layer "F.Cu")
		(net "FAN_6_OK_R_LED")
	)
	(segment
		(start 24.033226 -177.261774)
		(end 24.033226 -184.225946)
		(width 0.2794)
		(layer "F.Cu")
		(net "FAN_6_OK_R_LED")
	)
	(segment
		(start 21.082 -205.74)
		(end 20.21205 -206.60995)
		(width 0.2794)
		(layer "F.Cu")
		(net "FAN_6_OK_R_LED")
	)
	(segment
		(start 19.558 -206.60995)
		(end 18.322036 -206.60995)
		(width 0.2794)
		(layer "F.Cu")
		(net "FAN_6_OK_R_LED")
	)
	(segment
		(start 22.37105 -187.4901)
		(end 19.48815 -190.373)
		(width 0.2794)
		(layer "F.Cu")
		(net "FAN_6_OK_R_LED")
	)
	(segment
		(start 18.322036 -206.60995)
		(end 18.1991 -206.487014)
		(width 0.2794)
		(layer "F.Cu")
		(net "FAN_6_OK_R_LED")
	)
	(segment
		(start 27.686 -173.609)
		(end 24.033226 -177.261774)
		(width 0.2794)
		(layer "F.Cu")
		(net "FAN_6_OK_R_LED")
	)
	(segment
		(start 20.21205 -206.60995)
		(end 19.558 -206.60995)
		(width 0.2794)
		(layer "F.Cu")
		(net "FAN_6_OK_R_LED")
	)
	(segment
		(start 22.37105 -185.888122)
		(end 22.37105 -187.4901)
		(width 0.2794)
		(layer "F.Cu")
		(net "FAN_6_OK_R_LED")
	)
	(via
		(at 19.48815 -190.373)
		(size 0.508)
		(drill 0.254)
		(layers "F.Cu" "B.Cu")
		(net "FAN_6_OK_R_LED")
	)
	(via
		(at 21.082 -205.74)
		(size 0.508)
		(drill 0.254)
		(layers "F.Cu" "B.Cu")
		(net "FAN_6_OK_R_LED")
	)
	(segment
		(start 20.0914 -199.3392)
		(end 20.0914 -204.7494)
		(width 0.2286)
		(layer "In2.Cu")
		(net "FAN_6_OK_R_LED")
	)
	(segment
		(start 19.48815 -190.373)
		(end 20.70862 -191.59347)
		(width 0.2286)
		(layer "In2.Cu")
		(net "FAN_6_OK_R_LED")
	)
	(segment
		(start 20.70862 -191.59347)
		(end 20.70862 -198.72198)
		(width 0.2286)
		(layer "In2.Cu")
		(net "FAN_6_OK_R_LED")
	)
	(segment
		(start 20.0914 -204.7494)
		(end 21.082 -205.74)
		(width 0.2286)
		(layer "In2.Cu")
		(net "FAN_6_OK_R_LED")
	)
	(segment
		(start 20.70862 -198.72198)
		(end 20.0914 -199.3392)
		(width 0.2286)
		(layer "In2.Cu")
		(net "FAN_6_OK_R_LED")
	)
	(segment
		(start 33.92805 -176.403)
		(end 33.92805 -175.768)
		(width 0.2794)
		(layer "F.Cu")
		(net "FAN_4_OK_R_LED")
	)
	(segment
		(start 19.308064 -26.274014)
		(end 18.1991 -26.274014)
		(width 0.2794)
		(layer "F.Cu")
		(net "FAN_4_OK_R_LED")
	)
	(segment
		(start 20.193 -26.52395)
		(end 19.558 -26.52395)
		(width 0.2794)
		(layer "F.Cu")
		(net "FAN_4_OK_R_LED")
	)
	(segment
		(start 19.558 -26.52395)
		(end 19.308064 -26.274014)
		(width 0.2794)
		(layer "F.Cu")
		(net "FAN_4_OK_R_LED")
	)
	(via
		(at 33.92805 -175.768)
		(size 0.508)
		(drill 0.254)
		(layers "F.Cu" "B.Cu")
		(net "FAN_4_OK_R_LED")
	)
	(via
		(at 20.193 -26.52395)
		(size 0.508)
		(drill 0.254)
		(layers "F.Cu" "B.Cu")
		(net "FAN_4_OK_R_LED")
	)
	(segment
		(start 22.3774 -34.292286)
		(end 19.088354 -37.581332)
		(width 0.2286)
		(layer "In2.Cu")
		(net "FAN_4_OK_R_LED")
	)
	(segment
		(start 33.274 -141.997938)
		(end 33.274 -144.526254)
		(width 0.2286)
		(layer "In2.Cu")
		(net "FAN_4_OK_R_LED")
	)
	(segment
		(start 19.088354 -37.581332)
		(end 19.088354 -51.986942)
		(width 0.2286)
		(layer "In2.Cu")
		(net "FAN_4_OK_R_LED")
	)
	(segment
		(start 35.5092 -174.187358)
		(end 33.92805 -175.768)
		(width 0.2286)
		(layer "In2.Cu")
		(net "FAN_4_OK_R_LED")
	)
	(segment
		(start 22.3774 -31.80842)
		(end 22.3774 -34.292286)
		(width 0.2286)
		(layer "In2.Cu")
		(net "FAN_4_OK_R_LED")
	)
	(segment
		(start 25.020778 -101.4476)
		(end 25.020778 -114.040412)
		(width 0.2286)
		(layer "In2.Cu")
		(net "FAN_4_OK_R_LED")
	)
	(segment
		(start 35.394138 -127.547116)
		(end 34.50082 -128.440434)
		(width 0.2286)
		(layer "In2.Cu")
		(net "FAN_4_OK_R_LED")
	)
	(segment
		(start 21.4884 -27.84602)
		(end 21.4884 -30.91942)
		(width 0.2286)
		(layer "In2.Cu")
		(net "FAN_4_OK_R_LED")
	)
	(segment
		(start 35.5092 -161.173668)
		(end 35.5092 -174.187358)
		(width 0.2286)
		(layer "In2.Cu")
		(net "FAN_4_OK_R_LED")
	)
	(segment
		(start 20.193 -26.55062)
		(end 21.4884 -27.84602)
		(width 0.2286)
		(layer "In2.Cu")
		(net "FAN_4_OK_R_LED")
	)
	(segment
		(start 34.27095 -158.187136)
		(end 35.5092 -161.173668)
		(width 0.2286)
		(layer "In2.Cu")
		(net "FAN_4_OK_R_LED")
	)
	(segment
		(start 24.131016 -84.395056)
		(end 24.131016 -100.557838)
		(width 0.2286)
		(layer "In2.Cu")
		(net "FAN_4_OK_R_LED")
	)
	(segment
		(start 33.655 -123.571254)
		(end 35.394138 -125.310392)
		(width 0.2286)
		(layer "In2.Cu")
		(net "FAN_4_OK_R_LED")
	)
	(segment
		(start 23.58898 -62.867794)
		(end 23.58898 -83.85302)
		(width 0.2286)
		(layer "In2.Cu")
		(net "FAN_4_OK_R_LED")
	)
	(segment
		(start 33.655 -122.674634)
		(end 33.655 -123.571254)
		(width 0.2286)
		(layer "In2.Cu")
		(net "FAN_4_OK_R_LED")
	)
	(segment
		(start 19.088354 -51.986942)
		(end 23.58898 -62.867794)
		(width 0.2286)
		(layer "In2.Cu")
		(net "FAN_4_OK_R_LED")
	)
	(segment
		(start 34.27095 -158.168594)
		(end 34.27095 -158.187136)
		(width 0.2286)
		(layer "In2.Cu")
		(net "FAN_4_OK_R_LED")
	)
	(segment
		(start 34.50082 -140.771118)
		(end 33.274 -141.997938)
		(width 0.2286)
		(layer "In2.Cu")
		(net "FAN_4_OK_R_LED")
	)
	(segment
		(start 23.58898 -83.85302)
		(end 24.131016 -84.395056)
		(width 0.2286)
		(layer "In2.Cu")
		(net "FAN_4_OK_R_LED")
	)
	(segment
		(start 24.131016 -100.557838)
		(end 25.020778 -101.4476)
		(width 0.2286)
		(layer "In2.Cu")
		(net "FAN_4_OK_R_LED")
	)
	(segment
		(start 34.50082 -128.440434)
		(end 34.50082 -140.771118)
		(width 0.2286)
		(layer "In2.Cu")
		(net "FAN_4_OK_R_LED")
	)
	(segment
		(start 33.274 -144.526254)
		(end 33.909 -145.161254)
		(width 0.2286)
		(layer "In2.Cu")
		(net "FAN_4_OK_R_LED")
	)
	(segment
		(start 21.4884 -30.91942)
		(end 22.3774 -31.80842)
		(width 0.2286)
		(layer "In2.Cu")
		(net "FAN_4_OK_R_LED")
	)
	(segment
		(start 33.909 -145.161254)
		(end 33.909 -157.289754)
		(width 0.2286)
		(layer "In2.Cu")
		(net "FAN_4_OK_R_LED")
	)
	(segment
		(start 25.020778 -114.040412)
		(end 33.655 -122.674634)
		(width 0.2286)
		(layer "In2.Cu")
		(net "FAN_4_OK_R_LED")
	)
	(segment
		(start 20.193 -26.52395)
		(end 20.193 -26.55062)
		(width 0.2286)
		(layer "In2.Cu")
		(net "FAN_4_OK_R_LED")
	)
	(segment
		(start 33.909 -157.289754)
		(end 34.27095 -158.168594)
		(width 0.2286)
		(layer "In2.Cu")
		(net "FAN_4_OK_R_LED")
	)
	(segment
		(start 35.394138 -125.310392)
		(end 35.394138 -127.547116)
		(width 0.2286)
		(layer "In2.Cu")
		(net "FAN_4_OK_R_LED")
	)
	(segment
		(start 33.80105 -16.51)
		(end 33.80105 -15.28445)
		(width 0.2794)
		(layer "F.Cu")
		(net "FAN_3_TACH_OL_R")
	)
	(segment
		(start 35.2298 -14.6558)
		(end 36.35375 -14.6558)
		(width 0.2794)
		(layer "F.Cu")
		(net "FAN_3_TACH_OL_R")
	)
	(segment
		(start 34.8488 -16.51)
		(end 33.80105 -16.51)
		(width 0.2794)
		(layer "F.Cu")
		(net "FAN_3_TACH_OL_R")
	)
	(segment
		(start 33.6296 -15.113)
		(end 34.0868 -14.6558)
		(width 0.2794)
		(layer "F.Cu")
		(net "FAN_3_TACH_OL_R")
	)
	(segment
		(start 35.1028 -16.256)
		(end 34.8488 -16.51)
		(width 0.2794)
		(layer "F.Cu")
		(net "FAN_3_TACH_OL_R")
	)
	(segment
		(start 36.35375 -14.6558)
		(end 36.449 -14.75105)
		(width 0.2794)
		(layer "F.Cu")
		(net "FAN_3_TACH_OL_R")
	)
	(segment
		(start 33.80105 -15.28445)
		(end 33.6296 -15.113)
		(width 0.2794)
		(layer "F.Cu")
		(net "FAN_3_TACH_OL_R")
	)
	(segment
		(start 34.0868 -14.6558)
		(end 35.2298 -14.6558)
		(width 0.2794)
		(layer "F.Cu")
		(net "FAN_3_TACH_OL_R")
	)
	(via
		(at 35.2298 -14.6558)
		(size 0.762)
		(drill 0.381)
		(layers "F.Cu" "B.Cu")
		(net "FAN_3_TACH_OL_R")
	)
	(segment
		(start 44.577 -176.276)
		(end 45.466 -176.276)
		(width 0.2794)
		(layer "F.Cu")
		(net "FAN_3_OK_R_LED")
	)
	(segment
		(start 32.258 -19.685)
		(end 32.258 -18.94205)
		(width 0.2794)
		(layer "F.Cu")
		(net "FAN_3_OK_R_LED")
	)
	(segment
		(start 32.258 -18.94205)
		(end 32.507936 -19.191986)
		(width 0.2794)
		(layer "F.Cu")
		(net "FAN_3_OK_R_LED")
	)
	(segment
		(start 43.96105 -175.895)
		(end 44.196 -175.895)
		(width 0.2794)
		(layer "F.Cu")
		(net "FAN_3_OK_R_LED")
	)
	(segment
		(start 44.196 -175.895)
		(end 44.577 -176.276)
		(width 0.2794)
		(layer "F.Cu")
		(net "FAN_3_OK_R_LED")
	)
	(segment
		(start 32.507936 -19.191986)
		(end 33.6169 -19.191986)
		(width 0.2794)
		(layer "F.Cu")
		(net "FAN_3_OK_R_LED")
	)
	(via
		(at 45.466 -176.276)
		(size 0.508)
		(drill 0.254)
		(layers "F.Cu" "B.Cu")
		(net "FAN_3_OK_R_LED")
	)
	(via
		(at 32.258 -19.685)
		(size 0.508)
		(drill 0.254)
		(layers "F.Cu" "B.Cu")
		(net "FAN_3_OK_R_LED")
	)
	(segment
		(start 37.5666 -25.755346)
		(end 37.5666 -33.945576)
		(width 0.2286)
		(layer "In2.Cu")
		(net "FAN_3_OK_R_LED")
	)
	(segment
		(start 45.67428 -123.23572)
		(end 45.67428 -134.50062)
		(width 0.2286)
		(layer "In2.Cu")
		(net "FAN_3_OK_R_LED")
	)
	(segment
		(start 30.6324 -81.716372)
		(end 30.6324 -95.581216)
		(width 0.2286)
		(layer "In2.Cu")
		(net "FAN_3_OK_R_LED")
	)
	(segment
		(start 32.924496 -24.034242)
		(end 33.445704 -24.55545)
		(width 0.2286)
		(layer "In2.Cu")
		(net "FAN_3_OK_R_LED")
	)
	(segment
		(start 47.243746 -176.276)
		(end 45.466 -176.276)
		(width 0.2286)
		(layer "In2.Cu")
		(net "FAN_3_OK_R_LED")
	)
	(segment
		(start 30.30474 -64.136778)
		(end 30.30474 -81.388712)
		(width 0.2286)
		(layer "In2.Cu")
		(net "FAN_3_OK_R_LED")
	)
	(segment
		(start 30.6324 -95.581216)
		(end 35.406838 -100.355654)
		(width 0.2286)
		(layer "In2.Cu")
		(net "FAN_3_OK_R_LED")
	)
	(segment
		(start 35.5346 -51.508152)
		(end 30.30474 -64.136778)
		(width 0.2286)
		(layer "In2.Cu")
		(net "FAN_3_OK_R_LED")
	)
	(segment
		(start 30.30474 -81.388712)
		(end 30.6324 -81.716372)
		(width 0.2286)
		(layer "In2.Cu")
		(net "FAN_3_OK_R_LED")
	)
	(segment
		(start 49.223676 -174.29607)
		(end 47.243746 -176.276)
		(width 0.2286)
		(layer "In2.Cu")
		(net "FAN_3_OK_R_LED")
	)
	(segment
		(start 35.406838 -100.355654)
		(end 36.609274 -100.355654)
		(width 0.2286)
		(layer "In2.Cu")
		(net "FAN_3_OK_R_LED")
	)
	(segment
		(start 33.445704 -24.55545)
		(end 36.366704 -24.55545)
		(width 0.2286)
		(layer "In2.Cu")
		(net "FAN_3_OK_R_LED")
	)
	(segment
		(start 45.67428 -134.50062)
		(end 45.9994 -134.82574)
		(width 0.2286)
		(layer "In2.Cu")
		(net "FAN_3_OK_R_LED")
	)
	(segment
		(start 45.9994 -134.82574)
		(end 45.9994 -139.35964)
		(width 0.2286)
		(layer "In2.Cu")
		(net "FAN_3_OK_R_LED")
	)
	(segment
		(start 37.5666 -33.945576)
		(end 35.5346 -35.977576)
		(width 0.2286)
		(layer "In2.Cu")
		(net "FAN_3_OK_R_LED")
	)
	(segment
		(start 36.366704 -24.55545)
		(end 37.5666 -25.755346)
		(width 0.2286)
		(layer "In2.Cu")
		(net "FAN_3_OK_R_LED")
	)
	(segment
		(start 32.924496 -20.243546)
		(end 32.924496 -24.034242)
		(width 0.2286)
		(layer "In2.Cu")
		(net "FAN_3_OK_R_LED")
	)
	(segment
		(start 32.258 -19.685)
		(end 32.36595 -19.685)
		(width 0.2286)
		(layer "In2.Cu")
		(net "FAN_3_OK_R_LED")
	)
	(segment
		(start 36.609274 -100.355654)
		(end 39.079424 -102.825804)
		(width 0.2286)
		(layer "In2.Cu")
		(net "FAN_3_OK_R_LED")
	)
	(segment
		(start 47.090076 -104.308656)
		(end 47.090076 -121.819924)
		(width 0.2286)
		(layer "In2.Cu")
		(net "FAN_3_OK_R_LED")
	)
	(segment
		(start 35.5346 -35.977576)
		(end 35.5346 -51.508152)
		(width 0.2286)
		(layer "In2.Cu")
		(net "FAN_3_OK_R_LED")
	)
	(segment
		(start 49.223676 -142.583916)
		(end 49.223676 -174.29607)
		(width 0.2286)
		(layer "In2.Cu")
		(net "FAN_3_OK_R_LED")
	)
	(segment
		(start 45.607224 -102.825804)
		(end 47.090076 -104.308656)
		(width 0.2286)
		(layer "In2.Cu")
		(net "FAN_3_OK_R_LED")
	)
	(segment
		(start 47.090076 -121.819924)
		(end 45.67428 -123.23572)
		(width 0.2286)
		(layer "In2.Cu")
		(net "FAN_3_OK_R_LED")
	)
	(segment
		(start 45.9994 -139.35964)
		(end 49.223676 -142.583916)
		(width 0.2286)
		(layer "In2.Cu")
		(net "FAN_3_OK_R_LED")
	)
	(segment
		(start 32.36595 -19.685)
		(end 32.924496 -20.243546)
		(width 0.2286)
		(layer "In2.Cu")
		(net "FAN_3_OK_R_LED")
	)
	(segment
		(start 39.079424 -102.825804)
		(end 45.607224 -102.825804)
		(width 0.2286)
		(layer "In2.Cu")
		(net "FAN_3_OK_R_LED")
	)
	(segment
		(start 39.878 -23.622)
		(end 38.394132 -25.105868)
		(width 0.2794)
		(layer "F.Cu")
		(net "SMB_FAN3_SDA_R")
	)
	(segment
		(start 42.050462 -21.449538)
		(end 39.878 -23.622)
		(width 0.2794)
		(layer "F.Cu")
		(net "SMB_FAN3_SDA_R")
	)
	(segment
		(start 44.99991 -20.409916)
		(end 43.960288 -21.449538)
		(width 0.2794)
		(layer "F.Cu")
		(net "SMB_FAN3_SDA_R")
	)
	(segment
		(start 43.960288 -21.449538)
		(end 42.050462 -21.449538)
		(width 0.2794)
		(layer "F.Cu")
		(net "SMB_FAN3_SDA_R")
	)
	(segment
		(start 38.394132 -25.105868)
		(end 37.73805 -25.105868)
		(width 0.2794)
		(layer "F.Cu")
		(net "SMB_FAN3_SDA_R")
	)
	(via
		(at 39.878 -23.622)
		(size 0.762)
		(drill 0.381)
		(layers "F.Cu" "B.Cu")
		(net "SMB_FAN3_SDA_R")
	)
	(segment
		(start 32.258 -296.164)
		(end 32.258 -295.29405)
		(width 0.2794)
		(layer "F.Cu")
		(net "FAN_0_FAIL_R_LED")
	)
	(segment
		(start 36.74872 -215.265)
		(end 37.663374 -214.350346)
		(width 0.2794)
		(layer "F.Cu")
		(net "FAN_0_FAIL_R_LED")
	)
	(segment
		(start 32.258 -295.29405)
		(end 32.2834 -295.29405)
		(width 0.2794)
		(layer "F.Cu")
		(net "FAN_0_FAIL_R_LED")
	)
	(segment
		(start 26.543 -211.963)
		(end 26.543 -212.471)
		(width 0.2794)
		(layer "F.Cu")
		(net "FAN_0_FAIL_R_LED")
	)
	(segment
		(start 37.663374 -214.350346)
		(end 37.663374 -213.076028)
		(width 0.2794)
		(layer "F.Cu")
		(net "FAN_0_FAIL_R_LED")
	)
	(segment
		(start 26.543 -212.471)
		(end 29.337 -215.265)
		(width 0.2794)
		(layer "F.Cu")
		(net "FAN_0_FAIL_R_LED")
	)
	(segment
		(start 29.337 -215.265)
		(end 36.74872 -215.265)
		(width 0.2794)
		(layer "F.Cu")
		(net "FAN_0_FAIL_R_LED")
	)
	(segment
		(start 43.96105 -170.815)
		(end 44.577 -170.815)
		(width 0.2794)
		(layer "F.Cu")
		(net "FAN_0_FAIL_R_LED")
	)
	(segment
		(start 32.787336 -295.797986)
		(end 33.6169 -295.797986)
		(width 0.2794)
		(layer "F.Cu")
		(net "FAN_0_FAIL_R_LED")
	)
	(segment
		(start 32.2834 -295.29405)
		(end 32.787336 -295.797986)
		(width 0.2794)
		(layer "F.Cu")
		(net "FAN_0_FAIL_R_LED")
	)
	(via
		(at 37.663374 -213.076028)
		(size 0.508)
		(drill 0.254)
		(layers "F.Cu" "B.Cu")
		(net "FAN_0_FAIL_R_LED")
	)
	(via
		(at 44.577 -170.815)
		(size 0.508)
		(drill 0.254)
		(layers "F.Cu" "B.Cu")
		(net "FAN_0_FAIL_R_LED")
	)
	(via
		(at 26.543 -211.963)
		(size 0.508)
		(drill 0.254)
		(layers "F.Cu" "B.Cu")
		(net "FAN_0_FAIL_R_LED")
	)
	(via
		(at 32.258 -296.164)
		(size 0.508)
		(drill 0.254)
		(layers "F.Cu" "B.Cu")
		(net "FAN_0_FAIL_R_LED")
	)
	(segment
		(start 20.272248 -244.861842)
		(end 26.5938 -251.183394)
		(width 0.2286)
		(layer "In2.Cu")
		(net "FAN_0_FAIL_R_LED")
	)
	(segment
		(start 43.942 -177.8)
		(end 43.942 -171.45)
		(width 0.2286)
		(layer "In2.Cu")
		(net "FAN_0_FAIL_R_LED")
	)
	(segment
		(start 26.5938 -251.183394)
		(end 26.5938 -281.816302)
		(width 0.2286)
		(layer "In2.Cu")
		(net "FAN_0_FAIL_R_LED")
	)
	(segment
		(start 45.1104 -190.97498)
		(end 45.1104 -178.9684)
		(width 0.2286)
		(layer "In2.Cu")
		(net "FAN_0_FAIL_R_LED")
	)
	(segment
		(start 26.5938 -281.816302)
		(end 29.1719 -284.394402)
		(width 0.2286)
		(layer "In2.Cu")
		(net "FAN_0_FAIL_R_LED")
	)
	(segment
		(start 39.935404 -196.149976)
		(end 45.1104 -190.97498)
		(width 0.2286)
		(layer "In2.Cu")
		(net "FAN_0_FAIL_R_LED")
	)
	(segment
		(start 26.543 -219.5576)
		(end 20.272248 -225.828352)
		(width 0.2286)
		(layer "In2.Cu")
		(net "FAN_0_FAIL_R_LED")
	)
	(segment
		(start 31.079694 -294.985694)
		(end 32.258 -296.164)
		(width 0.2286)
		(layer "In2.Cu")
		(net "FAN_0_FAIL_R_LED")
	)
	(segment
		(start 29.1719 -284.394402)
		(end 29.1719 -289.315652)
		(width 0.2286)
		(layer "In2.Cu")
		(net "FAN_0_FAIL_R_LED")
	)
	(segment
		(start 20.272248 -225.828352)
		(end 20.272248 -244.861842)
		(width 0.2286)
		(layer "In2.Cu")
		(net "FAN_0_FAIL_R_LED")
	)
	(segment
		(start 39.935404 -210.803998)
		(end 39.935404 -196.149976)
		(width 0.2286)
		(layer "In2.Cu")
		(net "FAN_0_FAIL_R_LED")
	)
	(segment
		(start 45.1104 -178.9684)
		(end 43.942 -177.8)
		(width 0.2286)
		(layer "In2.Cu")
		(net "FAN_0_FAIL_R_LED")
	)
	(segment
		(start 37.663374 -213.076028)
		(end 39.935404 -210.803998)
		(width 0.2286)
		(layer "In2.Cu")
		(net "FAN_0_FAIL_R_LED")
	)
	(segment
		(start 31.079694 -291.223446)
		(end 31.079694 -294.985694)
		(width 0.2286)
		(layer "In2.Cu")
		(net "FAN_0_FAIL_R_LED")
	)
	(segment
		(start 43.942 -171.45)
		(end 44.577 -170.815)
		(width 0.2286)
		(layer "In2.Cu")
		(net "FAN_0_FAIL_R_LED")
	)
	(segment
		(start 29.1719 -289.315652)
		(end 31.079694 -291.223446)
		(width 0.2286)
		(layer "In2.Cu")
		(net "FAN_0_FAIL_R_LED")
	)
	(segment
		(start 26.543 -211.963)
		(end 26.543 -219.5576)
		(width 0.2286)
		(layer "In2.Cu")
		(net "FAN_0_FAIL_R_LED")
	)
	(segment
		(start 35.57905 -27.391868)
		(end 35.57905 -27.470862)
		(width 0.2794)
		(layer "F.Cu")
		(net "FAN_3_PWM_IL_R")
	)
	(segment
		(start 37.73805 -27.391868)
		(end 38.9128 -27.391868)
		(width 0.2794)
		(layer "F.Cu")
		(net "FAN_3_PWM_IL_R")
	)
	(segment
		(start 37.73805 -27.7368)
		(end 37.45865 -28.0162)
		(width 0.2794)
		(layer "F.Cu")
		(net "FAN_3_PWM_IL_R")
	)
	(segment
		(start 44.99991 -24.409908)
		(end 44.653454 -24.409908)
		(width 0.2794)
		(layer "F.Cu")
		(net "FAN_3_PWM_IL_R")
	)
	(segment
		(start 40.8686 -25.163526)
		(end 40.8686 -26.275538)
		(width 0.2794)
		(layer "F.Cu")
		(net "FAN_3_PWM_IL_R")
	)
	(segment
		(start 35.57905 -27.470862)
		(end 34.925 -28.124912)
		(width 0.2794)
		(layer "F.Cu")
		(net "FAN_3_PWM_IL_R")
	)
	(segment
		(start 43.662346 -23.4188)
		(end 42.613326 -23.4188)
		(width 0.2794)
		(layer "F.Cu")
		(net "FAN_3_PWM_IL_R")
	)
	(segment
		(start 42.613326 -23.4188)
		(end 40.8686 -25.163526)
		(width 0.2794)
		(layer "F.Cu")
		(net "FAN_3_PWM_IL_R")
	)
	(segment
		(start 37.73805 -27.391868)
		(end 37.73805 -27.7368)
		(width 0.2794)
		(layer "F.Cu")
		(net "FAN_3_PWM_IL_R")
	)
	(segment
		(start 40.8686 -26.275538)
		(end 39.75227 -27.391868)
		(width 0.2794)
		(layer "F.Cu")
		(net "FAN_3_PWM_IL_R")
	)
	(segment
		(start 34.079942 -28.124912)
		(end 33.317942 -27.362912)
		(width 0.2794)
		(layer "F.Cu")
		(net "FAN_3_PWM_IL_R")
	)
	(segment
		(start 36.203382 -28.0162)
		(end 35.57905 -27.391868)
		(width 0.2794)
		(layer "F.Cu")
		(net "FAN_3_PWM_IL_R")
	)
	(segment
		(start 39.75227 -27.391868)
		(end 38.9128 -27.391868)
		(width 0.2794)
		(layer "F.Cu")
		(net "FAN_3_PWM_IL_R")
	)
	(segment
		(start 37.45865 -28.0162)
		(end 36.203382 -28.0162)
		(width 0.2794)
		(layer "F.Cu")
		(net "FAN_3_PWM_IL_R")
	)
	(segment
		(start 44.653454 -24.409908)
		(end 43.662346 -23.4188)
		(width 0.2794)
		(layer "F.Cu")
		(net "FAN_3_PWM_IL_R")
	)
	(segment
		(start 34.925 -28.124912)
		(end 34.079942 -28.124912)
		(width 0.2794)
		(layer "F.Cu")
		(net "FAN_3_PWM_IL_R")
	)
	(via
		(at 38.9128 -27.391868)
		(size 0.762)
		(drill 0.381)
		(layers "F.Cu" "B.Cu")
		(net "FAN_3_PWM_IL_R")
	)
	(segment
		(start 32.258 -202.45705)
		(end 32.02305 -202.45705)
		(width 0.2794)
		(layer "F.Cu")
		(net "FAN_1_FAIL_R_LED")
	)
	(segment
		(start 43.96105 -172.847)
		(end 44.831 -172.847)
		(width 0.2794)
		(layer "F.Cu")
		(net "FAN_1_FAIL_R_LED")
	)
	(segment
		(start 32.02305 -202.45705)
		(end 31.496 -201.93)
		(width 0.2794)
		(layer "F.Cu")
		(net "FAN_1_FAIL_R_LED")
	)
	(segment
		(start 31.496 -201.93)
		(end 31.496 -200.914)
		(width 0.2794)
		(layer "F.Cu")
		(net "FAN_1_FAIL_R_LED")
	)
	(segment
		(start 31.496 -200.914)
		(end 32.036512 -200.373488)
		(width 0.2794)
		(layer "F.Cu")
		(net "FAN_1_FAIL_R_LED")
	)
	(segment
		(start 32.604964 -202.45705)
		(end 32.258 -202.45705)
		(width 0.2794)
		(layer "F.Cu")
		(net "FAN_1_FAIL_R_LED")
	)
	(segment
		(start 44.831 -172.847)
		(end 45.085 -172.593)
		(width 0.2794)
		(layer "F.Cu")
		(net "FAN_1_FAIL_R_LED")
	)
	(segment
		(start 32.036512 -200.373488)
		(end 33.62198 -200.373488)
		(width 0.2794)
		(layer "F.Cu")
		(net "FAN_1_FAIL_R_LED")
	)
	(segment
		(start 33.6169 -203.468986)
		(end 32.604964 -202.45705)
		(width 0.2794)
		(layer "F.Cu")
		(net "FAN_1_FAIL_R_LED")
	)
	(via
		(at 45.085 -172.593)
		(size 0.508)
		(drill 0.254)
		(layers "F.Cu" "B.Cu")
		(net "FAN_1_FAIL_R_LED")
	)
	(via
		(at 33.62198 -200.373488)
		(size 0.508)
		(drill 0.254)
		(layers "F.Cu" "B.Cu")
		(net "FAN_1_FAIL_R_LED")
	)
	(segment
		(start 43.942 -164.846)
		(end 44.958 -164.846)
		(width 0.2286)
		(layer "In2.Cu")
		(net "FAN_1_FAIL_R_LED")
	)
	(segment
		(start 45.847 -170.433746)
		(end 44.57065 -171.710096)
		(width 0.2286)
		(layer "In2.Cu")
		(net "FAN_1_FAIL_R_LED")
	)
	(segment
		(start 45.847 -165.735)
		(end 45.847 -170.433746)
		(width 0.2286)
		(layer "In2.Cu")
		(net "FAN_1_FAIL_R_LED")
	)
	(segment
		(start 41.783 -174.878746)
		(end 41.663112 -174.758858)
		(width 0.2286)
		(layer "In2.Cu")
		(net "FAN_1_FAIL_R_LED")
	)
	(segment
		(start 44.57065 -171.710096)
		(end 44.57065 -172.07865)
		(width 0.2286)
		(layer "In2.Cu")
		(net "FAN_1_FAIL_R_LED")
	)
	(segment
		(start 31.786576 -198.947278)
		(end 31.786576 -197.908164)
		(width 0.2286)
		(layer "In2.Cu")
		(net "FAN_1_FAIL_R_LED")
	)
	(segment
		(start 31.786576 -197.908164)
		(end 41.783 -187.91174)
		(width 0.2286)
		(layer "In2.Cu")
		(net "FAN_1_FAIL_R_LED")
	)
	(segment
		(start 33.62198 -200.373488)
		(end 33.62198 -199.66686)
		(width 0.2286)
		(layer "In2.Cu")
		(net "FAN_1_FAIL_R_LED")
	)
	(segment
		(start 41.663112 -174.758858)
		(end 41.663112 -167.124888)
		(width 0.2286)
		(layer "In2.Cu")
		(net "FAN_1_FAIL_R_LED")
	)
	(segment
		(start 41.783 -187.91174)
		(end 41.783 -174.878746)
		(width 0.2286)
		(layer "In2.Cu")
		(net "FAN_1_FAIL_R_LED")
	)
	(segment
		(start 44.958 -164.846)
		(end 45.847 -165.735)
		(width 0.2286)
		(layer "In2.Cu")
		(net "FAN_1_FAIL_R_LED")
	)
	(segment
		(start 41.663112 -167.124888)
		(end 43.942 -164.846)
		(width 0.2286)
		(layer "In2.Cu")
		(net "FAN_1_FAIL_R_LED")
	)
	(segment
		(start 32.015176 -199.175878)
		(end 31.786576 -198.947278)
		(width 0.2286)
		(layer "In2.Cu")
		(net "FAN_1_FAIL_R_LED")
	)
	(segment
		(start 33.62198 -199.66686)
		(end 33.130998 -199.175878)
		(width 0.2286)
		(layer "In2.Cu")
		(net "FAN_1_FAIL_R_LED")
	)
	(segment
		(start 33.130998 -199.175878)
		(end 32.015176 -199.175878)
		(width 0.2286)
		(layer "In2.Cu")
		(net "FAN_1_FAIL_R_LED")
	)
	(segment
		(start 44.57065 -172.07865)
		(end 45.085 -172.593)
		(width 0.2286)
		(layer "In2.Cu")
		(net "FAN_1_FAIL_R_LED")
	)
	(segment
		(start 33.51022 -29.995368)
		(end 33.316418 -29.995368)
		(width 0.2794)
		(layer "F.Cu")
		(net "FAN_3_TACH_IL_R")
	)
	(segment
		(start 32.8676 -28.1686)
		(end 33.29305 -28.59405)
		(width 0.2794)
		(layer "F.Cu")
		(net "FAN_3_TACH_IL_R")
	)
	(segment
		(start 35.2298 -30.312868)
		(end 35.2298 -30.3276)
		(width 0.2794)
		(layer "F.Cu")
		(net "FAN_3_TACH_IL_R")
	)
	(segment
		(start 33.316418 -29.995368)
		(end 33.29305 -29.972)
		(width 0.2794)
		(layer "F.Cu")
		(net "FAN_3_TACH_IL_R")
	)
	(segment
		(start 35.2298 -30.3276)
		(end 34.9504 -30.607)
		(width 0.2794)
		(layer "F.Cu")
		(net "FAN_3_TACH_IL_R")
	)
	(segment
		(start 34.121852 -30.607)
		(end 33.51022 -29.995368)
		(width 0.2794)
		(layer "F.Cu")
		(net "FAN_3_TACH_IL_R")
	)
	(segment
		(start 31.115 -28.1686)
		(end 32.8676 -28.1686)
		(width 0.2794)
		(layer "F.Cu")
		(net "FAN_3_TACH_IL_R")
	)
	(segment
		(start 33.29305 -28.59405)
		(end 33.29305 -28.956)
		(width 0.2794)
		(layer "F.Cu")
		(net "FAN_3_TACH_IL_R")
	)
	(segment
		(start 34.29 -30.607)
		(end 34.121852 -30.607)
		(width 0.2794)
		(layer "F.Cu")
		(net "FAN_3_TACH_IL_R")
	)
	(segment
		(start 34.9504 -30.607)
		(end 34.29 -30.607)
		(width 0.2794)
		(layer "F.Cu")
		(net "FAN_3_TACH_IL_R")
	)
	(segment
		(start 33.29305 -29.972)
		(end 33.29305 -28.956)
		(width 0.2794)
		(layer "F.Cu")
		(net "FAN_3_TACH_IL_R")
	)
	(via
		(at 34.29 -30.607)
		(size 0.508)
		(drill 0.254)
		(layers "F.Cu" "B.Cu")
		(net "FAN_3_TACH_IL_R")
	)
	(segment
		(start 33.728914 -110.49)
		(end 32.40405 -110.49)
		(width 0.2794)
		(layer "F.Cu")
		(net "FAN_2_FAIL_R_LED")
	)
	(segment
		(start 45.466 -174.752)
		(end 46.355 -174.752)
		(width 0.2794)
		(layer "F.Cu")
		(net "FAN_2_FAIL_R_LED")
	)
	(segment
		(start 43.96105 -174.879)
		(end 45.339 -174.879)
		(width 0.2794)
		(layer "F.Cu")
		(net "FAN_2_FAIL_R_LED")
	)
	(segment
		(start 45.339 -174.879)
		(end 45.466 -174.752)
		(width 0.2794)
		(layer "F.Cu")
		(net "FAN_2_FAIL_R_LED")
	)
	(segment
		(start 33.7439 -110.504986)
		(end 33.728914 -110.49)
		(width 0.2794)
		(layer "F.Cu")
		(net "FAN_2_FAIL_R_LED")
	)
	(segment
		(start 32.40405 -110.1344)
		(end 32.68345 -109.855)
		(width 0.2794)
		(layer "F.Cu")
		(net "FAN_2_FAIL_R_LED")
	)
	(segment
		(start 32.40405 -110.49)
		(end 32.40405 -110.1344)
		(width 0.2794)
		(layer "F.Cu")
		(net "FAN_2_FAIL_R_LED")
	)
	(segment
		(start 32.68345 -109.855)
		(end 33.147 -109.855)
		(width 0.2794)
		(layer "F.Cu")
		(net "FAN_2_FAIL_R_LED")
	)
	(via
		(at 46.355 -174.752)
		(size 0.508)
		(drill 0.254)
		(layers "F.Cu" "B.Cu")
		(net "FAN_2_FAIL_R_LED")
	)
	(via
		(at 33.147 -109.855)
		(size 0.508)
		(drill 0.254)
		(layers "F.Cu" "B.Cu")
		(net "FAN_2_FAIL_R_LED")
	)
	(segment
		(start 41.80967 -116.51107)
		(end 41.80967 -137.65022)
		(width 0.2286)
		(layer "In2.Cu")
		(net "FAN_2_FAIL_R_LED")
	)
	(segment
		(start 48.133 -173.101)
		(end 46.482 -174.752)
		(width 0.2286)
		(layer "In2.Cu")
		(net "FAN_2_FAIL_R_LED")
	)
	(segment
		(start 46.99 -164.211)
		(end 48.133 -165.354)
		(width 0.2286)
		(layer "In2.Cu")
		(net "FAN_2_FAIL_R_LED")
	)
	(segment
		(start 47.5234 -143.36395)
		(end 47.5234 -161.417)
		(width 0.2286)
		(layer "In2.Cu")
		(net "FAN_2_FAIL_R_LED")
	)
	(segment
		(start 35.1536 -109.855)
		(end 41.80967 -116.51107)
		(width 0.2286)
		(layer "In2.Cu")
		(net "FAN_2_FAIL_R_LED")
	)
	(segment
		(start 47.5234 -161.417)
		(end 46.99 -161.9504)
		(width 0.2286)
		(layer "In2.Cu")
		(net "FAN_2_FAIL_R_LED")
	)
	(segment
		(start 41.80967 -137.65022)
		(end 47.5234 -143.36395)
		(width 0.2286)
		(layer "In2.Cu")
		(net "FAN_2_FAIL_R_LED")
	)
	(segment
		(start 33.147 -109.855)
		(end 35.1536 -109.855)
		(width 0.2286)
		(layer "In2.Cu")
		(net "FAN_2_FAIL_R_LED")
	)
	(segment
		(start 46.99 -161.9504)
		(end 46.99 -164.211)
		(width 0.2286)
		(layer "In2.Cu")
		(net "FAN_2_FAIL_R_LED")
	)
	(segment
		(start 46.482 -174.752)
		(end 46.355 -174.752)
		(width 0.2286)
		(layer "In2.Cu")
		(net "FAN_2_FAIL_R_LED")
	)
	(segment
		(start 48.133 -165.354)
		(end 48.133 -173.101)
		(width 0.2286)
		(layer "In2.Cu")
		(net "FAN_2_FAIL_R_LED")
	)
	(segment
		(start 39.878 -13.457428)
		(end 38.559486 -14.775942)
		(width 0.2794)
		(layer "F.Cu")
		(net "FAN_3_TACH_OL_D")
	)
	(segment
		(start 39.929308 -13.40612)
		(end 43.996102 -13.40612)
		(width 0.2794)
		(layer "F.Cu")
		(net "FAN_3_TACH_OL_D")
	)
	(segment
		(start 38.559486 -14.775942)
		(end 37.719 -14.775942)
		(width 0.2794)
		(layer "F.Cu")
		(net "FAN_3_TACH_OL_D")
	)
	(segment
		(start 37.2872 -15.207742)
		(end 37.2872 -16.256)
		(width 0.2794)
		(layer "F.Cu")
		(net "FAN_3_TACH_OL_D")
	)
	(segment
		(start 43.996102 -13.40612)
		(end 44.99991 -14.409928)
		(width 0.2794)
		(layer "F.Cu")
		(net "FAN_3_TACH_OL_D")
	)
	(segment
		(start 37.719 -14.775942)
		(end 37.2872 -15.207742)
		(width 0.2794)
		(layer "F.Cu")
		(net "FAN_3_TACH_OL_D")
	)
	(segment
		(start 39.878 -13.457428)
		(end 39.929308 -13.40612)
		(width 0.2794)
		(layer "F.Cu")
		(net "FAN_3_TACH_OL_D")
	)
	(via
		(at 39.878 -13.457428)
		(size 0.762)
		(drill 0.381)
		(layers "F.Cu" "B.Cu")
		(net "FAN_3_TACH_OL_D")
	)
	(segment
		(start 18.0721 -298.054014)
		(end 18.906236 -298.054014)
		(width 0.2794)
		(layer "F.Cu")
		(net "FAN_7_OK_R_LED")
	)
	(segment
		(start 18.9103 -298.04995)
		(end 19.431 -298.04995)
		(width 0.2794)
		(layer "F.Cu")
		(net "FAN_7_OK_R_LED")
	)
	(segment
		(start 18.906236 -298.054014)
		(end 18.9103 -298.04995)
		(width 0.2794)
		(layer "F.Cu")
		(net "FAN_7_OK_R_LED")
	)
	(segment
		(start 28.55595 -171.577)
		(end 25.732486 -171.577)
		(width 0.2794)
		(layer "F.Cu")
		(net "FAN_7_OK_R_LED")
	)
	(segment
		(start 19.431 -298.04995)
		(end 20.066 -298.04995)
		(width 0.2794)
		(layer "F.Cu")
		(net "FAN_7_OK_R_LED")
	)
	(via
		(at 25.732486 -171.577)
		(size 0.508)
		(drill 0.254)
		(layers "F.Cu" "B.Cu")
		(net "FAN_7_OK_R_LED")
	)
	(via
		(at 20.066 -298.04995)
		(size 0.508)
		(drill 0.254)
		(layers "F.Cu" "B.Cu")
		(net "FAN_7_OK_R_LED")
	)
	(segment
		(start 24.9936 -252.08484)
		(end 18.590514 -245.681754)
		(width 0.2286)
		(layer "In2.Cu")
		(net "FAN_7_OK_R_LED")
	)
	(segment
		(start 23.322026 -212.64372)
		(end 23.322026 -209.249772)
		(width 0.2286)
		(layer "In2.Cu")
		(net "FAN_7_OK_R_LED")
	)
	(segment
		(start 23.014686 -183.926988)
		(end 25.729692 -181.211982)
		(width 0.2286)
		(layer "In2.Cu")
		(net "FAN_7_OK_R_LED")
	)
	(segment
		(start 23.622 -212.943694)
		(end 23.322026 -212.64372)
		(width 0.2286)
		(layer "In2.Cu")
		(net "FAN_7_OK_R_LED")
	)
	(segment
		(start 23.014686 -189.611)
		(end 23.014686 -183.926988)
		(width 0.2286)
		(layer "In2.Cu")
		(net "FAN_7_OK_R_LED")
	)
	(segment
		(start 20.066 -298.04995)
		(end 24.207978 -293.907972)
		(width 0.2286)
		(layer "In2.Cu")
		(net "FAN_7_OK_R_LED")
	)
	(segment
		(start 24.207978 -293.907972)
		(end 24.207978 -285.364428)
		(width 0.2286)
		(layer "In2.Cu")
		(net "FAN_7_OK_R_LED")
	)
	(segment
		(start 25.729692 -181.211982)
		(end 25.729692 -171.579794)
		(width 0.2286)
		(layer "In2.Cu")
		(net "FAN_7_OK_R_LED")
	)
	(segment
		(start 25.729692 -171.579794)
		(end 25.732486 -171.577)
		(width 0.2286)
		(layer "In2.Cu")
		(net "FAN_7_OK_R_LED")
	)
	(segment
		(start 24.9936 -284.578806)
		(end 24.9936 -252.08484)
		(width 0.2286)
		(layer "In2.Cu")
		(net "FAN_7_OK_R_LED")
	)
	(segment
		(start 23.14702 -189.743334)
		(end 23.014686 -189.611)
		(width 0.2286)
		(layer "In2.Cu")
		(net "FAN_7_OK_R_LED")
	)
	(segment
		(start 23.014686 -201.038968)
		(end 23.14702 -200.906634)
		(width 0.2286)
		(layer "In2.Cu")
		(net "FAN_7_OK_R_LED")
	)
	(segment
		(start 23.322026 -209.249772)
		(end 23.014686 -208.942432)
		(width 0.2286)
		(layer "In2.Cu")
		(net "FAN_7_OK_R_LED")
	)
	(segment
		(start 23.014686 -208.942432)
		(end 23.014686 -201.038968)
		(width 0.2286)
		(layer "In2.Cu")
		(net "FAN_7_OK_R_LED")
	)
	(segment
		(start 23.622 -219.712286)
		(end 23.622 -212.943694)
		(width 0.2286)
		(layer "In2.Cu")
		(net "FAN_7_OK_R_LED")
	)
	(segment
		(start 18.590514 -224.743772)
		(end 23.622 -219.712286)
		(width 0.2286)
		(layer "In2.Cu")
		(net "FAN_7_OK_R_LED")
	)
	(segment
		(start 18.590514 -245.681754)
		(end 18.590514 -224.743772)
		(width 0.2286)
		(layer "In2.Cu")
		(net "FAN_7_OK_R_LED")
	)
	(segment
		(start 24.207978 -285.364428)
		(end 24.9936 -284.578806)
		(width 0.2286)
		(layer "In2.Cu")
		(net "FAN_7_OK_R_LED")
	)
	(segment
		(start 23.14702 -200.906634)
		(end 23.14702 -189.743334)
		(width 0.2286)
		(layer "In2.Cu")
		(net "FAN_7_OK_R_LED")
	)
	(segment
		(start 43.990006 -25.4)
		(end 44.99991 -26.409904)
		(width 0.2794)
		(layer "F.Cu")
		(net "FAN_3_TACH_IL_D")
	)
	(segment
		(start 38.1762 -29.1084)
		(end 37.729668 -28.661868)
		(width 0.2794)
		(layer "F.Cu")
		(net "FAN_3_TACH_IL_D")
	)
	(segment
		(start 40.1828 -27.7876)
		(end 42.5704 -25.4)
		(width 0.2794)
		(layer "F.Cu")
		(net "FAN_3_TACH_IL_D")
	)
	(segment
		(start 39.7764 -29.1084)
		(end 38.1762 -29.1084)
		(width 0.2794)
		(layer "F.Cu")
		(net "FAN_3_TACH_IL_D")
	)
	(segment
		(start 40.1828 -28.702)
		(end 40.1828 -27.7876)
		(width 0.2794)
		(layer "F.Cu")
		(net "FAN_3_TACH_IL_D")
	)
	(segment
		(start 42.5704 -25.4)
		(end 43.990006 -25.4)
		(width 0.2794)
		(layer "F.Cu")
		(net "FAN_3_TACH_IL_D")
	)
	(segment
		(start 36.746942 -29.64561)
		(end 37.4142 -30.312868)
		(width 0.2794)
		(layer "F.Cu")
		(net "FAN_3_TACH_IL_D")
	)
	(segment
		(start 37.729668 -28.661868)
		(end 36.746942 -28.661868)
		(width 0.2794)
		(layer "F.Cu")
		(net "FAN_3_TACH_IL_D")
	)
	(segment
		(start 39.7764 -29.1084)
		(end 40.1828 -28.702)
		(width 0.2794)
		(layer "F.Cu")
		(net "FAN_3_TACH_IL_D")
	)
	(segment
		(start 36.746942 -28.661868)
		(end 36.746942 -29.64561)
		(width 0.2794)
		(layer "F.Cu")
		(net "FAN_3_TACH_IL_D")
	)
	(via
		(at 39.7764 -29.1084)
		(size 0.762)
		(drill 0.381)
		(layers "F.Cu" "B.Cu")
		(net "FAN_3_TACH_IL_D")
	)
	(segment
		(start 43.96105 -173.863)
		(end 45.847 -173.863)
		(width 0.2794)
		(layer "F.Cu")
		(net "FAN_2_OK_R_LED")
	)
	(segment
		(start 33.003236 -107.08005)
		(end 33.6423 -106.440986)
		(width 0.2794)
		(layer "F.Cu")
		(net "FAN_2_OK_R_LED")
	)
	(segment
		(start 32.385 -107.08005)
		(end 33.003236 -107.08005)
		(width 0.2794)
		(layer "F.Cu")
		(net "FAN_2_OK_R_LED")
	)
	(segment
		(start 33.7439 -106.440986)
		(end 33.7439 -107.146598)
		(width 0.2794)
		(layer "F.Cu")
		(net "FAN_2_OK_R_LED")
	)
	(segment
		(start 33.6423 -106.440986)
		(end 33.7439 -106.440986)
		(width 0.2794)
		(layer "F.Cu")
		(net "FAN_2_OK_R_LED")
	)
	(via
		(at 45.847 -173.863)
		(size 0.762)
		(drill 0.254)
		(layers "F.Cu" "B.Cu")
		(net "FAN_2_OK_R_LED")
	)
	(via
		(at 33.7439 -107.146598)
		(size 0.508)
		(drill 0.254)
		(layers "F.Cu" "B.Cu")
		(net "FAN_2_OK_R_LED")
	)
	(segment
		(start 48.690276 -174.07509)
		(end 47.365666 -175.3997)
		(width 0.2286)
		(layer "In2.Cu")
		(net "FAN_2_OK_R_LED")
	)
	(segment
		(start 48.690276 -142.939516)
		(end 48.690276 -174.07509)
		(width 0.2286)
		(layer "In2.Cu")
		(net "FAN_2_OK_R_LED")
	)
	(segment
		(start 44.377102 -123.643898)
		(end 44.377102 -138.626342)
		(width 0.2286)
		(layer "In2.Cu")
		(net "FAN_2_OK_R_LED")
	)
	(segment
		(start 45.339 -103.378)
		(end 46.556676 -104.595676)
		(width 0.2286)
		(layer "In2.Cu")
		(net "FAN_2_OK_R_LED")
	)
	(segment
		(start 45.9486 -175.3997)
		(end 45.72 -175.1711)
		(width 0.2286)
		(layer "In2.Cu")
		(net "FAN_2_OK_R_LED")
	)
	(segment
		(start 41.021 -103.378)
		(end 45.339 -103.378)
		(width 0.2286)
		(layer "In2.Cu")
		(net "FAN_2_OK_R_LED")
	)
	(segment
		(start 45.72 -173.99)
		(end 45.847 -173.863)
		(width 0.2286)
		(layer "In2.Cu")
		(net "FAN_2_OK_R_LED")
	)
	(segment
		(start 45.72 -175.1711)
		(end 45.72 -173.99)
		(width 0.2286)
		(layer "In2.Cu")
		(net "FAN_2_OK_R_LED")
	)
	(segment
		(start 33.7439 -107.146598)
		(end 34.166302 -107.569)
		(width 0.2286)
		(layer "In2.Cu")
		(net "FAN_2_OK_R_LED")
	)
	(segment
		(start 47.365666 -175.3997)
		(end 45.9486 -175.3997)
		(width 0.2286)
		(layer "In2.Cu")
		(net "FAN_2_OK_R_LED")
	)
	(segment
		(start 46.556676 -104.595676)
		(end 46.556676 -121.464324)
		(width 0.2286)
		(layer "In2.Cu")
		(net "FAN_2_OK_R_LED")
	)
	(segment
		(start 36.83 -107.569)
		(end 41.021 -103.378)
		(width 0.2286)
		(layer "In2.Cu")
		(net "FAN_2_OK_R_LED")
	)
	(segment
		(start 46.556676 -121.464324)
		(end 44.377102 -123.643898)
		(width 0.2286)
		(layer "In2.Cu")
		(net "FAN_2_OK_R_LED")
	)
	(segment
		(start 34.166302 -107.569)
		(end 36.83 -107.569)
		(width 0.2286)
		(layer "In2.Cu")
		(net "FAN_2_OK_R_LED")
	)
	(segment
		(start 44.377102 -138.626342)
		(end 48.690276 -142.939516)
		(width 0.2286)
		(layer "In2.Cu")
		(net "FAN_2_OK_R_LED")
	)
	(segment
		(start 19.558 -109.83595)
		(end 20.183602 -109.210348)
		(width 0.2794)
		(layer "F.Cu")
		(net "FAN_5_FAIL_R_LED")
	)
	(segment
		(start 28.55595 -174.9552)
		(end 28.83535 -175.2346)
		(width 0.2794)
		(layer "F.Cu")
		(net "FAN_5_FAIL_R_LED")
	)
	(segment
		(start 19.553936 -109.840014)
		(end 19.558 -109.83595)
		(width 0.2794)
		(layer "F.Cu")
		(net "FAN_5_FAIL_R_LED")
	)
	(segment
		(start 28.55595 -174.625)
		(end 28.55595 -174.9552)
		(width 0.2794)
		(layer "F.Cu")
		(net "FAN_5_FAIL_R_LED")
	)
	(segment
		(start 18.1991 -109.840014)
		(end 19.553936 -109.840014)
		(width 0.2794)
		(layer "F.Cu")
		(net "FAN_5_FAIL_R_LED")
	)
	(segment
		(start 28.83535 -175.2346)
		(end 29.845 -175.2346)
		(width 0.2794)
		(layer "F.Cu")
		(net "FAN_5_FAIL_R_LED")
	)
	(via
		(at 29.845 -175.2346)
		(size 0.508)
		(drill 0.254)
		(layers "F.Cu" "B.Cu")
		(net "FAN_5_FAIL_R_LED")
	)
	(via
		(at 20.183602 -109.210348)
		(size 0.508)
		(drill 0.254)
		(layers "F.Cu" "B.Cu")
		(net "FAN_5_FAIL_R_LED")
	)
	(segment
		(start 25.0571 -124.60097)
		(end 25.0571 -127.736346)
		(width 0.2286)
		(layer "In2.Cu")
		(net "FAN_5_FAIL_R_LED")
	)
	(segment
		(start 25.0571 -127.736346)
		(end 24.374602 -128.418844)
		(width 0.2286)
		(layer "In2.Cu")
		(net "FAN_5_FAIL_R_LED")
	)
	(segment
		(start 31.385002 -162.64382)
		(end 31.385002 -164.224208)
		(width 0.2286)
		(layer "In2.Cu")
		(net "FAN_5_FAIL_R_LED")
	)
	(segment
		(start 19.6596 -113.923318)
		(end 19.6596 -117.145054)
		(width 0.2286)
		(layer "In2.Cu")
		(net "FAN_5_FAIL_R_LED")
	)
	(segment
		(start 24.999696 -141.878304)
		(end 24.999696 -143.845534)
		(width 0.2286)
		(layer "In2.Cu")
		(net "FAN_5_FAIL_R_LED")
	)
	(segment
		(start 26.0858 -149.558248)
		(end 31.385002 -162.64382)
		(width 0.2286)
		(layer "In2.Cu")
		(net "FAN_5_FAIL_R_LED")
	)
	(segment
		(start 29.984954 -175.094646)
		(end 29.845 -175.2346)
		(width 0.2286)
		(layer "In2.Cu")
		(net "FAN_5_FAIL_R_LED")
	)
	(segment
		(start 26.0858 -144.931638)
		(end 26.0858 -149.558248)
		(width 0.2286)
		(layer "In2.Cu")
		(net "FAN_5_FAIL_R_LED")
	)
	(segment
		(start 26.70175 -133.328156)
		(end 26.70175 -135.5979)
		(width 0.2286)
		(layer "In2.Cu")
		(net "FAN_5_FAIL_R_LED")
	)
	(segment
		(start 26.70175 -135.5979)
		(end 25.908 -136.39165)
		(width 0.2286)
		(layer "In2.Cu")
		(net "FAN_5_FAIL_R_LED")
	)
	(segment
		(start 25.908 -136.39165)
		(end 25.908 -140.97)
		(width 0.2286)
		(layer "In2.Cu")
		(net "FAN_5_FAIL_R_LED")
	)
	(segment
		(start 19.6596 -117.145054)
		(end 20.955 -118.440454)
		(width 0.2286)
		(layer "In2.Cu")
		(net "FAN_5_FAIL_R_LED")
	)
	(segment
		(start 20.955 -118.440454)
		(end 20.955 -120.49887)
		(width 0.2286)
		(layer "In2.Cu")
		(net "FAN_5_FAIL_R_LED")
	)
	(segment
		(start 29.984954 -165.624256)
		(end 29.984954 -175.094646)
		(width 0.2286)
		(layer "In2.Cu")
		(net "FAN_5_FAIL_R_LED")
	)
	(segment
		(start 24.999696 -143.845534)
		(end 26.0858 -144.931638)
		(width 0.2286)
		(layer "In2.Cu")
		(net "FAN_5_FAIL_R_LED")
	)
	(segment
		(start 20.183602 -109.210348)
		(end 20.183602 -113.399316)
		(width 0.2286)
		(layer "In2.Cu")
		(net "FAN_5_FAIL_R_LED")
	)
	(segment
		(start 24.374602 -128.418844)
		(end 24.374602 -131.001008)
		(width 0.2286)
		(layer "In2.Cu")
		(net "FAN_5_FAIL_R_LED")
	)
	(segment
		(start 25.908 -140.97)
		(end 24.999696 -141.878304)
		(width 0.2286)
		(layer "In2.Cu")
		(net "FAN_5_FAIL_R_LED")
	)
	(segment
		(start 31.385002 -164.224208)
		(end 29.984954 -165.624256)
		(width 0.2286)
		(layer "In2.Cu")
		(net "FAN_5_FAIL_R_LED")
	)
	(segment
		(start 24.374602 -131.001008)
		(end 26.70175 -133.328156)
		(width 0.2286)
		(layer "In2.Cu")
		(net "FAN_5_FAIL_R_LED")
	)
	(segment
		(start 20.183602 -113.399316)
		(end 19.6596 -113.923318)
		(width 0.2286)
		(layer "In2.Cu")
		(net "FAN_5_FAIL_R_LED")
	)
	(segment
		(start 20.955 -120.49887)
		(end 25.0571 -124.60097)
		(width 0.2286)
		(layer "In2.Cu")
		(net "FAN_5_FAIL_R_LED")
	)
	(segment
		(start 32.258 -22.49805)
		(end 33.015936 -23.255986)
		(width 0.2794)
		(layer "F.Cu")
		(net "FAN_3_FAIL_R_LED")
	)
	(segment
		(start 33.015936 -23.255986)
		(end 33.6169 -23.255986)
		(width 0.2794)
		(layer "F.Cu")
		(net "FAN_3_FAIL_R_LED")
	)
	(segment
		(start 43.96105 -176.911)
		(end 45.974 -176.911)
		(width 0.2794)
		(layer "F.Cu")
		(net "FAN_3_FAIL_R_LED")
	)
	(segment
		(start 33.6169 -23.255986)
		(end 33.6169 -23.945342)
		(width 0.2794)
		(layer "F.Cu")
		(net "FAN_3_FAIL_R_LED")
	)
	(via
		(at 45.974 -176.911)
		(size 0.762)
		(drill 0.254)
		(layers "F.Cu" "B.Cu")
		(net "FAN_3_FAIL_R_LED")
	)
	(via
		(at 33.6169 -23.945342)
		(size 0.508)
		(drill 0.254)
		(layers "F.Cu" "B.Cu")
		(net "FAN_3_FAIL_R_LED")
	)
	(segment
		(start 46.20768 -134.27964)
		(end 46.5328 -134.60476)
		(width 0.2286)
		(layer "In2.Cu")
		(net "FAN_3_FAIL_R_LED")
	)
	(segment
		(start 33.6169 -23.614634)
		(end 34.009838 -23.221696)
		(width 0.2286)
		(layer "In2.Cu")
		(net "FAN_3_FAIL_R_LED")
	)
	(segment
		(start 33.6169 -23.945342)
		(end 33.6169 -23.614634)
		(width 0.2286)
		(layer "In2.Cu")
		(net "FAN_3_FAIL_R_LED")
	)
	(segment
		(start 36.556696 -23.221696)
		(end 38.1 -24.765)
		(width 0.2286)
		(layer "In2.Cu")
		(net "FAN_3_FAIL_R_LED")
	)
	(segment
		(start 34.009838 -23.221696)
		(end 36.556696 -23.221696)
		(width 0.2286)
		(layer "In2.Cu")
		(net "FAN_3_FAIL_R_LED")
	)
	(segment
		(start 36.1823 -36.26612)
		(end 36.1823 -51.338988)
		(width 0.2286)
		(layer "In2.Cu")
		(net "FAN_3_FAIL_R_LED")
	)
	(segment
		(start 38.1 -24.765)
		(end 38.1 -34.34842)
		(width 0.2286)
		(layer "In2.Cu")
		(net "FAN_3_FAIL_R_LED")
	)
	(segment
		(start 46.5328 -139.136628)
		(end 49.757076 -142.360904)
		(width 0.2286)
		(layer "In2.Cu")
		(net "FAN_3_FAIL_R_LED")
	)
	(segment
		(start 39.300404 -102.292404)
		(end 45.828204 -102.292404)
		(width 0.2286)
		(layer "In2.Cu")
		(net "FAN_3_FAIL_R_LED")
	)
	(segment
		(start 46.20768 -123.46432)
		(end 46.20768 -134.27964)
		(width 0.2286)
		(layer "In2.Cu")
		(net "FAN_3_FAIL_R_LED")
	)
	(segment
		(start 31.1658 -95.25)
		(end 35.7378 -99.822)
		(width 0.2286)
		(layer "In2.Cu")
		(net "FAN_3_FAIL_R_LED")
	)
	(segment
		(start 35.7378 -99.822)
		(end 36.83 -99.822)
		(width 0.2286)
		(layer "In2.Cu")
		(net "FAN_3_FAIL_R_LED")
	)
	(segment
		(start 49.757076 -142.360904)
		(end 49.757076 -174.532798)
		(width 0.2286)
		(layer "In2.Cu")
		(net "FAN_3_FAIL_R_LED")
	)
	(segment
		(start 47.623476 -104.087676)
		(end 47.623476 -122.048524)
		(width 0.2286)
		(layer "In2.Cu")
		(net "FAN_3_FAIL_R_LED")
	)
	(segment
		(start 30.83814 -64.24295)
		(end 30.83814 -81.167224)
		(width 0.2286)
		(layer "In2.Cu")
		(net "FAN_3_FAIL_R_LED")
	)
	(segment
		(start 38.1 -34.34842)
		(end 36.1823 -36.26612)
		(width 0.2286)
		(layer "In2.Cu")
		(net "FAN_3_FAIL_R_LED")
	)
	(segment
		(start 30.83814 -81.167224)
		(end 31.1658 -81.494884)
		(width 0.2286)
		(layer "In2.Cu")
		(net "FAN_3_FAIL_R_LED")
	)
	(segment
		(start 31.1658 -81.494884)
		(end 31.1658 -95.25)
		(width 0.2286)
		(layer "In2.Cu")
		(net "FAN_3_FAIL_R_LED")
	)
	(segment
		(start 47.623476 -122.048524)
		(end 46.20768 -123.46432)
		(width 0.2286)
		(layer "In2.Cu")
		(net "FAN_3_FAIL_R_LED")
	)
	(segment
		(start 47.378874 -176.911)
		(end 45.974 -176.911)
		(width 0.2286)
		(layer "In2.Cu")
		(net "FAN_3_FAIL_R_LED")
	)
	(segment
		(start 45.828204 -102.292404)
		(end 47.623476 -104.087676)
		(width 0.2286)
		(layer "In2.Cu")
		(net "FAN_3_FAIL_R_LED")
	)
	(segment
		(start 36.1823 -51.338988)
		(end 30.83814 -64.24295)
		(width 0.2286)
		(layer "In2.Cu")
		(net "FAN_3_FAIL_R_LED")
	)
	(segment
		(start 46.5328 -134.60476)
		(end 46.5328 -139.136628)
		(width 0.2286)
		(layer "In2.Cu")
		(net "FAN_3_FAIL_R_LED")
	)
	(segment
		(start 49.757076 -174.532798)
		(end 47.378874 -176.911)
		(width 0.2286)
		(layer "In2.Cu")
		(net "FAN_3_FAIL_R_LED")
	)
	(segment
		(start 36.83 -99.822)
		(end 39.300404 -102.292404)
		(width 0.2286)
		(layer "In2.Cu")
		(net "FAN_3_FAIL_R_LED")
	)
	(segment
		(start 42.999914 -22.409912)
		(end 42.352722 -22.409912)
		(width 0.2794)
		(layer "F.Cu")
		(net "SMB_FAN3_SCL_R")
	)
	(segment
		(start 39.562532 -26.248868)
		(end 37.73805 -26.248868)
		(width 0.2794)
		(layer "F.Cu")
		(net "SMB_FAN3_SCL_R")
	)
	(segment
		(start 39.878 -25.654)
		(end 39.878 -25.9334)
		(width 0.2794)
		(layer "F.Cu")
		(net "SMB_FAN3_SCL_R")
	)
	(segment
		(start 42.352722 -22.409912)
		(end 39.878 -24.884634)
		(width 0.2794)
		(layer "F.Cu")
		(net "SMB_FAN3_SCL_R")
	)
	(segment
		(start 39.878 -24.884634)
		(end 39.878 -25.654)
		(width 0.2794)
		(layer "F.Cu")
		(net "SMB_FAN3_SCL_R")
	)
	(segment
		(start 39.878 -25.9334)
		(end 39.562532 -26.248868)
		(width 0.2794)
		(layer "F.Cu")
		(net "SMB_FAN3_SCL_R")
	)
	(via
		(at 39.878 -25.654)
		(size 0.762)
		(drill 0.381)
		(layers "F.Cu" "B.Cu")
		(net "SMB_FAN3_SCL_R")
	)
	(segment
		(start 23.391622 -177.014378)
		(end 23.391622 -183.781954)
		(width 0.2794)
		(layer "F.Cu")
		(net "FAN_6_FAIL_R_LED")
	)
	(segment
		(start 28.55595 -172.593)
		(end 27.813 -172.593)
		(width 0.2794)
		(layer "F.Cu")
		(net "FAN_6_FAIL_R_LED")
	)
	(segment
		(start 20.828 -204.216)
		(end 19.91995 -203.30795)
		(width 0.2794)
		(layer "F.Cu")
		(net "FAN_6_FAIL_R_LED")
	)
	(segment
		(start 27.813 -172.593)
		(end 23.391622 -177.014378)
		(width 0.2794)
		(layer "F.Cu")
		(net "FAN_6_FAIL_R_LED")
	)
	(segment
		(start 21.717 -186.5503)
		(end 20.31365 -187.95365)
		(width 0.2794)
		(layer "F.Cu")
		(net "FAN_6_FAIL_R_LED")
	)
	(segment
		(start 19.558 -203.30795)
		(end 19.084036 -203.30795)
		(width 0.2794)
		(layer "F.Cu")
		(net "FAN_6_FAIL_R_LED")
	)
	(segment
		(start 21.082 -204.216)
		(end 20.828 -204.216)
		(width 0.2794)
		(layer "F.Cu")
		(net "FAN_6_FAIL_R_LED")
	)
	(segment
		(start 23.391622 -183.781954)
		(end 21.717 -185.456576)
		(width 0.2794)
		(layer "F.Cu")
		(net "FAN_6_FAIL_R_LED")
	)
	(segment
		(start 19.084036 -203.30795)
		(end 18.1991 -202.423014)
		(width 0.2794)
		(layer "F.Cu")
		(net "FAN_6_FAIL_R_LED")
	)
	(segment
		(start 19.91995 -203.30795)
		(end 19.558 -203.30795)
		(width 0.2794)
		(layer "F.Cu")
		(net "FAN_6_FAIL_R_LED")
	)
	(segment
		(start 21.717 -185.456576)
		(end 21.717 -186.5503)
		(width 0.2794)
		(layer "F.Cu")
		(net "FAN_6_FAIL_R_LED")
	)
	(via
		(at 21.082 -204.216)
		(size 0.508)
		(drill 0.254)
		(layers "F.Cu" "B.Cu")
		(net "FAN_6_FAIL_R_LED")
	)
	(via
		(at 20.31365 -187.95365)
		(size 0.508)
		(drill 0.254)
		(layers "F.Cu" "B.Cu")
		(net "FAN_6_FAIL_R_LED")
	)
	(segment
		(start 21.24202 -190.835026)
		(end 21.04136 -190.634366)
		(width 0.2286)
		(layer "In2.Cu")
		(net "FAN_6_FAIL_R_LED")
	)
	(segment
		(start 20.7264 -203.8604)
		(end 20.7264 -199.771)
		(width 0.2286)
		(layer "In2.Cu")
		(net "FAN_6_FAIL_R_LED")
	)
	(segment
		(start 21.082 -204.216)
		(end 20.7264 -203.8604)
		(width 0.2286)
		(layer "In2.Cu")
		(net "FAN_6_FAIL_R_LED")
	)
	(segment
		(start 21.04136 -188.68136)
		(end 20.31365 -187.95365)
		(width 0.2286)
		(layer "In2.Cu")
		(net "FAN_6_FAIL_R_LED")
	)
	(segment
		(start 21.04136 -190.634366)
		(end 21.04136 -188.68136)
		(width 0.2286)
		(layer "In2.Cu")
		(net "FAN_6_FAIL_R_LED")
	)
	(segment
		(start 21.24202 -199.25538)
		(end 21.24202 -190.835026)
		(width 0.2286)
		(layer "In2.Cu")
		(net "FAN_6_FAIL_R_LED")
	)
	(segment
		(start 20.7264 -199.771)
		(end 21.24202 -199.25538)
		(width 0.2286)
		(layer "In2.Cu")
		(net "FAN_6_FAIL_R_LED")
	)
	(segment
		(start 48.145192 -164.1348)
		(end 48.579786 -163.700206)
		(width 0.2794)
		(layer "F.Cu")
		(net "FAN_3_PRESENT_R_N")
	)
	(segment
		(start 43.20794 -164.1348)
		(end 48.145192 -164.1348)
		(width 0.2794)
		(layer "F.Cu")
		(net "FAN_3_PRESENT_R_N")
	)
	(segment
		(start 48.579786 -163.700206)
		(end 48.579786 -139.065)
		(width 0.2794)
		(layer "F.Cu")
		(net "FAN_3_PRESENT_R_N")
	)
	(segment
		(start 34.7726 -166.40556)
		(end 38.41242 -166.40556)
		(width 0.2794)
		(layer "F.Cu")
		(net "FAN_3_PRESENT_R_N")
	)
	(segment
		(start 21.843746 -165.9382)
		(end 34.30524 -165.9382)
		(width 0.2794)
		(layer "F.Cu")
		(net "FAN_3_PRESENT_R_N")
	)
	(segment
		(start 38.898068 -165.919912)
		(end 43.20794 -164.1348)
		(width 0.2794)
		(layer "F.Cu")
		(net "FAN_3_PRESENT_R_N")
	)
	(segment
		(start 38.41242 -166.40556)
		(end 38.898068 -165.919912)
		(width 0.2794)
		(layer "F.Cu")
		(net "FAN_3_PRESENT_R_N")
	)
	(segment
		(start 18.30705 -167.005)
		(end 20.776946 -167.005)
		(width 0.2794)
		(layer "F.Cu")
		(net "FAN_3_PRESENT_R_N")
	)
	(segment
		(start 34.30524 -165.9382)
		(end 34.7726 -166.40556)
		(width 0.2794)
		(layer "F.Cu")
		(net "FAN_3_PRESENT_R_N")
	)
	(segment
		(start 20.776946 -167.005)
		(end 21.843746 -165.9382)
		(width 0.2794)
		(layer "F.Cu")
		(net "FAN_3_PRESENT_R_N")
	)
	(via
		(at 48.579786 -139.065)
		(size 0.508)
		(drill 0.254)
		(layers "F.Cu" "B.Cu")
		(net "FAN_3_PRESENT_R_N")
	)
	(segment
		(start 46.74108 -123.69292)
		(end 46.74108 -134.05866)
		(width 0.2286)
		(layer "In2.Cu")
		(net "FAN_3_PRESENT_R_N")
	)
	(segment
		(start 46.020482 -101.662738)
		(end 46.035976 -101.664516)
		(width 0.2286)
		(layer "In2.Cu")
		(net "FAN_3_PRESENT_R_N")
	)
	(segment
		(start 36.7157 -51.445922)
		(end 31.37154 -64.349122)
		(width 0.2286)
		(layer "In2.Cu")
		(net "FAN_3_PRESENT_R_N")
	)
	(segment
		(start 48.156876 -103.782876)
		(end 48.156876 -122.277124)
		(width 0.2286)
		(layer "In2.Cu")
		(net "FAN_3_PRESENT_R_N")
	)
	(segment
		(start 48.156876 -122.277124)
		(end 46.74108 -123.69292)
		(width 0.2286)
		(layer "In2.Cu")
		(net "FAN_3_PRESENT_R_N")
	)
	(segment
		(start 35.8648 -99.187)
		(end 36.957254 -99.187)
		(width 0.2286)
		(layer "In2.Cu")
		(net "FAN_3_PRESENT_R_N")
	)
	(segment
		(start 46.74108 -134.05866)
		(end 47.0662 -134.38378)
		(width 0.2286)
		(layer "In2.Cu")
		(net "FAN_3_PRESENT_R_N")
	)
	(segment
		(start 38.735 -28.674822)
		(end 38.735 -34.4678)
		(width 0.2286)
		(layer "In2.Cu")
		(net "FAN_3_PRESENT_R_N")
	)
	(segment
		(start 47.0662 -134.38378)
		(end 47.0662 -137.551414)
		(width 0.2286)
		(layer "In2.Cu")
		(net "FAN_3_PRESENT_R_N")
	)
	(segment
		(start 46.048676 -101.674676)
		(end 48.156876 -103.782876)
		(width 0.2286)
		(layer "In2.Cu")
		(net "FAN_3_PRESENT_R_N")
	)
	(segment
		(start 38.735 -34.4678)
		(end 36.7157 -36.4871)
		(width 0.2286)
		(layer "In2.Cu")
		(net "FAN_3_PRESENT_R_N")
	)
	(segment
		(start 36.7157 -36.4871)
		(end 36.7157 -51.445922)
		(width 0.2286)
		(layer "In2.Cu")
		(net "FAN_3_PRESENT_R_N")
	)
	(segment
		(start 31.6992 -81.1276)
		(end 31.6992 -95.0214)
		(width 0.2286)
		(layer "In2.Cu")
		(net "FAN_3_PRESENT_R_N")
	)
	(segment
		(start 46.035976 -101.664516)
		(end 46.048676 -101.674676)
		(width 0.2286)
		(layer "In2.Cu")
		(net "FAN_3_PRESENT_R_N")
	)
	(segment
		(start 42.999914 -24.409908)
		(end 38.735 -28.674822)
		(width 0.2286)
		(layer "In2.Cu")
		(net "FAN_3_PRESENT_R_N")
	)
	(segment
		(start 39.432992 -101.662738)
		(end 46.020482 -101.662738)
		(width 0.2286)
		(layer "In2.Cu")
		(net "FAN_3_PRESENT_R_N")
	)
	(segment
		(start 31.6992 -95.0214)
		(end 35.8648 -99.187)
		(width 0.2286)
		(layer "In2.Cu")
		(net "FAN_3_PRESENT_R_N")
	)
	(segment
		(start 31.37154 -80.79994)
		(end 31.6992 -81.1276)
		(width 0.2286)
		(layer "In2.Cu")
		(net "FAN_3_PRESENT_R_N")
	)
	(segment
		(start 36.957254 -99.187)
		(end 39.432992 -101.662738)
		(width 0.2286)
		(layer "In2.Cu")
		(net "FAN_3_PRESENT_R_N")
	)
	(segment
		(start 47.0662 -137.551414)
		(end 48.579786 -139.065)
		(width 0.2286)
		(layer "In2.Cu")
		(net "FAN_3_PRESENT_R_N")
	)
	(segment
		(start 31.37154 -64.349122)
		(end 31.37154 -80.79994)
		(width 0.2286)
		(layer "In2.Cu")
		(net "FAN_3_PRESENT_R_N")
	)
	(segment
		(start 18.906236 -293.990014)
		(end 18.9103 -293.98595)
		(width 0.2794)
		(layer "F.Cu")
		(net "FAN_7_FAIL_R_LED")
	)
	(segment
		(start 18.9103 -293.98595)
		(end 19.431 -293.98595)
		(width 0.2794)
		(layer "F.Cu")
		(net "FAN_7_FAIL_R_LED")
	)
	(segment
		(start 19.431 -293.98595)
		(end 20.066 -293.98595)
		(width 0.2794)
		(layer "F.Cu")
		(net "FAN_7_FAIL_R_LED")
	)
	(segment
		(start 18.0721 -293.990014)
		(end 18.906236 -293.990014)
		(width 0.2794)
		(layer "F.Cu")
		(net "FAN_7_FAIL_R_LED")
	)
	(segment
		(start 28.55595 -170.561)
		(end 25.726136 -170.561)
		(width 0.2794)
		(layer "F.Cu")
		(net "FAN_7_FAIL_R_LED")
	)
	(via
		(at 25.726136 -170.561)
		(size 0.762)
		(drill 0.254)
		(layers "F.Cu" "B.Cu")
		(net "FAN_7_FAIL_R_LED")
	)
	(via
		(at 20.066 -293.98595)
		(size 0.508)
		(drill 0.254)
		(layers "F.Cu" "B.Cu")
		(net "FAN_7_FAIL_R_LED")
	)
	(segment
		(start 22.479 -183.547766)
		(end 22.479 -189.829694)
		(width 0.2286)
		(layer "In2.Cu")
		(net "FAN_7_FAIL_R_LED")
	)
	(segment
		(start 22.606 -284.987746)
		(end 22.606 -292.481254)
		(width 0.2286)
		(layer "In2.Cu")
		(net "FAN_7_FAIL_R_LED")
	)
	(segment
		(start 22.61362 -189.964314)
		(end 22.61362 -200.34758)
		(width 0.2286)
		(layer "In2.Cu")
		(net "FAN_7_FAIL_R_LED")
	)
	(segment
		(start 25.146 -171.141136)
		(end 25.146 -180.880766)
		(width 0.2286)
		(layer "In2.Cu")
		(net "FAN_7_FAIL_R_LED")
	)
	(segment
		(start 21.101304 -293.98595)
		(end 20.066 -293.98595)
		(width 0.2286)
		(layer "In2.Cu")
		(net "FAN_7_FAIL_R_LED")
	)
	(segment
		(start 22.479 -209.161126)
		(end 22.788626 -209.470752)
		(width 0.2286)
		(layer "In2.Cu")
		(net "FAN_7_FAIL_R_LED")
	)
	(segment
		(start 18.034 -245.87962)
		(end 24.4602 -252.30582)
		(width 0.2286)
		(layer "In2.Cu")
		(net "FAN_7_FAIL_R_LED")
	)
	(segment
		(start 22.61362 -200.34758)
		(end 22.479 -200.4822)
		(width 0.2286)
		(layer "In2.Cu")
		(net "FAN_7_FAIL_R_LED")
	)
	(segment
		(start 18.034 -224.392236)
		(end 18.034 -245.87962)
		(width 0.2286)
		(layer "In2.Cu")
		(net "FAN_7_FAIL_R_LED")
	)
	(segment
		(start 22.479 -200.4822)
		(end 22.479 -209.161126)
		(width 0.2286)
		(layer "In2.Cu")
		(net "FAN_7_FAIL_R_LED")
	)
	(segment
		(start 22.788626 -213.171786)
		(end 23.0886 -213.47176)
		(width 0.2286)
		(layer "In2.Cu")
		(net "FAN_7_FAIL_R_LED")
	)
	(segment
		(start 23.0886 -213.47176)
		(end 23.0886 -219.337636)
		(width 0.2286)
		(layer "In2.Cu")
		(net "FAN_7_FAIL_R_LED")
	)
	(segment
		(start 23.0886 -219.337636)
		(end 18.034 -224.392236)
		(width 0.2286)
		(layer "In2.Cu")
		(net "FAN_7_FAIL_R_LED")
	)
	(segment
		(start 25.726136 -170.561)
		(end 25.146 -171.141136)
		(width 0.2286)
		(layer "In2.Cu")
		(net "FAN_7_FAIL_R_LED")
	)
	(segment
		(start 22.606 -292.481254)
		(end 21.101304 -293.98595)
		(width 0.2286)
		(layer "In2.Cu")
		(net "FAN_7_FAIL_R_LED")
	)
	(segment
		(start 25.146 -180.880766)
		(end 22.479 -183.547766)
		(width 0.2286)
		(layer "In2.Cu")
		(net "FAN_7_FAIL_R_LED")
	)
	(segment
		(start 24.4602 -283.133546)
		(end 22.606 -284.987746)
		(width 0.2286)
		(layer "In2.Cu")
		(net "FAN_7_FAIL_R_LED")
	)
	(segment
		(start 22.788626 -209.470752)
		(end 22.788626 -213.171786)
		(width 0.2286)
		(layer "In2.Cu")
		(net "FAN_7_FAIL_R_LED")
	)
	(segment
		(start 22.479 -189.829694)
		(end 22.61362 -189.964314)
		(width 0.2286)
		(layer "In2.Cu")
		(net "FAN_7_FAIL_R_LED")
	)
	(segment
		(start 24.4602 -252.30582)
		(end 24.4602 -283.133546)
		(width 0.2286)
		(layer "In2.Cu")
		(net "FAN_7_FAIL_R_LED")
	)
	(segment
		(start 40.9956 -29.7942)
		(end 39.147496 -31.642304)
		(width 0.2794)
		(layer "F.Cu")
		(net "FAN_3_PWM_OL_R")
	)
	(segment
		(start 33.952942 -31.623)
		(end 34.079942 -31.496)
		(width 0.2794)
		(layer "F.Cu")
		(net "FAN_3_PWM_OL_R")
	)
	(segment
		(start 35.433254 -31.496)
		(end 35.96005 -32.022796)
		(width 0.2794)
		(layer "F.Cu")
		(net "FAN_3_PWM_OL_R")
	)
	(segment
		(start 34.079942 -31.496)
		(end 35.433254 -31.496)
		(width 0.2794)
		(layer "F.Cu")
		(net "FAN_3_PWM_OL_R")
	)
	(segment
		(start 42.999914 -26.409904)
		(end 40.9956 -28.414218)
		(width 0.2794)
		(layer "F.Cu")
		(net "FAN_3_PWM_OL_R")
	)
	(segment
		(start 38.571932 -32.217868)
		(end 37.86505 -32.217868)
		(width 0.2794)
		(layer "F.Cu")
		(net "FAN_3_PWM_OL_R")
	)
	(segment
		(start 35.96005 -32.217868)
		(end 36.554918 -31.623)
		(width 0.2794)
		(layer "F.Cu")
		(net "FAN_3_PWM_OL_R")
	)
	(segment
		(start 39.147496 -31.642304)
		(end 38.571932 -32.217868)
		(width 0.2794)
		(layer "F.Cu")
		(net "FAN_3_PWM_OL_R")
	)
	(segment
		(start 37.86505 -32.158178)
		(end 37.86505 -32.217868)
		(width 0.2794)
		(layer "F.Cu")
		(net "FAN_3_PWM_OL_R")
	)
	(segment
		(start 40.9956 -28.414218)
		(end 40.9956 -29.7942)
		(width 0.2794)
		(layer "F.Cu")
		(net "FAN_3_PWM_OL_R")
	)
	(segment
		(start 37.329872 -31.623)
		(end 37.86505 -32.158178)
		(width 0.2794)
		(layer "F.Cu")
		(net "FAN_3_PWM_OL_R")
	)
	(segment
		(start 36.554918 -31.623)
		(end 37.329872 -31.623)
		(width 0.2794)
		(layer "F.Cu")
		(net "FAN_3_PWM_OL_R")
	)
	(segment
		(start 35.96005 -32.022796)
		(end 35.96005 -32.217868)
		(width 0.2794)
		(layer "F.Cu")
		(net "FAN_3_PWM_OL_R")
	)
	(via
		(at 39.147496 -31.642304)
		(size 0.762)
		(drill 0.381)
		(layers "F.Cu" "B.Cu")
		(net "FAN_3_PWM_OL_R")
	)
	(segment
		(start 18.80616 -114.031014)
		(end 18.1991 -114.031014)
		(width 0.2794)
		(layer "F.Cu")
		(net "FAN_5_OK_R_LED")
	)
	(segment
		(start 28.55595 -176.022)
		(end 28.55595 -176.5427)
		(width 0.2794)
		(layer "F.Cu")
		(net "FAN_5_OK_R_LED")
	)
	(segment
		(start 28.79725 -176.784)
		(end 29.972 -176.784)
		(width 0.2794)
		(layer "F.Cu")
		(net "FAN_5_OK_R_LED")
	)
	(segment
		(start 20.193 -114.28095)
		(end 19.558 -114.28095)
		(width 0.2794)
		(layer "F.Cu")
		(net "FAN_5_OK_R_LED")
	)
	(segment
		(start 28.55595 -176.5427)
		(end 28.79725 -176.784)
		(width 0.2794)
		(layer "F.Cu")
		(net "FAN_5_OK_R_LED")
	)
	(segment
		(start 19.558 -114.28095)
		(end 19.056096 -114.28095)
		(width 0.2794)
		(layer "F.Cu")
		(net "FAN_5_OK_R_LED")
	)
	(segment
		(start 19.056096 -114.28095)
		(end 18.80616 -114.031014)
		(width 0.2794)
		(layer "F.Cu")
		(net "FAN_5_OK_R_LED")
	)
	(via
		(at 20.193 -114.28095)
		(size 0.508)
		(drill 0.254)
		(layers "F.Cu" "B.Cu")
		(net "FAN_5_OK_R_LED")
	)
	(via
		(at 29.972 -176.784)
		(size 0.508)
		(drill 0.254)
		(layers "F.Cu" "B.Cu")
		(net "FAN_5_OK_R_LED")
	)
	(segment
		(start 26.13406 -132.006086)
		(end 27.23515 -133.107176)
		(width 0.2286)
		(layer "In2.Cu")
		(net "FAN_5_OK_R_LED")
	)
	(segment
		(start 25.5905 -124.142246)
		(end 25.5905 -129.623566)
		(width 0.2286)
		(layer "In2.Cu")
		(net "FAN_5_OK_R_LED")
	)
	(segment
		(start 20.193 -114.28095)
		(end 20.193 -114.30635)
		(width 0.2286)
		(layer "In2.Cu")
		(net "FAN_5_OK_R_LED")
	)
	(segment
		(start 22.479 -118.999)
		(end 22.479 -121.030746)
		(width 0.2286)
		(layer "In2.Cu")
		(net "FAN_5_OK_R_LED")
	)
	(segment
		(start 30.678628 -165.684962)
		(end 30.678628 -176.077372)
		(width 0.2286)
		(layer "In2.Cu")
		(net "FAN_5_OK_R_LED")
	)
	(segment
		(start 25.5905 -129.623566)
		(end 26.13406 -130.167126)
		(width 0.2286)
		(layer "In2.Cu")
		(net "FAN_5_OK_R_LED")
	)
	(segment
		(start 26.6192 -149.453092)
		(end 31.918402 -162.538664)
		(width 0.2286)
		(layer "In2.Cu")
		(net "FAN_5_OK_R_LED")
	)
	(segment
		(start 27.23515 -135.81888)
		(end 26.6192 -136.43483)
		(width 0.2286)
		(layer "In2.Cu")
		(net "FAN_5_OK_R_LED")
	)
	(segment
		(start 31.918402 -162.538664)
		(end 31.918402 -164.445188)
		(width 0.2286)
		(layer "In2.Cu")
		(net "FAN_5_OK_R_LED")
	)
	(segment
		(start 20.460716 -114.574066)
		(end 20.460716 -116.980716)
		(width 0.2286)
		(layer "In2.Cu")
		(net "FAN_5_OK_R_LED")
	)
	(segment
		(start 22.479 -121.030746)
		(end 25.5905 -124.142246)
		(width 0.2286)
		(layer "In2.Cu")
		(net "FAN_5_OK_R_LED")
	)
	(segment
		(start 26.6192 -136.43483)
		(end 26.6192 -149.453092)
		(width 0.2286)
		(layer "In2.Cu")
		(net "FAN_5_OK_R_LED")
	)
	(segment
		(start 27.23515 -133.107176)
		(end 27.23515 -135.81888)
		(width 0.2286)
		(layer "In2.Cu")
		(net "FAN_5_OK_R_LED")
	)
	(segment
		(start 26.13406 -130.167126)
		(end 26.13406 -132.006086)
		(width 0.2286)
		(layer "In2.Cu")
		(net "FAN_5_OK_R_LED")
	)
	(segment
		(start 30.678628 -176.077372)
		(end 29.972 -176.784)
		(width 0.2286)
		(layer "In2.Cu")
		(net "FAN_5_OK_R_LED")
	)
	(segment
		(start 20.193 -114.30635)
		(end 20.460716 -114.574066)
		(width 0.2286)
		(layer "In2.Cu")
		(net "FAN_5_OK_R_LED")
	)
	(segment
		(start 31.918402 -164.445188)
		(end 30.678628 -165.684962)
		(width 0.2286)
		(layer "In2.Cu")
		(net "FAN_5_OK_R_LED")
	)
	(segment
		(start 20.460716 -116.980716)
		(end 22.479 -118.999)
		(width 0.2286)
		(layer "In2.Cu")
		(net "FAN_5_OK_R_LED")
	)
	(segment
		(start 28.42895 -167.64)
		(end 28.55595 -167.513)
		(width 0.2794)
		(layer "F.Cu")
		(net "SMB_PDBV_FAN_SDA")
	)
	(segment
		(start 28.067 -136.40435)
		(end 28.067 -137.668)
		(width 0.2794)
		(layer "F.Cu")
		(net "SMB_PDBV_FAN_SDA")
	)
	(segment
		(start 17.272 -160.833054)
		(end 17.272 -160.42005)
		(width 0.2794)
		(layer "F.Cu")
		(net "SMB_PDBV_FAN_SDA")
	)
	(segment
		(start 19.812 -184.688734)
		(end 19.812 -185.9407)
		(width 0.2794)
		(layer "F.Cu")
		(net "SMB_PDBV_FAN_SDA")
	)
	(segment
		(start 19.983958 -161.87801)
		(end 19.690588 -162.17138)
		(width 0.2794)
		(layer "F.Cu")
		(net "SMB_PDBV_FAN_SDA")
	)
	(segment
		(start 19.812 -185.9407)
		(end 19.1897 -186.563)
		(width 0.2794)
		(layer "F.Cu")
		(net "SMB_PDBV_FAN_SDA")
	)
	(segment
		(start 18.81505 -183.896)
		(end 19.019266 -183.896)
		(width 0.2794)
		(layer "F.Cu")
		(net "SMB_PDBV_FAN_SDA")
	)
	(segment
		(start 25.72385 -14.605)
		(end 26.035 -14.29385)
		(width 0.2794)
		(layer "F.Cu")
		(net "SMB_PDBV_FAN_SDA")
	)
	(segment
		(start 12.075414 -137.7696)
		(end 6.0706 -137.7696)
		(width 0.2794)
		(layer "F.Cu")
		(net "SMB_PDBV_FAN_SDA")
	)
	(segment
		(start 19.150584 -138.303)
		(end 13.363448 -138.303)
		(width 0.2794)
		(layer "F.Cu")
		(net "SMB_PDBV_FAN_SDA")
	)
	(segment
		(start 25.92705 -121.539)
		(end 26.543 -121.539)
		(width 0.2794)
		(layer "F.Cu")
		(net "SMB_PDBV_FAN_SDA")
	)
	(segment
		(start 27.94 -135.78205)
		(end 27.94 -136.27735)
		(width 0.2794)
		(layer "F.Cu")
		(net "SMB_PDBV_FAN_SDA")
	)
	(segment
		(start 19.019266 -183.896)
		(end 19.812 -184.688734)
		(width 0.2794)
		(layer "F.Cu")
		(net "SMB_PDBV_FAN_SDA")
	)
	(segment
		(start 27.94 -136.27735)
		(end 28.067 -136.40435)
		(width 0.2794)
		(layer "F.Cu")
		(net "SMB_PDBV_FAN_SDA")
	)
	(segment
		(start 48.66005 -135.128)
		(end 48.641 -135.10895)
		(width 0.2794)
		(layer "F.Cu")
		(net "SMB_PDBV_FAN_SDA")
	)
	(segment
		(start 24.138128 -167.64)
		(end 28.42895 -167.64)
		(width 0.2794)
		(layer "F.Cu")
		(net "SMB_PDBV_FAN_SDA")
	)
	(segment
		(start 18.610326 -162.17138)
		(end 17.272 -160.833054)
		(width 0.2794)
		(layer "F.Cu")
		(net "SMB_PDBV_FAN_SDA")
	)
	(segment
		(start 19.1897 -186.563)
		(end 18.81505 -186.563)
		(width 0.2794)
		(layer "F.Cu")
		(net "SMB_PDBV_FAN_SDA")
	)
	(segment
		(start 27.686 -138.049)
		(end 27.432 -138.303)
		(width 0.2794)
		(layer "F.Cu")
		(net "SMB_PDBV_FAN_SDA")
	)
	(segment
		(start 48.641 -135.10895)
		(end 48.641 -134.493)
		(width 0.2794)
		(layer "F.Cu")
		(net "SMB_PDBV_FAN_SDA")
	)
	(segment
		(start 6.0706 -137.7696)
		(end 4.826 -136.525)
		(width 0.2794)
		(layer "F.Cu")
		(net "SMB_PDBV_FAN_SDA")
	)
	(segment
		(start 25.370282 -14.605)
		(end 25.72385 -14.605)
		(width 0.2794)
		(layer "F.Cu")
		(net "SMB_PDBV_FAN_SDA")
	)
	(segment
		(start 19.690588 -162.17138)
		(end 18.610326 -162.17138)
		(width 0.2794)
		(layer "F.Cu")
		(net "SMB_PDBV_FAN_SDA")
	)
	(segment
		(start 18.81505 -183.896)
		(end 18.81505 -184.531)
		(width 0.2794)
		(layer "F.Cu")
		(net "SMB_PDBV_FAN_SDA")
	)
	(segment
		(start 13.363448 -138.303)
		(end 12.075414 -137.7696)
		(width 0.2794)
		(layer "F.Cu")
		(net "SMB_PDBV_FAN_SDA")
	)
	(segment
		(start 28.067 -137.668)
		(end 27.686 -138.049)
		(width 0.2794)
		(layer "F.Cu")
		(net "SMB_PDBV_FAN_SDA")
	)
	(segment
		(start 4.826 -136.525)
		(end 4.826 -135.65505)
		(width 0.2794)
		(layer "F.Cu")
		(net "SMB_PDBV_FAN_SDA")
	)
	(segment
		(start 27.432 -138.303)
		(end 19.150584 -138.303)
		(width 0.2794)
		(layer "F.Cu")
		(net "SMB_PDBV_FAN_SDA")
	)
	(via
		(at 18.81505 -184.531)
		(size 0.508)
		(drill 0.254)
		(layers "F.Cu" "B.Cu")
		(net "SMB_PDBV_FAN_SDA")
	)
	(via
		(at 26.543 -121.539)
		(size 0.508)
		(drill 0.254)
		(layers "F.Cu" "B.Cu")
		(net "SMB_PDBV_FAN_SDA")
	)
	(via
		(at 39.116 -119.634)
		(size 0.508)
		(drill 0.254)
		(layers "F.Cu" "B.Cu")
		(net "SMB_PDBV_FAN_SDA")
	)
	(via
		(at 25.370282 -14.605)
		(size 0.508)
		(drill 0.254)
		(layers "F.Cu" "B.Cu")
		(net "SMB_PDBV_FAN_SDA")
	)
	(via
		(at 19.983958 -161.87801)
		(size 0.508)
		(drill 0.254)
		(layers "F.Cu" "B.Cu")
		(net "SMB_PDBV_FAN_SDA")
	)
	(via
		(at 24.138128 -167.64)
		(size 0.508)
		(drill 0.254)
		(layers "F.Cu" "B.Cu")
		(net "SMB_PDBV_FAN_SDA")
	)
	(via
		(at 48.641 -134.493)
		(size 0.508)
		(drill 0.254)
		(layers "F.Cu" "B.Cu")
		(net "SMB_PDBV_FAN_SDA")
	)
	(via
		(at 19.150584 -138.303)
		(size 0.508)
		(drill 0.254)
		(layers "F.Cu" "B.Cu")
		(net "SMB_PDBV_FAN_SDA")
	)
	(via
		(at 27.686 -138.049)
		(size 0.508)
		(drill 0.254)
		(layers "F.Cu" "B.Cu")
		(net "SMB_PDBV_FAN_SDA")
	)
	(segment
		(start 38.845744 -119.904256)
		(end 39.116 -119.634)
		(width 0.2794)
		(layer "B.Cu")
		(net "SMB_PDBV_FAN_SDA")
	)
	(segment
		(start 44.323 -140.462)
		(end 35.433 -140.462)
		(width 0.2794)
		(layer "B.Cu")
		(net "SMB_PDBV_FAN_SDA")
	)
	(segment
		(start 47.752 -135.921496)
		(end 47.752 -137.033)
		(width 0.2794)
		(layer "B.Cu")
		(net "SMB_PDBV_FAN_SDA")
	)
	(segment
		(start 35.433 -140.462)
		(end 33.02 -138.049)
		(width 0.2794)
		(layer "B.Cu")
		(net "SMB_PDBV_FAN_SDA")
	)
	(segment
		(start 48.641 -134.493)
		(end 49.05502 -134.493)
		(width 0.2794)
		(layer "B.Cu")
		(net "SMB_PDBV_FAN_SDA")
	)
	(segment
		(start 49.05502 -134.493)
		(end 50.165 -133.38302)
		(width 0.2794)
		(layer "B.Cu")
		(net "SMB_PDBV_FAN_SDA")
	)
	(segment
		(start 47.752 -137.033)
		(end 44.323 -140.462)
		(width 0.2794)
		(layer "B.Cu")
		(net "SMB_PDBV_FAN_SDA")
	)
	(segment
		(start 27.890724 -119.904256)
		(end 38.845744 -119.904256)
		(width 0.2794)
		(layer "B.Cu")
		(net "SMB_PDBV_FAN_SDA")
	)
	(segment
		(start 48.641 -134.493)
		(end 48.641 -135.032496)
		(width 0.2794)
		(layer "B.Cu")
		(net "SMB_PDBV_FAN_SDA")
	)
	(segment
		(start 50.165 -128.524)
		(end 44.4119 -122.7709)
		(width 0.2794)
		(layer "B.Cu")
		(net "SMB_PDBV_FAN_SDA")
	)
	(segment
		(start 50.165 -133.38302)
		(end 50.165 -128.524)
		(width 0.2794)
		(layer "B.Cu")
		(net "SMB_PDBV_FAN_SDA")
	)
	(segment
		(start 44.4119 -122.7709)
		(end 43.7261 -122.7709)
		(width 0.2794)
		(layer "B.Cu")
		(net "SMB_PDBV_FAN_SDA")
	)
	(segment
		(start 43.7261 -122.7709)
		(end 40.5892 -119.634)
		(width 0.2794)
		(layer "B.Cu")
		(net "SMB_PDBV_FAN_SDA")
	)
	(segment
		(start 26.543 -121.25198)
		(end 27.890724 -119.904256)
		(width 0.2794)
		(layer "B.Cu")
		(net "SMB_PDBV_FAN_SDA")
	)
	(segment
		(start 26.543 -121.539)
		(end 26.543 -121.25198)
		(width 0.2794)
		(layer "B.Cu")
		(net "SMB_PDBV_FAN_SDA")
	)
	(segment
		(start 40.5892 -119.634)
		(end 39.116 -119.634)
		(width 0.2794)
		(layer "B.Cu")
		(net "SMB_PDBV_FAN_SDA")
	)
	(segment
		(start 48.641 -135.032496)
		(end 47.752 -135.921496)
		(width 0.2794)
		(layer "B.Cu")
		(net "SMB_PDBV_FAN_SDA")
	)
	(segment
		(start 33.02 -138.049)
		(end 27.686 -138.049)
		(width 0.2794)
		(layer "B.Cu")
		(net "SMB_PDBV_FAN_SDA")
	)
	(segment
		(start 39.116 -119.634)
		(end 38.989 -119.507)
		(width 0.2286)
		(layer "In2.Cu")
		(net "SMB_PDBV_FAN_SDA")
	)
	(segment
		(start 19.150584 -138.303)
		(end 19.150584 -139.165584)
		(width 0.2286)
		(layer "In2.Cu")
		(net "SMB_PDBV_FAN_SDA")
	)
	(segment
		(start 32.2834 -101.11232)
		(end 27.636216 -96.465136)
		(width 0.2286)
		(layer "In2.Cu")
		(net "SMB_PDBV_FAN_SDA")
	)
	(segment
		(start 24.138128 -165.913308)
		(end 24.138128 -167.64)
		(width 0.2286)
		(layer "In2.Cu")
		(net "SMB_PDBV_FAN_SDA")
	)
	(segment
		(start 27.636216 -96.465136)
		(end 27.636216 -82.830416)
		(width 0.2286)
		(layer "In2.Cu")
		(net "SMB_PDBV_FAN_SDA")
	)
	(segment
		(start 24.138128 -168.689782)
		(end 23.0886 -169.73931)
		(width 0.2286)
		(layer "In2.Cu")
		(net "SMB_PDBV_FAN_SDA")
	)
	(segment
		(start 30.5562 -110.912148)
		(end 30.5562 -105.87736)
		(width 0.2286)
		(layer "In2.Cu")
		(net "SMB_PDBV_FAN_SDA")
	)
	(segment
		(start 20.828 -140.843)
		(end 20.828 -148.596096)
		(width 0.2286)
		(layer "In2.Cu")
		(net "SMB_PDBV_FAN_SDA")
	)
	(segment
		(start 38.989 -119.507)
		(end 38.989 -117.570504)
		(width 0.2286)
		(layer "In2.Cu")
		(net "SMB_PDBV_FAN_SDA")
	)
	(segment
		(start 20.828 -148.596096)
		(end 22.3647 -152.306528)
		(width 0.2286)
		(layer "In2.Cu")
		(net "SMB_PDBV_FAN_SDA")
	)
	(segment
		(start 33.02 -33.273746)
		(end 33.02 -32.05734)
		(width 0.2286)
		(layer "In2.Cu")
		(net "SMB_PDBV_FAN_SDA")
	)
	(segment
		(start 32.318706 -112.674654)
		(end 30.5562 -110.912148)
		(width 0.2286)
		(layer "In2.Cu")
		(net "SMB_PDBV_FAN_SDA")
	)
	(segment
		(start 38.989 -117.570504)
		(end 34.09315 -112.674654)
		(width 0.2286)
		(layer "In2.Cu")
		(net "SMB_PDBV_FAN_SDA")
	)
	(segment
		(start 24.138128 -167.64)
		(end 24.138128 -168.689782)
		(width 0.2286)
		(layer "In2.Cu")
		(net "SMB_PDBV_FAN_SDA")
	)
	(segment
		(start 32.657034 -33.636712)
		(end 33.02 -33.273746)
		(width 0.2286)
		(layer "In2.Cu")
		(net "SMB_PDBV_FAN_SDA")
	)
	(segment
		(start 23.0886 -179.959)
		(end 18.81505 -184.23255)
		(width 0.2286)
		(layer "In2.Cu")
		(net "SMB_PDBV_FAN_SDA")
	)
	(segment
		(start 30.889956 -19.205956)
		(end 30.889956 -18.758662)
		(width 0.2286)
		(layer "In2.Cu")
		(net "SMB_PDBV_FAN_SDA")
	)
	(segment
		(start 19.983958 -161.87801)
		(end 20.10283 -161.87801)
		(width 0.2286)
		(layer "In2.Cu")
		(net "SMB_PDBV_FAN_SDA")
	)
	(segment
		(start 32.2834 -104.15016)
		(end 32.2834 -101.11232)
		(width 0.2286)
		(layer "In2.Cu")
		(net "SMB_PDBV_FAN_SDA")
	)
	(segment
		(start 20.10283 -161.87801)
		(end 24.138128 -165.913308)
		(width 0.2286)
		(layer "In2.Cu")
		(net "SMB_PDBV_FAN_SDA")
	)
	(segment
		(start 18.81505 -184.23255)
		(end 18.81505 -184.531)
		(width 0.2286)
		(layer "In2.Cu")
		(net "SMB_PDBV_FAN_SDA")
	)
	(segment
		(start 27.09418 -82.28838)
		(end 27.09418 -64.654938)
		(width 0.2286)
		(layer "In2.Cu")
		(net "SMB_PDBV_FAN_SDA")
	)
	(segment
		(start 32.657034 -51.219862)
		(end 32.657034 -33.636712)
		(width 0.2286)
		(layer "In2.Cu")
		(net "SMB_PDBV_FAN_SDA")
	)
	(segment
		(start 30.889956 -18.758662)
		(end 26.736294 -14.605)
		(width 0.2286)
		(layer "In2.Cu")
		(net "SMB_PDBV_FAN_SDA")
	)
	(segment
		(start 32.238696 -20.554696)
		(end 30.889956 -19.205956)
		(width 0.2286)
		(layer "In2.Cu")
		(net "SMB_PDBV_FAN_SDA")
	)
	(segment
		(start 26.736294 -14.605)
		(end 25.370282 -14.605)
		(width 0.2286)
		(layer "In2.Cu")
		(net "SMB_PDBV_FAN_SDA")
	)
	(segment
		(start 29.9212 -24.648922)
		(end 32.238696 -22.331426)
		(width 0.2286)
		(layer "In2.Cu")
		(net "SMB_PDBV_FAN_SDA")
	)
	(segment
		(start 22.3647 -159.497268)
		(end 19.983958 -161.87801)
		(width 0.2286)
		(layer "In2.Cu")
		(net "SMB_PDBV_FAN_SDA")
	)
	(segment
		(start 23.0886 -169.73931)
		(end 23.0886 -179.959)
		(width 0.2286)
		(layer "In2.Cu")
		(net "SMB_PDBV_FAN_SDA")
	)
	(segment
		(start 29.9212 -28.95854)
		(end 29.9212 -24.648922)
		(width 0.2286)
		(layer "In2.Cu")
		(net "SMB_PDBV_FAN_SDA")
	)
	(segment
		(start 27.09418 -64.654938)
		(end 32.657034 -51.219862)
		(width 0.2286)
		(layer "In2.Cu")
		(net "SMB_PDBV_FAN_SDA")
	)
	(segment
		(start 19.150584 -139.165584)
		(end 20.828 -140.843)
		(width 0.2286)
		(layer "In2.Cu")
		(net "SMB_PDBV_FAN_SDA")
	)
	(segment
		(start 27.636216 -82.830416)
		(end 27.09418 -82.28838)
		(width 0.2286)
		(layer "In2.Cu")
		(net "SMB_PDBV_FAN_SDA")
	)
	(segment
		(start 30.5562 -105.87736)
		(end 32.2834 -104.15016)
		(width 0.2286)
		(layer "In2.Cu")
		(net "SMB_PDBV_FAN_SDA")
	)
	(segment
		(start 33.02 -32.05734)
		(end 29.9212 -28.95854)
		(width 0.2286)
		(layer "In2.Cu")
		(net "SMB_PDBV_FAN_SDA")
	)
	(segment
		(start 34.09315 -112.674654)
		(end 32.318706 -112.674654)
		(width 0.2286)
		(layer "In2.Cu")
		(net "SMB_PDBV_FAN_SDA")
	)
	(segment
		(start 22.3647 -152.306528)
		(end 22.3647 -159.497268)
		(width 0.2286)
		(layer "In2.Cu")
		(net "SMB_PDBV_FAN_SDA")
	)
	(segment
		(start 32.238696 -22.331426)
		(end 32.238696 -20.554696)
		(width 0.2286)
		(layer "In2.Cu")
		(net "SMB_PDBV_FAN_SDA")
	)
	(segment
		(start 33.67405 -101.4984)
		(end 33.67405 -102.546912)
		(width 0.2794)
		(layer "F.Cu")
		(net "FAN_2_TACH_OL_R")
	)
	(segment
		(start 33.650682 -102.57028)
		(end 33.650682 -103.608632)
		(width 0.2794)
		(layer "F.Cu")
		(net "FAN_2_TACH_OL_R")
	)
	(segment
		(start 33.67405 -102.546912)
		(end 33.650682 -102.57028)
		(width 0.2794)
		(layer "F.Cu")
		(net "FAN_2_TACH_OL_R")
	)
	(segment
		(start 34.35223 -103.435912)
		(end 33.793938 -103.435912)
		(width 0.2794)
		(layer "F.Cu")
		(net "FAN_2_TACH_OL_R")
	)
	(segment
		(start 33.67405 -103.5558)
		(end 33.67405 -103.632)
		(width 0.2794)
		(layer "F.Cu")
		(net "FAN_2_TACH_OL_R")
	)
	(segment
		(start 33.650682 -103.608632)
		(end 33.67405 -103.632)
		(width 0.2794)
		(layer "F.Cu")
		(net "FAN_2_TACH_OL_R")
	)
	(segment
		(start 33.69945 -101.473)
		(end 33.67405 -101.4984)
		(width 0.2794)
		(layer "F.Cu")
		(net "FAN_2_TACH_OL_R")
	)
	(segment
		(start 34.35223 -103.435912)
		(end 35.2298 -103.435912)
		(width 0.2794)
		(layer "F.Cu")
		(net "FAN_2_TACH_OL_R")
	)
	(segment
		(start 33.793938 -103.435912)
		(end 33.67405 -103.5558)
		(width 0.2794)
		(layer "F.Cu")
		(net "FAN_2_TACH_OL_R")
	)
	(via
		(at 34.35223 -103.435912)
		(size 0.508)
		(drill 0.254)
		(layers "F.Cu" "B.Cu")
		(net "FAN_2_TACH_OL_R")
	)
	(segment
		(start 19.558 -22.07895)
		(end 20.193 -22.07895)
		(width 0.2794)
		(layer "F.Cu")
		(net "FAN_4_FAIL_R_LED")
	)
	(segment
		(start 18.1991 -21.956014)
		(end 19.435064 -21.956014)
		(width 0.2794)
		(layer "F.Cu")
		(net "FAN_4_FAIL_R_LED")
	)
	(segment
		(start 31.89605 -176.403)
		(end 32.512 -176.403)
		(width 0.2794)
		(layer "F.Cu")
		(net "FAN_4_FAIL_R_LED")
	)
	(segment
		(start 19.435064 -21.956014)
		(end 19.558 -22.07895)
		(width 0.2794)
		(layer "F.Cu")
		(net "FAN_4_FAIL_R_LED")
	)
	(via
		(at 20.193 -22.07895)
		(size 0.508)
		(drill 0.254)
		(layers "F.Cu" "B.Cu")
		(net "FAN_4_FAIL_R_LED")
	)
	(via
		(at 32.512 -176.403)
		(size 0.508)
		(drill 0.254)
		(layers "F.Cu" "B.Cu")
		(net "FAN_4_FAIL_R_LED")
	)
	(segment
		(start 21.844 -34.071306)
		(end 18.521172 -37.394134)
		(width 0.2286)
		(layer "In2.Cu")
		(net "FAN_4_FAIL_R_LED")
	)
	(segment
		(start 18.521172 -52.012088)
		(end 23.05558 -62.973966)
		(width 0.2286)
		(layer "In2.Cu")
		(net "FAN_4_FAIL_R_LED")
	)
	(segment
		(start 34.6202 -127.484886)
		(end 33.96742 -128.137666)
		(width 0.2286)
		(layer "In2.Cu")
		(net "FAN_4_FAIL_R_LED")
	)
	(segment
		(start 19.558 -26.67)
		(end 20.955 -28.067)
		(width 0.2286)
		(layer "In2.Cu")
		(net "FAN_4_FAIL_R_LED")
	)
	(segment
		(start 33.3756 -157.395672)
		(end 33.73755 -158.274258)
		(width 0.2286)
		(layer "In2.Cu")
		(net "FAN_4_FAIL_R_LED")
	)
	(segment
		(start 33.3756 -145.5166)
		(end 33.3756 -157.395672)
		(width 0.2286)
		(layer "In2.Cu")
		(net "FAN_4_FAIL_R_LED")
	)
	(segment
		(start 32.385 -123.808236)
		(end 34.6202 -126.043436)
		(width 0.2286)
		(layer "In2.Cu")
		(net "FAN_4_FAIL_R_LED")
	)
	(segment
		(start 34.9758 -172.4533)
		(end 32.86252 -174.56658)
		(width 0.2286)
		(layer "In2.Cu")
		(net "FAN_4_FAIL_R_LED")
	)
	(segment
		(start 20.193 -22.07895)
		(end 20.193 -25.019)
		(width 0.2286)
		(layer "In2.Cu")
		(net "FAN_4_FAIL_R_LED")
	)
	(segment
		(start 34.6202 -126.043436)
		(end 34.6202 -127.484886)
		(width 0.2286)
		(layer "In2.Cu")
		(net "FAN_4_FAIL_R_LED")
	)
	(segment
		(start 23.597616 -100.813362)
		(end 24.487378 -101.703124)
		(width 0.2286)
		(layer "In2.Cu")
		(net "FAN_4_FAIL_R_LED")
	)
	(segment
		(start 32.86252 -176.05248)
		(end 32.512 -176.403)
		(width 0.2286)
		(layer "In2.Cu")
		(net "FAN_4_FAIL_R_LED")
	)
	(segment
		(start 33.96742 -140.454888)
		(end 32.639 -141.783308)
		(width 0.2286)
		(layer "In2.Cu")
		(net "FAN_4_FAIL_R_LED")
	)
	(segment
		(start 23.05558 -84.074)
		(end 23.597616 -84.616036)
		(width 0.2286)
		(layer "In2.Cu")
		(net "FAN_4_FAIL_R_LED")
	)
	(segment
		(start 23.597616 -84.616036)
		(end 23.597616 -100.813362)
		(width 0.2286)
		(layer "In2.Cu")
		(net "FAN_4_FAIL_R_LED")
	)
	(segment
		(start 33.73755 -158.293562)
		(end 34.974784 -161.277808)
		(width 0.2286)
		(layer "In2.Cu")
		(net "FAN_4_FAIL_R_LED")
	)
	(segment
		(start 20.193 -25.019)
		(end 19.558 -25.654)
		(width 0.2286)
		(layer "In2.Cu")
		(net "FAN_4_FAIL_R_LED")
	)
	(segment
		(start 24.487378 -114.403632)
		(end 32.385 -122.301254)
		(width 0.2286)
		(layer "In2.Cu")
		(net "FAN_4_FAIL_R_LED")
	)
	(segment
		(start 19.558 -25.654)
		(end 19.558 -26.67)
		(width 0.2286)
		(layer "In2.Cu")
		(net "FAN_4_FAIL_R_LED")
	)
	(segment
		(start 34.9758 -161.280094)
		(end 34.9758 -172.4533)
		(width 0.2286)
		(layer "In2.Cu")
		(net "FAN_4_FAIL_R_LED")
	)
	(segment
		(start 18.521172 -37.394134)
		(end 18.521172 -52.012088)
		(width 0.2286)
		(layer "In2.Cu")
		(net "FAN_4_FAIL_R_LED")
	)
	(segment
		(start 21.844 -32.0294)
		(end 21.844 -34.071306)
		(width 0.2286)
		(layer "In2.Cu")
		(net "FAN_4_FAIL_R_LED")
	)
	(segment
		(start 32.86252 -174.56658)
		(end 32.86252 -176.05248)
		(width 0.2286)
		(layer "In2.Cu")
		(net "FAN_4_FAIL_R_LED")
	)
	(segment
		(start 33.96742 -128.137666)
		(end 33.96742 -140.454888)
		(width 0.2286)
		(layer "In2.Cu")
		(net "FAN_4_FAIL_R_LED")
	)
	(segment
		(start 20.955 -28.067)
		(end 20.955 -31.1404)
		(width 0.2286)
		(layer "In2.Cu")
		(net "FAN_4_FAIL_R_LED")
	)
	(segment
		(start 24.487378 -101.703124)
		(end 24.487378 -114.403632)
		(width 0.2286)
		(layer "In2.Cu")
		(net "FAN_4_FAIL_R_LED")
	)
	(segment
		(start 23.05558 -62.973966)
		(end 23.05558 -84.074)
		(width 0.2286)
		(layer "In2.Cu")
		(net "FAN_4_FAIL_R_LED")
	)
	(segment
		(start 32.639 -144.78)
		(end 33.3756 -145.5166)
		(width 0.2286)
		(layer "In2.Cu")
		(net "FAN_4_FAIL_R_LED")
	)
	(segment
		(start 20.955 -31.1404)
		(end 21.844 -32.0294)
		(width 0.2286)
		(layer "In2.Cu")
		(net "FAN_4_FAIL_R_LED")
	)
	(segment
		(start 34.974784 -161.277808)
		(end 34.9758 -161.280094)
		(width 0.2286)
		(layer "In2.Cu")
		(net "FAN_4_FAIL_R_LED")
	)
	(segment
		(start 32.385 -122.301254)
		(end 32.385 -123.808236)
		(width 0.2286)
		(layer "In2.Cu")
		(net "FAN_4_FAIL_R_LED")
	)
	(segment
		(start 33.73755 -158.274258)
		(end 33.73755 -158.293562)
		(width 0.2286)
		(layer "In2.Cu")
		(net "FAN_4_FAIL_R_LED")
	)
	(segment
		(start 32.639 -141.783308)
		(end 32.639 -144.78)
		(width 0.2286)
		(layer "In2.Cu")
		(net "FAN_4_FAIL_R_LED")
	)
	(segment
		(start 40.824912 -112.452912)
		(end 42.08653 -113.71453)
		(width 0.2794)
		(layer "F.Cu")
		(net "SMB_FAN2_SDA_R")
	)
	(segment
		(start 39.878 -112.452912)
		(end 40.824912 -112.452912)
		(width 0.2794)
		(layer "F.Cu")
		(net "SMB_FAN2_SDA_R")
	)
	(segment
		(start 43.99534 -113.71453)
		(end 44.99991 -112.70996)
		(width 0.2794)
		(layer "F.Cu")
		(net "SMB_FAN2_SDA_R")
	)
	(segment
		(start 39.878 -112.452912)
		(end 37.73805 -112.452912)
		(width 0.2794)
		(layer "F.Cu")
		(net "SMB_FAN2_SDA_R")
	)
	(segment
		(start 42.08653 -113.71453)
		(end 43.99534 -113.71453)
		(width 0.2794)
		(layer "F.Cu")
		(net "SMB_FAN2_SDA_R")
	)
	(via
		(at 39.878 -112.452912)
		(size 0.762)
		(drill 0.381)
		(layers "F.Cu" "B.Cu")
		(net "SMB_FAN2_SDA_R")
	)
	(segment
		(start 43.73626 -169.164)
		(end 45.34535 -169.164)
		(width 0.2794)
		(layer "F.Cu")
		(net "PCA9552_MB1_A2")
	)
	(segment
		(start 42.302938 -168.529)
		(end 43.16095 -168.529)
		(width 0.2794)
		(layer "F.Cu")
		(net "PCA9552_MB1_A2")
	)
	(segment
		(start 42.302938 -168.529)
		(end 41.530016 -169.301922)
		(width 0.2794)
		(layer "F.Cu")
		(net "PCA9552_MB1_A2")
	)
	(segment
		(start 45.34535 -169.164)
		(end 45.95495 -168.5544)
		(width 0.2794)
		(layer "F.Cu")
		(net "PCA9552_MB1_A2")
	)
	(segment
		(start 43.16095 -168.58869)
		(end 43.73626 -169.164)
		(width 0.2794)
		(layer "F.Cu")
		(net "PCA9552_MB1_A2")
	)
	(segment
		(start 43.16095 -168.529)
		(end 43.16095 -168.58869)
		(width 0.2794)
		(layer "F.Cu")
		(net "PCA9552_MB1_A2")
	)
	(segment
		(start 41.530016 -169.301922)
		(end 39.243 -169.301922)
		(width 0.2794)
		(layer "F.Cu")
		(net "PCA9552_MB1_A2")
	)
	(segment
		(start 45.95495 -168.5544)
		(end 45.95495 -168.529)
		(width 0.2794)
		(layer "F.Cu")
		(net "PCA9552_MB1_A2")
	)
	(via
		(at 42.302938 -168.529)
		(size 0.508)
		(drill 0.254)
		(layers "F.Cu" "B.Cu")
		(net "PCA9552_MB1_A2")
	)
	(segment
		(start 20.701 -184.055766)
		(end 20.701 -186.309)
		(width 0.2794)
		(layer "F.Cu")
		(net "SMB_PDBV_FAN_SCL")
	)
	(segment
		(start 24.449278 -14.451584)
		(end 24.384 -14.29385)
		(width 0.2794)
		(layer "F.Cu")
		(net "SMB_PDBV_FAN_SCL")
	)
	(segment
		(start 6.4516 -136.8806)
		(end 5.842 -136.271)
		(width 0.2794)
		(layer "F.Cu")
		(net "SMB_PDBV_FAN_SCL")
	)
	(segment
		(start 13.540486 -137.414)
		(end 12.252452 -136.8806)
		(width 0.2794)
		(layer "F.Cu")
		(net "SMB_PDBV_FAN_SCL")
	)
	(segment
		(start 26.924 -135.78205)
		(end 26.924 -136.525)
		(width 0.2794)
		(layer "F.Cu")
		(net "SMB_PDBV_FAN_SCL")
	)
	(segment
		(start 5.842 -136.271)
		(end 5.842 -135.65505)
		(width 0.2794)
		(layer "F.Cu")
		(net "SMB_PDBV_FAN_SCL")
	)
	(segment
		(start 18.90649 -161.03854)
		(end 18.288 -160.42005)
		(width 0.2794)
		(layer "F.Cu")
		(net "SMB_PDBV_FAN_SCL")
	)
	(segment
		(start 20.701 -186.309)
		(end 19.431 -187.579)
		(width 0.2794)
		(layer "F.Cu")
		(net "SMB_PDBV_FAN_SCL")
	)
	(segment
		(start 18.81505 -182.626)
		(end 18.81505 -183.261)
		(width 0.2794)
		(layer "F.Cu")
		(net "SMB_PDBV_FAN_SCL")
	)
	(segment
		(start 12.252452 -136.8806)
		(end 6.4516 -136.8806)
		(width 0.2794)
		(layer "F.Cu")
		(net "SMB_PDBV_FAN_SCL")
	)
	(segment
		(start 23.249128 -168.468294)
		(end 23.694644 -168.468294)
		(width 0.2794)
		(layer "F.Cu")
		(net "SMB_PDBV_FAN_SCL")
	)
	(segment
		(start 27.432 -137.033)
		(end 27.051 -137.414)
		(width 0.2794)
		(layer "F.Cu")
		(net "SMB_PDBV_FAN_SCL")
	)
	(segment
		(start 25.92705 -122.78995)
		(end 26.543 -122.78995)
		(width 0.2794)
		(layer "F.Cu")
		(net "SMB_PDBV_FAN_SCL")
	)
	(segment
		(start 48.66005 -133.731)
		(end 48.66005 -133.096)
		(width 0.2794)
		(layer "F.Cu")
		(net "SMB_PDBV_FAN_SCL")
	)
	(segment
		(start 25.146 -15.494)
		(end 24.449278 -14.451584)
		(width 0.2794)
		(layer "F.Cu")
		(net "SMB_PDBV_FAN_SCL")
	)
	(segment
		(start 26.924 -136.525)
		(end 27.432 -137.033)
		(width 0.2794)
		(layer "F.Cu")
		(net "SMB_PDBV_FAN_SCL")
	)
	(segment
		(start 18.415 -137.541)
		(end 18.288 -137.414)
		(width 0.2794)
		(layer "F.Cu")
		(net "SMB_PDBV_FAN_SCL")
	)
	(segment
		(start 23.75535 -168.529)
		(end 28.55595 -168.529)
		(width 0.2794)
		(layer "F.Cu")
		(net "SMB_PDBV_FAN_SCL")
	)
	(segment
		(start 19.431 -187.579)
		(end 18.81505 -187.579)
		(width 0.2794)
		(layer "F.Cu")
		(net "SMB_PDBV_FAN_SCL")
	)
	(segment
		(start 18.542 -137.414)
		(end 18.415 -137.541)
		(width 0.2794)
		(layer "F.Cu")
		(net "SMB_PDBV_FAN_SCL")
	)
	(segment
		(start 19.928078 -161.03854)
		(end 18.90649 -161.03854)
		(width 0.2794)
		(layer "F.Cu")
		(net "SMB_PDBV_FAN_SCL")
	)
	(segment
		(start 23.694644 -168.468294)
		(end 23.75535 -168.529)
		(width 0.2794)
		(layer "F.Cu")
		(net "SMB_PDBV_FAN_SCL")
	)
	(segment
		(start 18.81505 -182.626)
		(end 19.271234 -182.626)
		(width 0.2794)
		(layer "F.Cu")
		(net "SMB_PDBV_FAN_SCL")
	)
	(segment
		(start 27.051 -137.414)
		(end 18.542 -137.414)
		(width 0.2794)
		(layer "F.Cu")
		(net "SMB_PDBV_FAN_SCL")
	)
	(segment
		(start 18.288 -137.414)
		(end 13.540486 -137.414)
		(width 0.2794)
		(layer "F.Cu")
		(net "SMB_PDBV_FAN_SCL")
	)
	(segment
		(start 19.271234 -182.626)
		(end 20.701 -184.055766)
		(width 0.2794)
		(layer "F.Cu")
		(net "SMB_PDBV_FAN_SCL")
	)
	(via
		(at 38.51529 -120.955308)
		(size 0.508)
		(drill 0.254)
		(layers "F.Cu" "B.Cu")
		(net "SMB_PDBV_FAN_SCL")
	)
	(via
		(at 23.249128 -168.468294)
		(size 0.508)
		(drill 0.254)
		(layers "F.Cu" "B.Cu")
		(net "SMB_PDBV_FAN_SCL")
	)
	(via
		(at 18.81505 -183.261)
		(size 0.508)
		(drill 0.254)
		(layers "F.Cu" "B.Cu")
		(net "SMB_PDBV_FAN_SCL")
	)
	(via
		(at 19.928078 -161.03854)
		(size 0.508)
		(drill 0.254)
		(layers "F.Cu" "B.Cu")
		(net "SMB_PDBV_FAN_SCL")
	)
	(via
		(at 26.543 -122.78995)
		(size 0.508)
		(drill 0.254)
		(layers "F.Cu" "B.Cu")
		(net "SMB_PDBV_FAN_SCL")
	)
	(via
		(at 48.66005 -133.096)
		(size 0.508)
		(drill 0.254)
		(layers "F.Cu" "B.Cu")
		(net "SMB_PDBV_FAN_SCL")
	)
	(via
		(at 25.146 -15.494)
		(size 0.508)
		(drill 0.254)
		(layers "F.Cu" "B.Cu")
		(net "SMB_PDBV_FAN_SCL")
	)
	(via
		(at 27.432 -137.033)
		(size 0.508)
		(drill 0.254)
		(layers "F.Cu" "B.Cu")
		(net "SMB_PDBV_FAN_SCL")
	)
	(via
		(at 18.415 -137.541)
		(size 0.508)
		(drill 0.254)
		(layers "F.Cu" "B.Cu")
		(net "SMB_PDBV_FAN_SCL")
	)
	(segment
		(start 28.910026 -121.7041)
		(end 29.658818 -120.955308)
		(width 0.2794)
		(layer "B.Cu")
		(net "SMB_PDBV_FAN_SCL")
	)
	(segment
		(start 46.736 -136.612122)
		(end 46.736 -135.382)
		(width 0.2794)
		(layer "B.Cu")
		(net "SMB_PDBV_FAN_SCL")
	)
	(segment
		(start 35.8013 -139.573)
		(end 43.775122 -139.573)
		(width 0.2794)
		(layer "B.Cu")
		(net "SMB_PDBV_FAN_SCL")
	)
	(segment
		(start 40.437308 -120.955308)
		(end 43.18 -123.698)
		(width 0.2794)
		(layer "B.Cu")
		(net "SMB_PDBV_FAN_SCL")
	)
	(segment
		(start 27.432 -137.033)
		(end 27.559 -137.16)
		(width 0.2794)
		(layer "B.Cu")
		(net "SMB_PDBV_FAN_SCL")
	)
	(segment
		(start 46.736 -135.382)
		(end 48.66005 -133.45795)
		(width 0.2794)
		(layer "B.Cu")
		(net "SMB_PDBV_FAN_SCL")
	)
	(segment
		(start 49.239424 -128.855724)
		(end 49.239424 -132.516626)
		(width 0.2794)
		(layer "B.Cu")
		(net "SMB_PDBV_FAN_SCL")
	)
	(segment
		(start 27.62885 -121.7041)
		(end 28.910026 -121.7041)
		(width 0.2794)
		(layer "B.Cu")
		(net "SMB_PDBV_FAN_SCL")
	)
	(segment
		(start 33.3883 -137.16)
		(end 35.8013 -139.573)
		(width 0.2794)
		(layer "B.Cu")
		(net "SMB_PDBV_FAN_SCL")
	)
	(segment
		(start 49.239424 -132.516626)
		(end 48.66005 -133.096)
		(width 0.2794)
		(layer "B.Cu")
		(net "SMB_PDBV_FAN_SCL")
	)
	(segment
		(start 27.559 -137.16)
		(end 33.3883 -137.16)
		(width 0.2794)
		(layer "B.Cu")
		(net "SMB_PDBV_FAN_SCL")
	)
	(segment
		(start 26.543 -122.78995)
		(end 27.62885 -121.7041)
		(width 0.2794)
		(layer "B.Cu")
		(net "SMB_PDBV_FAN_SCL")
	)
	(segment
		(start 29.658818 -120.955308)
		(end 38.51529 -120.955308)
		(width 0.2794)
		(layer "B.Cu")
		(net "SMB_PDBV_FAN_SCL")
	)
	(segment
		(start 38.51529 -120.955308)
		(end 40.437308 -120.955308)
		(width 0.2794)
		(layer "B.Cu")
		(net "SMB_PDBV_FAN_SCL")
	)
	(segment
		(start 48.66005 -133.45795)
		(end 48.66005 -133.096)
		(width 0.2794)
		(layer "B.Cu")
		(net "SMB_PDBV_FAN_SCL")
	)
	(segment
		(start 43.775122 -139.573)
		(end 46.736 -136.612122)
		(width 0.2794)
		(layer "B.Cu")
		(net "SMB_PDBV_FAN_SCL")
	)
	(segment
		(start 43.18 -123.698)
		(end 44.0817 -123.698)
		(width 0.2794)
		(layer "B.Cu")
		(net "SMB_PDBV_FAN_SCL")
	)
	(segment
		(start 44.0817 -123.698)
		(end 49.239424 -128.855724)
		(width 0.2794)
		(layer "B.Cu")
		(net "SMB_PDBV_FAN_SCL")
	)
	(segment
		(start 19.928078 -160.943036)
		(end 21.6789 -159.192214)
		(width 0.2286)
		(layer "In2.Cu")
		(net "SMB_PDBV_FAN_SCL")
	)
	(segment
		(start 28.289758 -17.145)
		(end 30.178756 -19.033998)
		(width 0.2286)
		(layer "In2.Cu")
		(net "SMB_PDBV_FAN_SCL")
	)
	(segment
		(start 32.021526 -113.360454)
		(end 33.808924 -113.360454)
		(width 0.2286)
		(layer "In2.Cu")
		(net "SMB_PDBV_FAN_SCL")
	)
	(segment
		(start 22.3774 -179.69865)
		(end 18.81505 -183.261)
		(width 0.2286)
		(layer "In2.Cu")
		(net "SMB_PDBV_FAN_SCL")
	)
	(segment
		(start 29.8704 -111.209328)
		(end 32.021526 -113.360454)
		(width 0.2286)
		(layer "In2.Cu")
		(net "SMB_PDBV_FAN_SCL")
	)
	(segment
		(start 31.552896 -22.0472)
		(end 29.2354 -24.364696)
		(width 0.2286)
		(layer "In2.Cu")
		(net "SMB_PDBV_FAN_SCL")
	)
	(segment
		(start 37.897308 -120.337326)
		(end 38.51529 -120.955308)
		(width 0.2286)
		(layer "In2.Cu")
		(net "SMB_PDBV_FAN_SCL")
	)
	(segment
		(start 31.971234 -51.08321)
		(end 26.40838 -64.518032)
		(width 0.2286)
		(layer "In2.Cu")
		(net "SMB_PDBV_FAN_SCL")
	)
	(segment
		(start 26.950416 -96.774762)
		(end 31.496 -101.320346)
		(width 0.2286)
		(layer "In2.Cu")
		(net "SMB_PDBV_FAN_SCL")
	)
	(segment
		(start 30.178756 -19.033998)
		(end 30.178756 -19.464782)
		(width 0.2286)
		(layer "In2.Cu")
		(net "SMB_PDBV_FAN_SCL")
	)
	(segment
		(start 25.526746 -17.145)
		(end 28.289758 -17.145)
		(width 0.2286)
		(layer "In2.Cu")
		(net "SMB_PDBV_FAN_SCL")
	)
	(segment
		(start 31.75 -31.757366)
		(end 31.75 -33.528254)
		(width 0.2286)
		(layer "In2.Cu")
		(net "SMB_PDBV_FAN_SCL")
	)
	(segment
		(start 23.249128 -166.079678)
		(end 23.249128 -168.468294)
		(width 0.2286)
		(layer "In2.Cu")
		(net "SMB_PDBV_FAN_SCL")
	)
	(segment
		(start 29.8704 -105.084626)
		(end 29.8704 -111.209328)
		(width 0.2286)
		(layer "In2.Cu")
		(net "SMB_PDBV_FAN_SCL")
	)
	(segment
		(start 19.405854 -162.236404)
		(end 23.249128 -166.079678)
		(width 0.2286)
		(layer "In2.Cu")
		(net "SMB_PDBV_FAN_SCL")
	)
	(segment
		(start 22.3774 -169.340022)
		(end 22.3774 -179.69865)
		(width 0.2286)
		(layer "In2.Cu")
		(net "SMB_PDBV_FAN_SCL")
	)
	(segment
		(start 31.496 -102.996746)
		(end 30.4038 -104.088946)
		(width 0.2286)
		(layer "In2.Cu")
		(net "SMB_PDBV_FAN_SCL")
	)
	(segment
		(start 30.178756 -19.464782)
		(end 31.552896 -20.838922)
		(width 0.2286)
		(layer "In2.Cu")
		(net "SMB_PDBV_FAN_SCL")
	)
	(segment
		(start 33.808924 -113.360454)
		(end 37.897308 -117.448838)
		(width 0.2286)
		(layer "In2.Cu")
		(net "SMB_PDBV_FAN_SCL")
	)
	(segment
		(start 20.1422 -141.1732)
		(end 18.415 -139.446)
		(width 0.2286)
		(layer "In2.Cu")
		(net "SMB_PDBV_FAN_SCL")
	)
	(segment
		(start 21.6789 -152.442926)
		(end 20.1422 -148.732494)
		(width 0.2286)
		(layer "In2.Cu")
		(net "SMB_PDBV_FAN_SCL")
	)
	(segment
		(start 31.971234 -33.749488)
		(end 31.971234 -51.08321)
		(width 0.2286)
		(layer "In2.Cu")
		(net "SMB_PDBV_FAN_SCL")
	)
	(segment
		(start 19.928078 -161.03854)
		(end 19.928078 -160.943036)
		(width 0.2286)
		(layer "In2.Cu")
		(net "SMB_PDBV_FAN_SCL")
	)
	(segment
		(start 31.496 -101.320346)
		(end 31.496 -102.996746)
		(width 0.2286)
		(layer "In2.Cu")
		(net "SMB_PDBV_FAN_SCL")
	)
	(segment
		(start 30.4038 -104.088946)
		(end 30.4038 -104.551226)
		(width 0.2286)
		(layer "In2.Cu")
		(net "SMB_PDBV_FAN_SCL")
	)
	(segment
		(start 26.40838 -82.644234)
		(end 26.950416 -83.18627)
		(width 0.2286)
		(layer "In2.Cu")
		(net "SMB_PDBV_FAN_SCL")
	)
	(segment
		(start 19.405854 -161.482532)
		(end 19.405854 -162.236404)
		(width 0.2286)
		(layer "In2.Cu")
		(net "SMB_PDBV_FAN_SCL")
	)
	(segment
		(start 23.249128 -168.468294)
		(end 22.3774 -169.340022)
		(width 0.2286)
		(layer "In2.Cu")
		(net "SMB_PDBV_FAN_SCL")
	)
	(segment
		(start 20.1422 -148.732494)
		(end 20.1422 -141.1732)
		(width 0.2286)
		(layer "In2.Cu")
		(net "SMB_PDBV_FAN_SCL")
	)
	(segment
		(start 26.950416 -83.18627)
		(end 26.950416 -96.774762)
		(width 0.2286)
		(layer "In2.Cu")
		(net "SMB_PDBV_FAN_SCL")
	)
	(segment
		(start 19.849846 -161.03854)
		(end 19.405854 -161.482532)
		(width 0.2286)
		(layer "In2.Cu")
		(net "SMB_PDBV_FAN_SCL")
	)
	(segment
		(start 29.2354 -29.242766)
		(end 31.75 -31.757366)
		(width 0.2286)
		(layer "In2.Cu")
		(net "SMB_PDBV_FAN_SCL")
	)
	(segment
		(start 30.4038 -104.551226)
		(end 29.8704 -105.084626)
		(width 0.2286)
		(layer "In2.Cu")
		(net "SMB_PDBV_FAN_SCL")
	)
	(segment
		(start 26.40838 -64.518032)
		(end 26.40838 -82.644234)
		(width 0.2286)
		(layer "In2.Cu")
		(net "SMB_PDBV_FAN_SCL")
	)
	(segment
		(start 19.928078 -161.03854)
		(end 19.849846 -161.03854)
		(width 0.2286)
		(layer "In2.Cu")
		(net "SMB_PDBV_FAN_SCL")
	)
	(segment
		(start 21.6789 -159.192214)
		(end 21.6789 -152.442926)
		(width 0.2286)
		(layer "In2.Cu")
		(net "SMB_PDBV_FAN_SCL")
	)
	(segment
		(start 25.146 -16.764254)
		(end 25.526746 -17.145)
		(width 0.2286)
		(layer "In2.Cu")
		(net "SMB_PDBV_FAN_SCL")
	)
	(segment
		(start 31.552896 -20.838922)
		(end 31.552896 -22.0472)
		(width 0.2286)
		(layer "In2.Cu")
		(net "SMB_PDBV_FAN_SCL")
	)
	(segment
		(start 29.2354 -24.364696)
		(end 29.2354 -29.242766)
		(width 0.2286)
		(layer "In2.Cu")
		(net "SMB_PDBV_FAN_SCL")
	)
	(segment
		(start 37.897308 -117.448838)
		(end 37.897308 -120.337326)
		(width 0.2286)
		(layer "In2.Cu")
		(net "SMB_PDBV_FAN_SCL")
	)
	(segment
		(start 31.75 -33.528254)
		(end 31.971234 -33.749488)
		(width 0.2286)
		(layer "In2.Cu")
		(net "SMB_PDBV_FAN_SCL")
	)
	(segment
		(start 18.415 -139.446)
		(end 18.415 -137.541)
		(width 0.2286)
		(layer "In2.Cu")
		(net "SMB_PDBV_FAN_SCL")
	)
	(segment
		(start 25.146 -15.494)
		(end 25.146 -16.764254)
		(width 0.2286)
		(layer "In2.Cu")
		(net "SMB_PDBV_FAN_SCL")
	)
	(segment
		(start 37.86505 -304.10531)
		(end 37.86505 -304.165)
		(width 0.2794)
		(layer "F.Cu")
		(net "FAN_0_PWM_OL_R")
	)
	(segment
		(start 35.70605 -304.27295)
		(end 35.70605 -304.165)
		(width 0.2794)
		(layer "F.Cu")
		(net "FAN_0_PWM_OL_R")
	)
	(segment
		(start 42.14495 -304.165)
		(end 42.999914 -303.310036)
		(width 0.2794)
		(layer "F.Cu")
		(net "FAN_0_PWM_OL_R")
	)
	(segment
		(start 36.257738 -303.53)
		(end 37.28974 -303.53)
		(width 0.2794)
		(layer "F.Cu")
		(net "FAN_0_PWM_OL_R")
	)
	(segment
		(start 35.70605 -304.081688)
		(end 36.257738 -303.53)
		(width 0.2794)
		(layer "F.Cu")
		(net "FAN_0_PWM_OL_R")
	)
	(segment
		(start 34.118042 -304.8381)
		(end 35.1409 -304.8381)
		(width 0.2794)
		(layer "F.Cu")
		(net "FAN_0_PWM_OL_R")
	)
	(segment
		(start 33.317942 -304.292)
		(end 33.571942 -304.292)
		(width 0.2794)
		(layer "F.Cu")
		(net "FAN_0_PWM_OL_R")
	)
	(segment
		(start 35.1409 -304.8381)
		(end 35.70605 -304.27295)
		(width 0.2794)
		(layer "F.Cu")
		(net "FAN_0_PWM_OL_R")
	)
	(segment
		(start 35.70605 -304.165)
		(end 35.70605 -304.081688)
		(width 0.2794)
		(layer "F.Cu")
		(net "FAN_0_PWM_OL_R")
	)
	(segment
		(start 37.28974 -303.53)
		(end 37.86505 -304.10531)
		(width 0.2794)
		(layer "F.Cu")
		(net "FAN_0_PWM_OL_R")
	)
	(segment
		(start 40.005 -304.165)
		(end 42.14495 -304.165)
		(width 0.2794)
		(layer "F.Cu")
		(net "FAN_0_PWM_OL_R")
	)
	(segment
		(start 37.86505 -304.165)
		(end 40.005 -304.165)
		(width 0.2794)
		(layer "F.Cu")
		(net "FAN_0_PWM_OL_R")
	)
	(segment
		(start 33.571942 -304.292)
		(end 34.118042 -304.8381)
		(width 0.2794)
		(layer "F.Cu")
		(net "FAN_0_PWM_OL_R")
	)
	(via
		(at 40.005 -304.165)
		(size 0.762)
		(drill 0.381)
		(layers "F.Cu" "B.Cu")
		(net "FAN_0_PWM_OL_R")
	)
	(segment
		(start 38.75659 -115.757452)
		(end 37.73805 -114.738912)
		(width 0.2794)
		(layer "F.Cu")
		(net "FAN_2_PWM_IL_R")
	)
	(segment
		(start 33.923986 -115.316)
		(end 35.080956 -115.316)
		(width 0.2794)
		(layer "F.Cu")
		(net "FAN_2_PWM_IL_R")
	)
	(segment
		(start 35.57905 -114.817906)
		(end 35.57905 -114.738912)
		(width 0.2794)
		(layer "F.Cu")
		(net "FAN_2_PWM_IL_R")
	)
	(segment
		(start 39.878 -115.757452)
		(end 38.75659 -115.757452)
		(width 0.2794)
		(layer "F.Cu")
		(net "FAN_2_PWM_IL_R")
	)
	(segment
		(start 35.080956 -115.316)
		(end 35.57905 -114.817906)
		(width 0.2794)
		(layer "F.Cu")
		(net "FAN_2_PWM_IL_R")
	)
	(segment
		(start 39.923212 -115.71224)
		(end 39.878 -115.757452)
		(width 0.2794)
		(layer "F.Cu")
		(net "FAN_2_PWM_IL_R")
	)
	(segment
		(start 44.99991 -116.709952)
		(end 44.680886 -116.709952)
		(width 0.2794)
		(layer "F.Cu")
		(net "FAN_2_PWM_IL_R")
	)
	(segment
		(start 33.317942 -114.709956)
		(end 33.923986 -115.316)
		(width 0.2794)
		(layer "F.Cu")
		(net "FAN_2_PWM_IL_R")
	)
	(segment
		(start 37.73805 -114.798602)
		(end 37.21354 -115.323112)
		(width 0.2794)
		(layer "F.Cu")
		(net "FAN_2_PWM_IL_R")
	)
	(segment
		(start 37.21354 -115.323112)
		(end 36.084256 -115.323112)
		(width 0.2794)
		(layer "F.Cu")
		(net "FAN_2_PWM_IL_R")
	)
	(segment
		(start 37.73805 -114.738912)
		(end 37.73805 -114.798602)
		(width 0.2794)
		(layer "F.Cu")
		(net "FAN_2_PWM_IL_R")
	)
	(segment
		(start 43.683174 -115.71224)
		(end 39.923212 -115.71224)
		(width 0.2794)
		(layer "F.Cu")
		(net "FAN_2_PWM_IL_R")
	)
	(segment
		(start 44.680886 -116.709952)
		(end 43.683174 -115.71224)
		(width 0.2794)
		(layer "F.Cu")
		(net "FAN_2_PWM_IL_R")
	)
	(segment
		(start 36.084256 -115.323112)
		(end 35.57905 -114.817906)
		(width 0.2794)
		(layer "F.Cu")
		(net "FAN_2_PWM_IL_R")
	)
	(via
		(at 39.878 -115.757452)
		(size 0.762)
		(drill 0.381)
		(layers "F.Cu" "B.Cu")
		(net "FAN_2_PWM_IL_R")
	)
	(segment
		(start 45.53585 -166.8399)
		(end 43.682158 -166.8399)
		(width 0.2794)
		(layer "F.Cu")
		(net "PCA9552_MB1_A1")
	)
	(segment
		(start 41.314878 -168.651936)
		(end 39.243 -168.651936)
		(width 0.2794)
		(layer "F.Cu")
		(net "PCA9552_MB1_A1")
	)
	(segment
		(start 43.682158 -166.8399)
		(end 43.16095 -167.361108)
		(width 0.2794)
		(layer "F.Cu")
		(net "PCA9552_MB1_A1")
	)
	(segment
		(start 43.16095 -167.513)
		(end 42.453814 -167.513)
		(width 0.2794)
		(layer "F.Cu")
		(net "PCA9552_MB1_A1")
	)
	(segment
		(start 42.453814 -167.513)
		(end 41.314878 -168.651936)
		(width 0.2794)
		(layer "F.Cu")
		(net "PCA9552_MB1_A1")
	)
	(segment
		(start 45.95495 -167.513)
		(end 45.95495 -167.259)
		(width 0.2794)
		(layer "F.Cu")
		(net "PCA9552_MB1_A1")
	)
	(segment
		(start 45.95495 -167.259)
		(end 45.53585 -166.8399)
		(width 0.2794)
		(layer "F.Cu")
		(net "PCA9552_MB1_A1")
	)
	(segment
		(start 43.16095 -167.361108)
		(end 43.16095 -167.513)
		(width 0.2794)
		(layer "F.Cu")
		(net "PCA9552_MB1_A1")
	)
	(via
		(at 43.682158 -166.8399)
		(size 0.508)
		(drill 0.254)
		(layers "F.Cu" "B.Cu")
		(net "PCA9552_MB1_A1")
	)
	(segment
		(start 33.2486 -116.332)
		(end 33.2486 -117.094)
		(width 0.2794)
		(layer "F.Cu")
		(net "FAN_2_TACH_IL_R")
	)
	(segment
		(start 34.29 -117.602)
		(end 35.2298 -117.602)
		(width 0.2794)
		(layer "F.Cu")
		(net "FAN_2_TACH_IL_R")
	)
	(segment
		(start 33.42005 -116.16055)
		(end 33.2486 -116.332)
		(width 0.2794)
		(layer "F.Cu")
		(net "FAN_2_TACH_IL_R")
	)
	(segment
		(start 34.0106 -118.237)
		(end 33.42005 -118.237)
		(width 0.2794)
		(layer "F.Cu")
		(net "FAN_2_TACH_IL_R")
	)
	(segment
		(start 34.29 -117.9576)
		(end 34.0106 -118.237)
		(width 0.2794)
		(layer "F.Cu")
		(net "FAN_2_TACH_IL_R")
	)
	(segment
		(start 33.2486 -117.094)
		(end 33.2486 -118.06555)
		(width 0.2794)
		(layer "F.Cu")
		(net "FAN_2_TACH_IL_R")
	)
	(segment
		(start 33.2486 -118.06555)
		(end 33.42005 -118.237)
		(width 0.2794)
		(layer "F.Cu")
		(net "FAN_2_TACH_IL_R")
	)
	(segment
		(start 33.42005 -116.008912)
		(end 33.42005 -116.16055)
		(width 0.2794)
		(layer "F.Cu")
		(net "FAN_2_TACH_IL_R")
	)
	(segment
		(start 34.29 -117.602)
		(end 34.29 -117.9576)
		(width 0.2794)
		(layer "F.Cu")
		(net "FAN_2_TACH_IL_R")
	)
	(via
		(at 34.29 -117.602)
		(size 0.508)
		(drill 0.254)
		(layers "F.Cu" "B.Cu")
		(net "FAN_2_TACH_IL_R")
	)
	(segment
		(start 43.16095 -165.5064)
		(end 43.16095 -165.481)
		(width 0.2794)
		(layer "F.Cu")
		(net "PCA9552_MB1_A0")
	)
	(segment
		(start 45.95495 -165.608)
		(end 45.95495 -165.6334)
		(width 0.2794)
		(layer "F.Cu")
		(net "PCA9552_MB1_A0")
	)
	(segment
		(start 43.16095 -165.716204)
		(end 43.16095 -165.5064)
		(width 0.2794)
		(layer "F.Cu")
		(net "PCA9552_MB1_A0")
	)
	(segment
		(start 40.6654 -168.00195)
		(end 41.694608 -166.972742)
		(width 0.2794)
		(layer "F.Cu")
		(net "PCA9552_MB1_A0")
	)
	(segment
		(start 43.700446 -166.2557)
		(end 43.16095 -165.716204)
		(width 0.2794)
		(layer "F.Cu")
		(net "PCA9552_MB1_A0")
	)
	(segment
		(start 39.243 -168.00195)
		(end 40.6654 -168.00195)
		(width 0.2794)
		(layer "F.Cu")
		(net "PCA9552_MB1_A0")
	)
	(segment
		(start 41.694608 -166.972742)
		(end 43.16095 -165.5064)
		(width 0.2794)
		(layer "F.Cu")
		(net "PCA9552_MB1_A0")
	)
	(segment
		(start 45.33265 -166.2557)
		(end 43.700446 -166.2557)
		(width 0.2794)
		(layer "F.Cu")
		(net "PCA9552_MB1_A0")
	)
	(segment
		(start 45.95495 -165.6334)
		(end 45.33265 -166.2557)
		(width 0.2794)
		(layer "F.Cu")
		(net "PCA9552_MB1_A0")
	)
	(via
		(at 41.694608 -166.972742)
		(size 0.762)
		(drill 0.381)
		(layers "F.Cu" "B.Cu")
		(net "PCA9552_MB1_A0")
	)
	(segment
		(start 36.746942 -102.532688)
		(end 37.4142 -103.199946)
		(width 0.2794)
		(layer "F.Cu")
		(net "FAN_2_TACH_OL_D")
	)
	(segment
		(start 40.82034 -105.71734)
		(end 44.007278 -105.71734)
		(width 0.2794)
		(layer "F.Cu")
		(net "FAN_2_TACH_OL_D")
	)
	(segment
		(start 36.746942 -101.784912)
		(end 36.746942 -102.532688)
		(width 0.2794)
		(layer "F.Cu")
		(net "FAN_2_TACH_OL_D")
	)
	(segment
		(start 37.4142 -103.199946)
		(end 37.4142 -103.435912)
		(width 0.2794)
		(layer "F.Cu")
		(net "FAN_2_TACH_OL_D")
	)
	(segment
		(start 39.243 -104.14)
		(end 40.82034 -105.71734)
		(width 0.2794)
		(layer "F.Cu")
		(net "FAN_2_TACH_OL_D")
	)
	(segment
		(start 39.243 -104.14)
		(end 38.118288 -104.14)
		(width 0.2794)
		(layer "F.Cu")
		(net "FAN_2_TACH_OL_D")
	)
	(segment
		(start 38.118288 -104.14)
		(end 37.4142 -103.435912)
		(width 0.2794)
		(layer "F.Cu")
		(net "FAN_2_TACH_OL_D")
	)
	(segment
		(start 44.007278 -105.71734)
		(end 44.99991 -106.709972)
		(width 0.2794)
		(layer "F.Cu")
		(net "FAN_2_TACH_OL_D")
	)
	(via
		(at 39.243 -104.14)
		(size 0.762)
		(drill 0.381)
		(layers "F.Cu" "B.Cu")
		(net "FAN_2_TACH_OL_D")
	)
	(segment
		(start 44.04741 -117.757448)
		(end 38.7604 -117.757448)
		(width 0.2794)
		(layer "F.Cu")
		(net "FAN_2_TACH_IL_D")
	)
	(segment
		(start 38.242748 -117.757448)
		(end 38.0873 -117.602)
		(width 0.2794)
		(layer "F.Cu")
		(net "FAN_2_TACH_IL_D")
	)
	(segment
		(start 38.7604 -117.757448)
		(end 38.242748 -117.757448)
		(width 0.2794)
		(layer "F.Cu")
		(net "FAN_2_TACH_IL_D")
	)
	(segment
		(start 44.99991 -118.709948)
		(end 44.04741 -117.757448)
		(width 0.2794)
		(layer "F.Cu")
		(net "FAN_2_TACH_IL_D")
	)
	(segment
		(start 36.746942 -116.008912)
		(end 36.746942 -116.934742)
		(width 0.2794)
		(layer "F.Cu")
		(net "FAN_2_TACH_IL_D")
	)
	(segment
		(start 38.0873 -117.602)
		(end 37.4142 -117.602)
		(width 0.2794)
		(layer "F.Cu")
		(net "FAN_2_TACH_IL_D")
	)
	(segment
		(start 36.746942 -116.934742)
		(end 37.4142 -117.602)
		(width 0.2794)
		(layer "F.Cu")
		(net "FAN_2_TACH_IL_D")
	)
	(via
		(at 38.7604 -117.757448)
		(size 0.762)
		(drill 0.381)
		(layers "F.Cu" "B.Cu")
		(net "FAN_2_TACH_IL_D")
	)
	(segment
		(start 37.73805 -113.595912)
		(end 38.431216 -113.595912)
		(width 0.2794)
		(layer "F.Cu")
		(net "SMB_FAN2_SCL_R")
	)
	(segment
		(start 42.999914 -114.709956)
		(end 39.54526 -114.709956)
		(width 0.2794)
		(layer "F.Cu")
		(net "SMB_FAN2_SCL_R")
	)
	(segment
		(start 38.431216 -113.595912)
		(end 38.944296 -114.108992)
		(width 0.2794)
		(layer "F.Cu")
		(net "SMB_FAN2_SCL_R")
	)
	(segment
		(start 39.54526 -114.709956)
		(end 38.944296 -114.108992)
		(width 0.2794)
		(layer "F.Cu")
		(net "SMB_FAN2_SCL_R")
	)
	(via
		(at 38.944296 -114.108992)
		(size 0.762)
		(drill 0.381)
		(layers "F.Cu" "B.Cu")
		(net "SMB_FAN2_SCL_R")
	)
	(segment
		(start 20.4978 -166.37)
		(end 19.19605 -166.37)
		(width 0.2794)
		(layer "F.Cu")
		(net "FAN_2_PRESENT_R_N")
	)
	(segment
		(start 34.59734 -165.354)
		(end 21.5138 -165.354)
		(width 0.2794)
		(layer "F.Cu")
		(net "FAN_2_PRESENT_R_N")
	)
	(segment
		(start 47.625 -163.449)
		(end 47.5234 -163.5506)
		(width 0.2794)
		(layer "F.Cu")
		(net "FAN_2_PRESENT_R_N")
	)
	(segment
		(start 21.5138 -165.354)
		(end 20.4978 -166.37)
		(width 0.2794)
		(layer "F.Cu")
		(net "FAN_2_PRESENT_R_N")
	)
	(segment
		(start 43.091608 -163.5506)
		(end 38.477444 -165.461696)
		(width 0.2794)
		(layer "F.Cu")
		(net "FAN_2_PRESENT_R_N")
	)
	(segment
		(start 38.477444 -165.461696)
		(end 38.1635 -165.77564)
		(width 0.2794)
		(layer "F.Cu")
		(net "FAN_2_PRESENT_R_N")
	)
	(segment
		(start 19.19605 -166.37)
		(end 18.30705 -165.481)
		(width 0.2794)
		(layer "F.Cu")
		(net "FAN_2_PRESENT_R_N")
	)
	(segment
		(start 35.01898 -165.77564)
		(end 34.59734 -165.354)
		(width 0.2794)
		(layer "F.Cu")
		(net "FAN_2_PRESENT_R_N")
	)
	(segment
		(start 47.5234 -163.5506)
		(end 43.091608 -163.5506)
		(width 0.2794)
		(layer "F.Cu")
		(net "FAN_2_PRESENT_R_N")
	)
	(segment
		(start 38.1635 -165.77564)
		(end 35.01898 -165.77564)
		(width 0.2794)
		(layer "F.Cu")
		(net "FAN_2_PRESENT_R_N")
	)
	(via
		(at 47.625 -163.449)
		(size 0.762)
		(drill 0.254)
		(layers "F.Cu" "B.Cu")
		(net "FAN_2_PRESENT_R_N")
	)
	(segment
		(start 43.79214 -123.33986)
		(end 43.79214 -138.87831)
		(width 0.2286)
		(layer "In2.Cu")
		(net "FAN_2_PRESENT_R_N")
	)
	(segment
		(start 45.974 -116.205)
		(end 45.974 -121.158)
		(width 0.2286)
		(layer "In2.Cu")
		(net "FAN_2_PRESENT_R_N")
	)
	(segment
		(start 43.79214 -138.87831)
		(end 48.156876 -143.243046)
		(width 0.2286)
		(layer "In2.Cu")
		(net "FAN_2_PRESENT_R_N")
	)
	(segment
		(start 44.012866 -115.697)
		(end 45.466 -115.697)
		(width 0.2286)
		(layer "In2.Cu")
		(net "FAN_2_PRESENT_R_N")
	)
	(segment
		(start 48.156876 -143.243046)
		(end 48.156876 -161.647124)
		(width 0.2286)
		(layer "In2.Cu")
		(net "FAN_2_PRESENT_R_N")
	)
	(segment
		(start 47.625 -162.179)
		(end 47.625 -163.449)
		(width 0.2286)
		(layer "In2.Cu")
		(net "FAN_2_PRESENT_R_N")
	)
	(segment
		(start 45.466 -115.697)
		(end 45.974 -116.205)
		(width 0.2286)
		(layer "In2.Cu")
		(net "FAN_2_PRESENT_R_N")
	)
	(segment
		(start 48.156876 -161.647124)
		(end 47.625 -162.179)
		(width 0.2286)
		(layer "In2.Cu")
		(net "FAN_2_PRESENT_R_N")
	)
	(segment
		(start 45.974 -121.158)
		(end 43.79214 -123.33986)
		(width 0.2286)
		(layer "In2.Cu")
		(net "FAN_2_PRESENT_R_N")
	)
	(segment
		(start 42.999914 -116.709952)
		(end 44.012866 -115.697)
		(width 0.2286)
		(layer "In2.Cu")
		(net "FAN_2_PRESENT_R_N")
	)
	(segment
		(start 35.70605 -119.564912)
		(end 35.70605 -119.716804)
		(width 0.2794)
		(layer "F.Cu")
		(net "FAN_2_PWM_OL_R")
	)
	(segment
		(start 37.86505 -119.564912)
		(end 38.430962 -118.999)
		(width 0.2794)
		(layer "F.Cu")
		(net "FAN_2_PWM_OL_R")
	)
	(segment
		(start 42.188892 -118.999)
		(end 42.711116 -118.998746)
		(width 0.2794)
		(layer "F.Cu")
		(net "FAN_2_PWM_OL_R")
	)
	(segment
		(start 33.915096 -120.142)
		(end 33.6169 -119.843804)
		(width 0.2794)
		(layer "F.Cu")
		(net "FAN_2_PWM_OL_R")
	)
	(segment
		(start 35.70605 -119.4816)
		(end 36.206938 -118.980712)
		(width 0.2794)
		(layer "F.Cu")
		(net "FAN_2_PWM_OL_R")
	)
	(segment
		(start 35.280854 -120.142)
		(end 33.915096 -120.142)
		(width 0.2794)
		(layer "F.Cu")
		(net "FAN_2_PWM_OL_R")
	)
	(segment
		(start 35.70605 -119.564912)
		(end 35.70605 -119.4816)
		(width 0.2794)
		(layer "F.Cu")
		(net "FAN_2_PWM_OL_R")
	)
	(segment
		(start 37.34054 -118.980712)
		(end 37.86505 -119.505222)
		(width 0.2794)
		(layer "F.Cu")
		(net "FAN_2_PWM_OL_R")
	)
	(segment
		(start 38.430962 -118.999)
		(end 39.878 -118.999)
		(width 0.2794)
		(layer "F.Cu")
		(net "FAN_2_PWM_OL_R")
	)
	(segment
		(start 33.6169 -119.843804)
		(end 33.6169 -119.73687)
		(width 0.2794)
		(layer "F.Cu")
		(net "FAN_2_PWM_OL_R")
	)
	(segment
		(start 36.206938 -118.980712)
		(end 37.34054 -118.980712)
		(width 0.2794)
		(layer "F.Cu")
		(net "FAN_2_PWM_OL_R")
	)
	(segment
		(start 42.711116 -118.998746)
		(end 42.999914 -118.709948)
		(width 0.2794)
		(layer "F.Cu")
		(net "FAN_2_PWM_OL_R")
	)
	(segment
		(start 37.86505 -119.505222)
		(end 37.86505 -119.564912)
		(width 0.2794)
		(layer "F.Cu")
		(net "FAN_2_PWM_OL_R")
	)
	(segment
		(start 35.70605 -119.716804)
		(end 35.280854 -120.142)
		(width 0.2794)
		(layer "F.Cu")
		(net "FAN_2_PWM_OL_R")
	)
	(segment
		(start 33.6169 -119.73687)
		(end 33.444942 -119.564912)
		(width 0.2794)
		(layer "F.Cu")
		(net "FAN_2_PWM_OL_R")
	)
	(segment
		(start 39.878 -118.999)
		(end 42.188892 -118.999)
		(width 0.2794)
		(layer "F.Cu")
		(net "FAN_2_PWM_OL_R")
	)
	(via
		(at 39.878 -118.999)
		(size 0.762)
		(drill 0.381)
		(layers "F.Cu" "B.Cu")
		(net "FAN_2_PWM_OL_R")
	)
	(segment
		(start 35.0266 -195.707)
		(end 35.1028 -195.7832)
		(width 0.2794)
		(layer "F.Cu")
		(net "FAN_1_TACH_OL_R")
	)
	(segment
		(start 34.39795 -193.65595)
		(end 35.0266 -194.2846)
		(width 0.2794)
		(layer "F.Cu")
		(net "FAN_1_TACH_OL_R")
	)
	(segment
		(start 34.39795 -193.548)
		(end 34.39795 -193.65595)
		(width 0.2794)
		(layer "F.Cu")
		(net "FAN_1_TACH_OL_R")
	)
	(segment
		(start 35.0266 -194.691)
		(end 35.0266 -195.707)
		(width 0.2794)
		(layer "F.Cu")
		(net "FAN_1_TACH_OL_R")
	)
	(segment
		(start 35.0266 -194.2846)
		(end 35.0266 -194.691)
		(width 0.2794)
		(layer "F.Cu")
		(net "FAN_1_TACH_OL_R")
	)
	(segment
		(start 35.1028 -195.7832)
		(end 35.1028 -196.370956)
		(width 0.2794)
		(layer "F.Cu")
		(net "FAN_1_TACH_OL_R")
	)
	(segment
		(start 33.42005 -193.548)
		(end 34.39795 -193.548)
		(width 0.2794)
		(layer "F.Cu")
		(net "FAN_1_TACH_OL_R")
	)
	(segment
		(start 40.199818 -206.014574)
		(end 43.99534 -206.014574)
		(width 0.2794)
		(layer "F.Cu")
		(net "SMB_FAN1_SDA_R")
	)
	(segment
		(start 38.9382 -204.752956)
		(end 40.199818 -206.014574)
		(width 0.2794)
		(layer "F.Cu")
		(net "SMB_FAN1_SDA_R")
	)
	(segment
		(start 37.73805 -204.752956)
		(end 38.9382 -204.752956)
		(width 0.2794)
		(layer "F.Cu")
		(net "SMB_FAN1_SDA_R")
	)
	(segment
		(start 43.99534 -206.014574)
		(end 44.99991 -205.010004)
		(width 0.2794)
		(layer "F.Cu")
		(net "SMB_FAN1_SDA_R")
	)
	(via
		(at 38.9382 -204.752956)
		(size 0.762)
		(drill 0.381)
		(layers "F.Cu" "B.Cu")
		(net "SMB_FAN1_SDA_R")
	)
	(segment
		(start 37.73805 -207.038956)
		(end 37.73805 -207.098646)
		(width 0.2794)
		(layer "F.Cu")
		(net "FAN_1_PWM_IL_R")
	)
	(segment
		(start 34.925 -207.772)
		(end 35.57905 -207.11795)
		(width 0.2794)
		(layer "F.Cu")
		(net "FAN_1_PWM_IL_R")
	)
	(segment
		(start 35.889946 -207.623156)
		(end 35.57905 -207.31226)
		(width 0.2794)
		(layer "F.Cu")
		(net "FAN_1_PWM_IL_R")
	)
	(segment
		(start 38.75405 -208.054956)
		(end 37.73805 -207.038956)
		(width 0.2794)
		(layer "F.Cu")
		(net "FAN_1_PWM_IL_R")
	)
	(segment
		(start 37.73805 -207.098646)
		(end 37.27704 -207.559656)
		(width 0.2794)
		(layer "F.Cu")
		(net "FAN_1_PWM_IL_R")
	)
	(segment
		(start 34.079942 -207.772)
		(end 34.925 -207.772)
		(width 0.2794)
		(layer "F.Cu")
		(net "FAN_1_PWM_IL_R")
	)
	(segment
		(start 37.243512 -207.559656)
		(end 37.180012 -207.623156)
		(width 0.2794)
		(layer "F.Cu")
		(net "FAN_1_PWM_IL_R")
	)
	(segment
		(start 35.57905 -207.038956)
		(end 35.57905 -207.11795)
		(width 0.2794)
		(layer "F.Cu")
		(net "FAN_1_PWM_IL_R")
	)
	(segment
		(start 37.180012 -207.623156)
		(end 35.889946 -207.623156)
		(width 0.2794)
		(layer "F.Cu")
		(net "FAN_1_PWM_IL_R")
	)
	(segment
		(start 44.99991 -209.009996)
		(end 44.04487 -208.054956)
		(width 0.2794)
		(layer "F.Cu")
		(net "FAN_1_PWM_IL_R")
	)
	(segment
		(start 39.878 -208.054956)
		(end 38.75405 -208.054956)
		(width 0.2794)
		(layer "F.Cu")
		(net "FAN_1_PWM_IL_R")
	)
	(segment
		(start 35.57905 -207.31226)
		(end 35.57905 -207.11795)
		(width 0.2794)
		(layer "F.Cu")
		(net "FAN_1_PWM_IL_R")
	)
	(segment
		(start 33.317942 -207.01)
		(end 34.079942 -207.772)
		(width 0.2794)
		(layer "F.Cu")
		(net "FAN_1_PWM_IL_R")
	)
	(segment
		(start 37.27704 -207.559656)
		(end 37.243512 -207.559656)
		(width 0.2794)
		(layer "F.Cu")
		(net "FAN_1_PWM_IL_R")
	)
	(segment
		(start 44.04487 -208.054956)
		(end 39.878 -208.054956)
		(width 0.2794)
		(layer "F.Cu")
		(net "FAN_1_PWM_IL_R")
	)
	(via
		(at 39.878 -208.054956)
		(size 0.762)
		(drill 0.381)
		(layers "F.Cu" "B.Cu")
		(net "FAN_1_PWM_IL_R")
	)
	(segment
		(start 33.42005 -210.512406)
		(end 33.5026 -210.594956)
		(width 0.2794)
		(layer "F.Cu")
		(net "FAN_1_TACH_IL_R")
	)
	(segment
		(start 33.42005 -208.308956)
		(end 33.42005 -209.451956)
		(width 0.2794)
		(layer "F.Cu")
		(net "FAN_1_TACH_IL_R")
	)
	(segment
		(start 33.6042 -210.594956)
		(end 34.2392 -209.959956)
		(width 0.2794)
		(layer "F.Cu")
		(net "FAN_1_TACH_IL_R")
	)
	(segment
		(start 33.42005 -209.451956)
		(end 33.42005 -210.512406)
		(width 0.2794)
		(layer "F.Cu")
		(net "FAN_1_TACH_IL_R")
	)
	(segment
		(start 35.2298 -209.959956)
		(end 34.2392 -209.959956)
		(width 0.2794)
		(layer "F.Cu")
		(net "FAN_1_TACH_IL_R")
	)
	(segment
		(start 33.5026 -210.594956)
		(end 33.6042 -210.594956)
		(width 0.2794)
		(layer "F.Cu")
		(net "FAN_1_TACH_IL_R")
	)
	(via
		(at 34.2392 -209.959956)
		(size 0.508)
		(drill 0.254)
		(layers "F.Cu" "B.Cu")
		(net "FAN_1_TACH_IL_R")
	)
	(segment
		(start 44.99991 -199.010016)
		(end 46.228 -197.781926)
		(width 0.2794)
		(layer "F.Cu")
		(net "FAN_1_TACH_OL_D")
	)
	(segment
		(start 37.635942 -195.2625)
		(end 37.2872 -195.611242)
		(width 0.2794)
		(layer "F.Cu")
		(net "FAN_1_TACH_OL_D")
	)
	(segment
		(start 37.367464 -196.45122)
		(end 37.2872 -196.370956)
		(width 0.2794)
		(layer "F.Cu")
		(net "FAN_1_TACH_OL_D")
	)
	(segment
		(start 40.054784 -195.072)
		(end 38.675564 -196.45122)
		(width 0.2794)
		(layer "F.Cu")
		(net "FAN_1_TACH_OL_D")
	)
	(segment
		(start 38.675564 -196.45122)
		(end 37.367464 -196.45122)
		(width 0.2794)
		(layer "F.Cu")
		(net "FAN_1_TACH_OL_D")
	)
	(segment
		(start 46.228 -196.469)
		(end 44.831 -195.072)
		(width 0.2794)
		(layer "F.Cu")
		(net "FAN_1_TACH_OL_D")
	)
	(segment
		(start 37.2872 -195.611242)
		(end 37.2872 -196.370956)
		(width 0.2794)
		(layer "F.Cu")
		(net "FAN_1_TACH_OL_D")
	)
	(segment
		(start 44.831 -195.072)
		(end 40.054784 -195.072)
		(width 0.2794)
		(layer "F.Cu")
		(net "FAN_1_TACH_OL_D")
	)
	(segment
		(start 37.635942 -194.691)
		(end 37.635942 -195.2625)
		(width 0.2794)
		(layer "F.Cu")
		(net "FAN_1_TACH_OL_D")
	)
	(segment
		(start 46.228 -197.781926)
		(end 46.228 -196.469)
		(width 0.2794)
		(layer "F.Cu")
		(net "FAN_1_TACH_OL_D")
	)
	(via
		(at 38.675564 -196.45122)
		(size 0.762)
		(drill 0.381)
		(layers "F.Cu" "B.Cu")
		(net "FAN_1_TACH_OL_D")
	)
	(segment
		(start 37.4142 -209.959956)
		(end 37.511736 -210.057492)
		(width 0.2794)
		(layer "F.Cu")
		(net "FAN_1_TACH_IL_D")
	)
	(segment
		(start 36.746942 -209.292698)
		(end 37.4142 -209.959956)
		(width 0.2794)
		(layer "F.Cu")
		(net "FAN_1_TACH_IL_D")
	)
	(segment
		(start 39.5732 -210.057492)
		(end 44.04741 -210.057492)
		(width 0.2794)
		(layer "F.Cu")
		(net "FAN_1_TACH_IL_D")
	)
	(segment
		(start 44.04741 -210.057492)
		(end 44.99991 -211.009992)
		(width 0.2794)
		(layer "F.Cu")
		(net "FAN_1_TACH_IL_D")
	)
	(segment
		(start 36.746942 -208.308956)
		(end 36.746942 -209.292698)
		(width 0.2794)
		(layer "F.Cu")
		(net "FAN_1_TACH_IL_D")
	)
	(segment
		(start 37.511736 -210.057492)
		(end 39.5732 -210.057492)
		(width 0.2794)
		(layer "F.Cu")
		(net "FAN_1_TACH_IL_D")
	)
	(via
		(at 39.5732 -210.057492)
		(size 0.762)
		(drill 0.381)
		(layers "F.Cu" "B.Cu")
		(net "FAN_1_TACH_IL_D")
	)
	(segment
		(start 18.01495 -189.611)
		(end 18.01495 -188.595)
		(width 0.2794)
		(layer "F.Cu")
		(net "FRU_WP_N")
	)
	(segment
		(start 17.697704 -188.595)
		(end 16.532098 -189.760606)
		(width 0.2794)
		(layer "F.Cu")
		(net "FRU_WP_N")
	)
	(segment
		(start 14.518894 -189.760606)
		(end 16.532098 -189.760606)
		(width 0.2794)
		(layer "F.Cu")
		(net "FRU_WP_N")
	)
	(segment
		(start 18.01495 -188.595)
		(end 17.697704 -188.595)
		(width 0.2794)
		(layer "F.Cu")
		(net "FRU_WP_N")
	)
	(segment
		(start 12.9286 -189.357)
		(end 14.115288 -189.357)
		(width 0.2794)
		(layer "F.Cu")
		(net "FRU_WP_N")
	)
	(segment
		(start 14.115288 -189.357)
		(end 14.518894 -189.760606)
		(width 0.2794)
		(layer "F.Cu")
		(net "FRU_WP_N")
	)
	(via
		(at 16.532098 -189.760606)
		(size 0.762)
		(drill 0.381)
		(layers "F.Cu" "B.Cu")
		(net "FRU_WP_N")
	)
	(segment
		(start 16.65478 -186.563)
		(end 15.621254 -186.563)
		(width 0.2794)
		(layer "F.Cu")
		(net "SMB_FRU_DAT")
	)
	(segment
		(start 15.621254 -186.563)
		(end 15.367254 -186.817)
		(width 0.2794)
		(layer "F.Cu")
		(net "SMB_FRU_DAT")
	)
	(segment
		(start 18.01495 -186.563)
		(end 16.65478 -186.563)
		(width 0.2794)
		(layer "F.Cu")
		(net "SMB_FRU_DAT")
	)
	(segment
		(start 15.367254 -186.817)
		(end 12.9286 -186.817)
		(width 0.2794)
		(layer "F.Cu")
		(net "SMB_FRU_DAT")
	)
	(via
		(at 16.65478 -186.563)
		(size 0.508)
		(drill 0.254)
		(layers "F.Cu" "B.Cu")
		(net "SMB_FRU_DAT")
	)
	(segment
		(start 39.158672 -206.417926)
		(end 38.636702 -205.895956)
		(width 0.2794)
		(layer "F.Cu")
		(net "SMB_FAN1_SCL_R")
	)
	(segment
		(start 39.750746 -207.01)
		(end 39.158672 -206.417926)
		(width 0.2794)
		(layer "F.Cu")
		(net "SMB_FAN1_SCL_R")
	)
	(segment
		(start 38.636702 -205.895956)
		(end 37.73805 -205.895956)
		(width 0.2794)
		(layer "F.Cu")
		(net "SMB_FAN1_SCL_R")
	)
	(segment
		(start 42.999914 -207.01)
		(end 39.750746 -207.01)
		(width 0.2794)
		(layer "F.Cu")
		(net "SMB_FAN1_SCL_R")
	)
	(via
		(at 39.158672 -206.417926)
		(size 0.762)
		(drill 0.381)
		(layers "F.Cu" "B.Cu")
		(net "SMB_FAN1_SCL_R")
	)
	(segment
		(start 5.86105 -188.214)
		(end 7.00405 -189.357)
		(width 0.2794)
		(layer "F.Cu")
		(net "FRU_ADDR1")
	)
	(segment
		(start 3.19405 -188.214)
		(end 4.163314 -187.244736)
		(width 0.2794)
		(layer "F.Cu")
		(net "FRU_ADDR1")
	)
	(segment
		(start 4.163314 -187.244736)
		(end 4.434332 -187.244736)
		(width 0.2794)
		(layer "F.Cu")
		(net "FRU_ADDR1")
	)
	(segment
		(start 4.434332 -187.244736)
		(end 5.043678 -187.244736)
		(width 0.2794)
		(layer "F.Cu")
		(net "FRU_ADDR1")
	)
	(segment
		(start 7.00405 -189.357)
		(end 7.6454 -189.357)
		(width 0.2794)
		(layer "F.Cu")
		(net "FRU_ADDR1")
	)
	(segment
		(start 5.86105 -188.062108)
		(end 5.86105 -188.214)
		(width 0.2794)
		(layer "F.Cu")
		(net "FRU_ADDR1")
	)
	(segment
		(start 5.043678 -187.244736)
		(end 5.86105 -188.062108)
		(width 0.2794)
		(layer "F.Cu")
		(net "FRU_ADDR1")
	)
	(via
		(at 4.434332 -187.244736)
		(size 0.508)
		(drill 0.254)
		(layers "F.Cu" "B.Cu")
		(net "FRU_ADDR1")
	)
	(segment
		(start 19.451574 -165.482524)
		(end 20.547076 -165.482524)
		(width 0.2794)
		(layer "F.Cu")
		(net "FAN_1_PRESENT_R_N")
	)
	(segment
		(start 20.547076 -165.482524)
		(end 21.340064 -164.689536)
		(width 0.2794)
		(layer "F.Cu")
		(net "FAN_1_PRESENT_R_N")
	)
	(segment
		(start 34.781236 -164.689536)
		(end 35.22726 -165.13556)
		(width 0.2794)
		(layer "F.Cu")
		(net "FAN_1_PRESENT_R_N")
	)
	(segment
		(start 21.340064 -164.689536)
		(end 34.781236 -164.689536)
		(width 0.2794)
		(layer "F.Cu")
		(net "FAN_1_PRESENT_R_N")
	)
	(segment
		(start 37.84092 -165.13556)
		(end 38.09873 -164.87775)
		(width 0.2794)
		(layer "F.Cu")
		(net "FAN_1_PRESENT_R_N")
	)
	(segment
		(start 35.22726 -165.13556)
		(end 37.84092 -165.13556)
		(width 0.2794)
		(layer "F.Cu")
		(net "FAN_1_PRESENT_R_N")
	)
	(segment
		(start 38.09873 -164.87775)
		(end 42.714418 -162.9664)
		(width 0.2794)
		(layer "F.Cu")
		(net "FAN_1_PRESENT_R_N")
	)
	(segment
		(start 18.30705 -164.338)
		(end 19.451574 -165.482524)
		(width 0.2794)
		(layer "F.Cu")
		(net "FAN_1_PRESENT_R_N")
	)
	(segment
		(start 42.714418 -162.9664)
		(end 46.355 -162.9664)
		(width 0.2794)
		(layer "F.Cu")
		(net "FAN_1_PRESENT_R_N")
	)
	(via
		(at 46.355 -162.9664)
		(size 0.508)
		(drill 0.254)
		(layers "F.Cu" "B.Cu")
		(net "FAN_1_PRESENT_R_N")
	)
	(segment
		(start 46.99 -165.354)
		(end 46.355 -164.719)
		(width 0.2286)
		(layer "In2.Cu")
		(net "FAN_1_PRESENT_R_N")
	)
	(segment
		(start 45.85462 -173.228)
		(end 46.99 -172.09262)
		(width 0.2286)
		(layer "In2.Cu")
		(net "FAN_1_PRESENT_R_N")
	)
	(segment
		(start 49.53 -189.865)
		(end 49.53 -182.626)
		(width 0.2286)
		(layer "In2.Cu")
		(net "FAN_1_PRESENT_R_N")
	)
	(segment
		(start 46.99 -172.09262)
		(end 46.99 -165.354)
		(width 0.2286)
		(layer "In2.Cu")
		(net "FAN_1_PRESENT_R_N")
	)
	(segment
		(start 44.577 -177.673)
		(end 44.577 -173.99)
		(width 0.2286)
		(layer "In2.Cu")
		(net "FAN_1_PRESENT_R_N")
	)
	(segment
		(start 45.8216 -193.5734)
		(end 49.53 -189.865)
		(width 0.2286)
		(layer "In2.Cu")
		(net "FAN_1_PRESENT_R_N")
	)
	(segment
		(start 45.8216 -195.095622)
		(end 45.8216 -193.5734)
		(width 0.2286)
		(layer "In2.Cu")
		(net "FAN_1_PRESENT_R_N")
	)
	(segment
		(start 46.355 -164.719)
		(end 46.355 -162.9664)
		(width 0.2286)
		(layer "In2.Cu")
		(net "FAN_1_PRESENT_R_N")
	)
	(segment
		(start 44.577 -173.99)
		(end 45.339 -173.228)
		(width 0.2286)
		(layer "In2.Cu")
		(net "FAN_1_PRESENT_R_N")
	)
	(segment
		(start 47.2186 -196.492622)
		(end 45.8216 -195.095622)
		(width 0.2286)
		(layer "In2.Cu")
		(net "FAN_1_PRESENT_R_N")
	)
	(segment
		(start 47.2186 -206.2988)
		(end 47.2186 -196.492622)
		(width 0.2286)
		(layer "In2.Cu")
		(net "FAN_1_PRESENT_R_N")
	)
	(segment
		(start 45.339 -173.228)
		(end 45.85462 -173.228)
		(width 0.2286)
		(layer "In2.Cu")
		(net "FAN_1_PRESENT_R_N")
	)
	(segment
		(start 44.00931 -208.0006)
		(end 45.5168 -208.0006)
		(width 0.2286)
		(layer "In2.Cu")
		(net "FAN_1_PRESENT_R_N")
	)
	(segment
		(start 42.999914 -209.009996)
		(end 44.00931 -208.0006)
		(width 0.2286)
		(layer "In2.Cu")
		(net "FAN_1_PRESENT_R_N")
	)
	(segment
		(start 49.53 -182.626)
		(end 44.577 -177.673)
		(width 0.2286)
		(layer "In2.Cu")
		(net "FAN_1_PRESENT_R_N")
	)
	(segment
		(start 45.5168 -208.0006)
		(end 47.2186 -206.2988)
		(width 0.2286)
		(layer "In2.Cu")
		(net "FAN_1_PRESENT_R_N")
	)
	(segment
		(start 3.19405 -189.992)
		(end 3.813048 -189.373002)
		(width 0.2794)
		(layer "F.Cu")
		(net "FRU_ADDR0")
	)
	(segment
		(start 5.303266 -189.282324)
		(end 5.86105 -189.840108)
		(width 0.2794)
		(layer "F.Cu")
		(net "FRU_ADDR0")
	)
	(segment
		(start 6.49605 -190.627)
		(end 7.6454 -190.627)
		(width 0.2794)
		(layer "F.Cu")
		(net "FRU_ADDR0")
	)
	(segment
		(start 5.86105 -189.992)
		(end 6.49605 -190.627)
		(width 0.2794)
		(layer "F.Cu")
		(net "FRU_ADDR0")
	)
	(segment
		(start 3.903726 -189.282324)
		(end 5.303266 -189.282324)
		(width 0.2794)
		(layer "F.Cu")
		(net "FRU_ADDR0")
	)
	(segment
		(start 5.86105 -189.840108)
		(end 5.86105 -189.992)
		(width 0.2794)
		(layer "F.Cu")
		(net "FRU_ADDR0")
	)
	(segment
		(start 3.813048 -189.373002)
		(end 3.903726 -189.282324)
		(width 0.2794)
		(layer "F.Cu")
		(net "FRU_ADDR0")
	)
	(via
		(at 3.813048 -189.373002)
		(size 0.508)
		(drill 0.254)
		(layers "F.Cu" "B.Cu")
		(net "FRU_ADDR0")
	)
	(segment
		(start 35.70605 -211.972906)
		(end 35.70605 -211.864956)
		(width 0.2794)
		(layer "F.Cu")
		(net "FAN_1_PWM_OL_R")
	)
	(segment
		(start 37.86505 -211.864956)
		(end 39.8526 -211.864956)
		(width 0.2794)
		(layer "F.Cu")
		(net "FAN_1_PWM_OL_R")
	)
	(segment
		(start 35.1409 -212.538056)
		(end 35.70605 -211.972906)
		(width 0.2794)
		(layer "F.Cu")
		(net "FAN_1_PWM_OL_R")
	)
	(segment
		(start 37.387784 -211.328)
		(end 37.86505 -211.805266)
		(width 0.2794)
		(layer "F.Cu")
		(net "FAN_1_PWM_OL_R")
	)
	(segment
		(start 36.119816 -211.864956)
		(end 36.656772 -211.328)
		(width 0.2794)
		(layer "F.Cu")
		(net "FAN_1_PWM_OL_R")
	)
	(segment
		(start 35.70605 -211.864956)
		(end 36.119816 -211.864956)
		(width 0.2794)
		(layer "F.Cu")
		(net "FAN_1_PWM_OL_R")
	)
	(segment
		(start 39.8526 -211.864956)
		(end 42.14495 -211.864956)
		(width 0.2794)
		(layer "F.Cu")
		(net "FAN_1_PWM_OL_R")
	)
	(segment
		(start 34.121598 -212.538056)
		(end 35.1409 -212.538056)
		(width 0.2794)
		(layer "F.Cu")
		(net "FAN_1_PWM_OL_R")
	)
	(segment
		(start 42.14495 -211.864956)
		(end 42.999914 -211.009992)
		(width 0.2794)
		(layer "F.Cu")
		(net "FAN_1_PWM_OL_R")
	)
	(segment
		(start 33.571942 -211.963)
		(end 33.571942 -211.9884)
		(width 0.2794)
		(layer "F.Cu")
		(net "FAN_1_PWM_OL_R")
	)
	(segment
		(start 36.656772 -211.328)
		(end 37.387784 -211.328)
		(width 0.2794)
		(layer "F.Cu")
		(net "FAN_1_PWM_OL_R")
	)
	(segment
		(start 37.86505 -211.805266)
		(end 37.86505 -211.864956)
		(width 0.2794)
		(layer "F.Cu")
		(net "FAN_1_PWM_OL_R")
	)
	(segment
		(start 33.571942 -211.9884)
		(end 34.121598 -212.538056)
		(width 0.2794)
		(layer "F.Cu")
		(net "FAN_1_PWM_OL_R")
	)
	(via
		(at 39.8526 -211.864956)
		(size 0.762)
		(drill 0.381)
		(layers "F.Cu" "B.Cu")
		(net "FAN_1_PWM_OL_R")
	)
	(segment
		(start 5.86105 -186.436)
		(end 5.86105 -186.55284)
		(width 0.2794)
		(layer "F.Cu")
		(net "FRU_ADDR2")
	)
	(segment
		(start 3.39725 -185.489596)
		(end 5.066538 -185.489596)
		(width 0.2794)
		(layer "F.Cu")
		(net "FRU_ADDR2")
	)
	(segment
		(start 3.19405 -186.436)
		(end 3.19405 -185.692796)
		(width 0.2794)
		(layer "F.Cu")
		(net "FRU_ADDR2")
	)
	(segment
		(start 5.86105 -186.284108)
		(end 5.86105 -186.436)
		(width 0.2794)
		(layer "F.Cu")
		(net "FRU_ADDR2")
	)
	(segment
		(start 7.39521 -188.087)
		(end 7.6454 -188.087)
		(width 0.2794)
		(layer "F.Cu")
		(net "FRU_ADDR2")
	)
	(segment
		(start 5.86105 -186.55284)
		(end 7.39521 -188.087)
		(width 0.2794)
		(layer "F.Cu")
		(net "FRU_ADDR2")
	)
	(segment
		(start 3.19405 -185.692796)
		(end 3.39725 -185.489596)
		(width 0.2794)
		(layer "F.Cu")
		(net "FRU_ADDR2")
	)
	(segment
		(start 5.066538 -185.489596)
		(end 5.86105 -186.284108)
		(width 0.2794)
		(layer "F.Cu")
		(net "FRU_ADDR2")
	)
	(via
		(at 3.39725 -185.489596)
		(size 0.508)
		(drill 0.254)
		(layers "F.Cu" "B.Cu")
		(net "FRU_ADDR2")
	)
	(segment
		(start 18.01495 -187.579)
		(end 16.256254 -187.579)
		(width 0.2794)
		(layer "F.Cu")
		(net "SMB_FRU_CLK")
	)
	(segment
		(start 16.256254 -187.579)
		(end 15.748254 -188.087)
		(width 0.2794)
		(layer "F.Cu")
		(net "SMB_FRU_CLK")
	)
	(segment
		(start 15.748254 -188.087)
		(end 14.887448 -188.087)
		(width 0.2794)
		(layer "F.Cu")
		(net "SMB_FRU_CLK")
	)
	(segment
		(start 14.887448 -188.087)
		(end 12.9286 -188.087)
		(width 0.2794)
		(layer "F.Cu")
		(net "SMB_FRU_CLK")
	)
	(via
		(at 14.887448 -188.087)
		(size 0.508)
		(drill 0.254)
		(layers "F.Cu" "B.Cu")
		(net "SMB_FRU_CLK")
	)
	(segment
		(start 45.48505 -181.102)
		(end 46.09465 -181.102)
		(width 0.4572)
		(layer "F.Cu")
		(net "GND")
	)
	(segment
		(start 21.717 -211.72805)
		(end 20.828 -211.72805)
		(width 0.4572)
		(layer "F.Cu")
		(net "GND")
	)
	(segment
		(start 28.575 -19.304)
		(end 28.814014 -19.543014)
		(width 0.4572)
		(layer "F.Cu")
		(net "GND")
	)
	(segment
		(start 10.85596 -173.228)
		(end 11.49096 -173.228)
		(width 0.4572)
		(layer "F.Cu")
		(net "GND")
	)
	(segment
		(start 16.920972 -106.776012)
		(end 17.530572 -106.776012)
		(width 0.4572)
		(layer "F.Cu")
		(net "GND")
	)
	(segment
		(start 15.802864 -211.776056)
		(end 15.802864 -211.04225)
		(width 0.4572)
		(layer "F.Cu")
		(net "GND")
	)
	(segment
		(start 3.287014 -313.4741)
		(end 2.601214 -313.4741)
		(width 0.4572)
		(layer "F.Cu")
		(net "GND")
	)
	(segment
		(start 19.529044 -199.037956)
		(end 19.812 -198.755)
		(width 0.4572)
		(layer "F.Cu")
		(net "GND")
	)
	(segment
		(start 46.75505 -167.513)
		(end 47.5107 -167.513)
		(width 0.4572)
		(layer "F.Cu")
		(net "GND")
	)
	(segment
		(start 33.71215 -26.67)
		(end 34.16935 -27.1272)
		(width 0.4572)
		(layer "F.Cu")
		(net "GND")
	)
	(segment
		(start 38.4302 -192.1256)
		(end 36.220146 -192.1256)
		(width 0.4572)
		(layer "F.Cu")
		(net "GND")
	)
	(segment
		(start 14.775942 -300.736)
		(end 14.775942 -300.144942)
		(width 0.4572)
		(layer "F.Cu")
		(net "GND")
	)
	(segment
		(start 23.128986 -208.256378)
		(end 23.128986 -207.83804)
		(width 0.4572)
		(layer "F.Cu")
		(net "GND")
	)
	(segment
		(start 18.034 -136.41705)
		(end 19.431 -136.41705)
		(width 0.4572)
		(layer "F.Cu")
		(net "GND")
	)
	(segment
		(start 45.48505 -189.738)
		(end 46.09465 -189.738)
		(width 0.4572)
		(layer "F.Cu")
		(net "GND")
	)
	(segment
		(start 10.85596 -170.053)
		(end 11.49096 -170.053)
		(width 0.4572)
		(layer "F.Cu")
		(net "GND")
	)
	(segment
		(start 33.838896 -127.959104)
		(end 33.495996 -127.959104)
		(width 0.1778)
		(layer "F.Cu")
		(net "GND")
	)
	(segment
		(start 18.1991 -23.255986)
		(end 18.1991 -23.941786)
		(width 0.4572)
		(layer "F.Cu")
		(net "GND")
	)
	(segment
		(start 20.828 -304.81905)
		(end 21.717 -303.93005)
		(width 0.4572)
		(layer "F.Cu")
		(net "GND")
	)
	(segment
		(start 16.02105 -166.4716)
		(end 16.8656 -166.4716)
		(width 0.4572)
		(layer "F.Cu")
		(net "GND")
	)
	(segment
		(start 42.926 -137.68705)
		(end 43.561 -137.68705)
		(width 0.4572)
		(layer "F.Cu")
		(net "GND")
	)
	(segment
		(start 25.180036 -32.018986)
		(end 26.162 -33.00095)
		(width 0.4572)
		(layer "F.Cu")
		(net "GND")
	)
	(segment
		(start 33.6169 -21.956014)
		(end 33.6169 -20.373086)
		(width 0.4572)
		(layer "F.Cu")
		(net "GND")
	)
	(segment
		(start 18.81505 -189.611)
		(end 18.81505 -190.881)
		(width 0.4572)
		(layer "F.Cu")
		(net "GND")
	)
	(segment
		(start 8.309864 -251.98705)
		(end 8.074914 -252.222)
		(width 0.4572)
		(layer "F.Cu")
		(net "GND")
	)
	(segment
		(start 32.595058 -119.564912)
		(end 32.163512 -119.564912)
		(width 0.4572)
		(layer "F.Cu")
		(net "GND")
	)
	(segment
		(start 23.128986 -300.04004)
		(end 23.128986 -299.105574)
		(width 0.4572)
		(layer "F.Cu")
		(net "GND")
	)
	(segment
		(start 34.77895 -114.15395)
		(end 34.77895 -114.738912)
		(width 0.4572)
		(layer "F.Cu")
		(net "GND")
	)
	(segment
		(start 8.309864 -251.587)
		(end 8.309864 -251.98705)
		(width 0.4572)
		(layer "F.Cu")
		(net "GND")
	)
	(segment
		(start 35.27044 -253.294896)
		(end 35.41649 -253.148846)
		(width 0.4572)
		(layer "F.Cu")
		(net "GND")
	)
	(segment
		(start 23.128986 -115.63604)
		(end 23.128986 -115.00104)
		(width 0.381)
		(layer "F.Cu")
		(net "GND")
	)
	(segment
		(start 39.606982 -71.812912)
		(end 39.606982 -71.412862)
		(width 0.4572)
		(layer "F.Cu")
		(net "GND")
	)
	(segment
		(start 32.61995 -300.609)
		(end 32.61995 -299.363892)
		(width 0.4572)
		(layer "F.Cu")
		(net "GND")
	)
	(segment
		(start 41.731184 -75.621642)
		(end 41.16705 -75.057508)
		(width 0.4572)
		(layer "F.Cu")
		(net "GND")
	)
	(segment
		(start 22.606 -172.2628)
		(end 22.606 -171.1452)
		(width 0.4572)
		(layer "F.Cu")
		(net "GND")
	)
	(segment
		(start 32.356044 -114.709956)
		(end 31.8008 -115.2652)
		(width 0.4572)
		(layer "F.Cu")
		(net "GND")
	)
	(segment
		(start 18.67027 -304.81905)
		(end 20.828 -304.81905)
		(width 0.4572)
		(layer "F.Cu")
		(net "GND")
	)
	(segment
		(start 16.793972 -286.6771)
		(end 17.409922 -286.6771)
		(width 0.4572)
		(layer "F.Cu")
		(net "GND")
	)
	(segment
		(start 30.099 -286.61995)
		(end 30.734 -286.61995)
		(width 0.4572)
		(layer "F.Cu")
		(net "GND")
	)
	(segment
		(start 33.103058 -31.860236)
		(end 33.6296 -32.386778)
		(width 0.4572)
		(layer "F.Cu")
		(net "GND")
	)
	(segment
		(start 14.097 -260.096)
		(end 13.462 -259.461)
		(width 0.4572)
		(layer "F.Cu")
		(net "GND")
	)
	(segment
		(start 33.6296 -32.386778)
		(end 34.99104 -32.386778)
		(width 0.4572)
		(layer "F.Cu")
		(net "GND")
	)
	(segment
		(start 24.23795 -185.674)
		(end 23.622 -185.674)
		(width 0.4572)
		(layer "F.Cu")
		(net "GND")
	)
	(segment
		(start 32.61995 -116.008912)
		(end 32.544512 -116.008912)
		(width 0.4572)
		(layer "F.Cu")
		(net "GND")
	)
	(segment
		(start 25.92705 -124.079)
		(end 26.87701 -124.079)
		(width 0.4572)
		(layer "F.Cu")
		(net "GND")
	)
	(segment
		(start 7.6454 -186.817)
		(end 7.493 -186.817)
		(width 0.4572)
		(layer "F.Cu")
		(net "GND")
	)
	(segment
		(start 34.293556 -13.0556)
		(end 34.750756 -13.5128)
		(width 0.4572)
		(layer "F.Cu")
		(net "GND")
	)
	(segment
		(start 24.765 -184.918858)
		(end 24.23795 -185.445908)
		(width 0.4572)
		(layer "F.Cu")
		(net "GND")
	)
	(segment
		(start 33.02 -121.51995)
		(end 34.417 -121.51995)
		(width 0.4572)
		(layer "F.Cu")
		(net "GND")
	)
	(segment
		(start 8.309864 -66.986912)
		(end 8.309864 -66.475864)
		(width 0.4572)
		(layer "F.Cu")
		(net "GND")
	)
	(segment
		(start 27.6352 -31.75)
		(end 26.6192 -30.734)
		(width 0.4572)
		(layer "F.Cu")
		(net "GND")
	)
	(segment
		(start 28.575 -31.75)
		(end 27.6352 -31.75)
		(width 0.4572)
		(layer "F.Cu")
		(net "GND")
	)
	(segment
		(start 14.224 -304.970942)
		(end 14.224 -305.631342)
		(width 0.4572)
		(layer "F.Cu")
		(net "GND")
	)
	(segment
		(start 12.19327 -257.057652)
		(end 11.972544 -256.836926)
		(width 0.4572)
		(layer "F.Cu")
		(net "GND")
	)
	(segment
		(start 32.516064 -29.995114)
		(end 32.49295 -29.972)
		(width 0.4572)
		(layer "F.Cu")
		(net "GND")
	)
	(segment
		(start 37.846 -63.5)
		(end 37.592 -63.246)
		(width 0.4572)
		(layer "F.Cu")
		(net "GND")
	)
	(segment
		(start 35.687 -118.491)
		(end 36.068 -118.11)
		(width 0.4572)
		(layer "F.Cu")
		(net "GND")
	)
	(segment
		(start 15.34795 -98.95205)
		(end 15.494 -98.806)
		(width 0.4572)
		(layer "F.Cu")
		(net "GND")
	)
	(segment
		(start 32.639 -26.67)
		(end 33.71215 -26.67)
		(width 0.4572)
		(layer "F.Cu")
		(net "GND")
	)
	(segment
		(start 21.717 -119.52605)
		(end 21.717 -120.13565)
		(width 0.4572)
		(layer "F.Cu")
		(net "GND")
	)
	(segment
		(start 32.516064 -30.484064)
		(end 32.516064 -29.995114)
		(width 0.4572)
		(layer "F.Cu")
		(net "GND")
	)
	(segment
		(start 35.27044 -67.894962)
		(end 35.41649 -67.748912)
		(width 0.4572)
		(layer "F.Cu")
		(net "GND")
	)
	(segment
		(start 34.18205 -166.751)
		(end 34.18205 -167.386)
		(width 0.4572)
		(layer "F.Cu")
		(net "GND")
	)
	(segment
		(start 35.897058 -208.308956)
		(end 35.897058 -208.994756)
		(width 0.4572)
		(layer "F.Cu")
		(net "GND")
	)
	(segment
		(start 19.431 -17.92605)
		(end 19.093942 -18.263108)
		(width 0.4572)
		(layer "F.Cu")
		(net "GND")
	)
	(segment
		(start 32.94507 -197.560184)
		(end 33.5407 -198.155814)
		(width 0.4572)
		(layer "F.Cu")
		(net "GND")
	)
	(segment
		(start 34.750756 -13.5128)
		(end 36.01085 -13.5128)
		(width 0.4572)
		(layer "F.Cu")
		(net "GND")
	)
	(segment
		(start 8.509 -176.38395)
		(end 7.366 -176.38395)
		(width 0.3556)
		(layer "F.Cu")
		(net "GND")
	)
	(segment
		(start 32.468058 -114.709956)
		(end 32.468058 -114.47272)
		(width 0.4572)
		(layer "F.Cu")
		(net "GND")
	)
	(segment
		(start 29.845 -194.41795)
		(end 29.845 -193.821304)
		(width 0.4572)
		(layer "F.Cu")
		(net "GND")
	)
	(segment
		(start 39.606982 -256.413)
		(end 39.606982 -256.01295)
		(width 0.4572)
		(layer "F.Cu")
		(net "GND")
	)
	(segment
		(start 16.02105 -173.99)
		(end 16.63065 -173.99)
		(width 0.4572)
		(layer "F.Cu")
		(net "GND")
	)
	(segment
		(start 19.781012 -101.950012)
		(end 19.104864 -101.950012)
		(width 0.4572)
		(layer "F.Cu")
		(net "GND")
	)
	(segment
		(start 32.468058 -114.47272)
		(end 32.894778 -114.046)
		(width 0.4572)
		(layer "F.Cu")
		(net "GND")
	)
	(segment
		(start 37.719 -99.20605)
		(end 37.719 -99.8728)
		(width 0.4572)
		(layer "F.Cu")
		(net "GND")
	)
	(segment
		(start 16.02105 -163.328604)
		(end 16.02105 -162.814)
		(width 0.4572)
		(layer "F.Cu")
		(net "GND")
	)
	(segment
		(start 32.61995 -299.363892)
		(end 32.595058 -299.339)
		(width 0.4572)
		(layer "F.Cu")
		(net "GND")
	)
	(segment
		(start 6.477 -249.19305)
		(end 6.477 -248.285)
		(width 0.4572)
		(layer "F.Cu")
		(net "GND")
	)
	(segment
		(start 38.1 -216.027)
		(end 39.09695 -217.02395)
		(width 0.4572)
		(layer "F.Cu")
		(net "GND")
	)
	(segment
		(start 15.802864 -105.506012)
		(end 15.802864 -104.820212)
		(width 0.4572)
		(layer "F.Cu")
		(net "GND")
	)
	(segment
		(start 12.196064 -130.941064)
		(end 10.559034 -130.941064)
		(width 0.2794)
		(layer "F.Cu")
		(net "GND")
	)
	(segment
		(start 20.5486 -159.131)
		(end 20.5486 -159.61995)
		(width 0.4572)
		(layer "F.Cu")
		(net "GND")
	)
	(segment
		(start 14.775942 -205.74)
		(end 15.494 -205.74)
		(width 0.4572)
		(layer "F.Cu")
		(net "GND")
	)
	(segment
		(start 39.4589 -100.33)
		(end 39.9161 -99.8728)
		(width 0.4572)
		(layer "F.Cu")
		(net "GND")
	)
	(segment
		(start 15.802864 -290.2331)
		(end 15.802864 -289.5473)
		(width 0.4572)
		(layer "F.Cu")
		(net "GND")
	)
	(segment
		(start 12.727686 -99.2124)
		(end 12.7381 -99.201986)
		(width 0.4572)
		(layer "F.Cu")
		(net "GND")
	)
	(segment
		(start 17.394174 -203.441554)
		(end 17.675606 -203.722986)
		(width 0.4572)
		(layer "F.Cu")
		(net "GND")
	)
	(segment
		(start 14.40942 -70.654926)
		(end 16.656558 -70.654926)
		(width 0.4572)
		(layer "F.Cu")
		(net "GND")
	)
	(segment
		(start 45.48505 -182.88)
		(end 46.09465 -182.88)
		(width 0.4572)
		(layer "F.Cu")
		(net "GND")
	)
	(segment
		(start 34.90595 -211.624926)
		(end 34.90595 -211.864956)
		(width 0.4572)
		(layer "F.Cu")
		(net "GND")
	)
	(segment
		(start 37.719 -99.8728)
		(end 38.1762 -100.33)
		(width 0.4572)
		(layer "F.Cu")
		(net "GND")
	)
	(segment
		(start 28.321 -101.19995)
		(end 28.321 -100.584)
		(width 0.4572)
		(layer "F.Cu")
		(net "GND")
	)
	(segment
		(start 19.562572 -211.850478)
		(end 19.562572 -212.538056)
		(width 0.4572)
		(layer "F.Cu")
		(net "GND")
	)
	(segment
		(start 28.829 -121.51995)
		(end 30.226 -121.51995)
		(width 0.4572)
		(layer "F.Cu")
		(net "GND")
	)
	(segment
		(start 34.77895 -207.038956)
		(end 34.16935 -207.038956)
		(width 0.4572)
		(layer "F.Cu")
		(net "GND")
	)
	(segment
		(start 36.913058 -108.712)
		(end 36.252658 -108.712)
		(width 0.4572)
		(layer "F.Cu")
		(net "GND")
	)
	(segment
		(start 18.0721 -299.353986)
		(end 18.875502 -299.353986)
		(width 0.4572)
		(layer "F.Cu")
		(net "GND")
	)
	(segment
		(start 44.06392 -70.904862)
		(end 43.91787 -71.050912)
		(width 0.4572)
		(layer "F.Cu")
		(net "GND")
	)
	(segment
		(start 36.479988 -203.27493)
		(end 36.066222 -203.27493)
		(width 0.4572)
		(layer "F.Cu")
		(net "GND")
	)
	(segment
		(start 17.272 -143.4338)
		(end 17.907 -142.7988)
		(width 0.4572)
		(layer "F.Cu")
		(net "GND")
	)
	(segment
		(start 18.0721 -295.289986)
		(end 18.0721 -296.037)
		(width 0.4572)
		(layer "F.Cu")
		(net "GND")
	)
	(segment
		(start 36.786058 -194.691)
		(end 36.786058 -193.93154)
		(width 0.4572)
		(layer "F.Cu")
		(net "GND")
	)
	(segment
		(start 19.06905 -104.14)
		(end 19.939 -104.14)
		(width 0.4572)
		(layer "F.Cu")
		(net "GND")
	)
	(segment
		(start 16.10995 -197.739)
		(end 14.902942 -197.739)
		(width 0.4572)
		(layer "F.Cu")
		(net "GND")
	)
	(segment
		(start 14.902942 -197.739)
		(end 14.902942 -197.0532)
		(width 0.4572)
		(layer "F.Cu")
		(net "GND")
	)
	(segment
		(start 22.479 -177.2412)
		(end 22.479 -178.435)
		(width 0.4572)
		(layer "F.Cu")
		(net "GND")
	)
	(segment
		(start 15.494 -98.806)
		(end 19.812 -98.806)
		(width 0.4572)
		(layer "F.Cu")
		(net "GND")
	)
	(segment
		(start 45.48505 -187.96)
		(end 46.09465 -187.96)
		(width 0.4572)
		(layer "F.Cu")
		(net "GND")
	)
	(segment
		(start 16.920972 -199.076056)
		(end 17.530572 -199.076056)
		(width 0.4572)
		(layer "F.Cu")
		(net "GND")
	)
	(segment
		(start 22.1488 -172.72)
		(end 22.606 -172.2628)
		(width 0.4572)
		(layer "F.Cu")
		(net "GND")
	)
	(segment
		(start 26.6192 -30.734)
		(end 26.5684 -30.734)
		(width 0.4572)
		(layer "F.Cu")
		(net "GND")
	)
	(segment
		(start 35.998912 -209.09661)
		(end 35.998912 -210.531964)
		(width 0.4572)
		(layer "F.Cu")
		(net "GND")
	)
	(segment
		(start 39.727378 -252.386846)
		(end 39.727378 -252.786896)
		(width 0.4572)
		(layer "F.Cu")
		(net "GND")
	)
	(segment
		(start 19.9136 -11.9888)
		(end 19.9136 -12.762992)
		(width 0.4572)
		(layer "F.Cu")
		(net "GND")
	)
	(segment
		(start 13.35405 -74.7522)
		(end 13.951204 -75.349354)
		(width 0.4572)
		(layer "F.Cu")
		(net "GND")
	)
	(segment
		(start 36.913058 -289.941)
		(end 35.978846 -289.941)
		(width 0.4572)
		(layer "F.Cu")
		(net "GND")
	)
	(segment
		(start 17.394174 -116.135912)
		(end 15.436342 -116.135912)
		(width 0.4572)
		(layer "F.Cu")
		(net "GND")
	)
	(segment
		(start 24.23795 -187.452)
		(end 23.62835 -187.452)
		(width 0.4572)
		(layer "F.Cu")
		(net "GND")
	)
	(segment
		(start 19.177 -32.40405)
		(end 19.91995 -32.40405)
		(width 0.4572)
		(layer "F.Cu")
		(net "GND")
	)
	(segment
		(start 28.687014 -290.50996)
		(end 28.687014 -291.14496)
		(width 0.4572)
		(layer "F.Cu")
		(net "GND")
	)
	(segment
		(start 35.897058 -28.661868)
		(end 35.897058 -29.347668)
		(width 0.4572)
		(layer "F.Cu")
		(net "GND")
	)
	(segment
		(start 21.59 -100.584)
		(end 28.321 -100.584)
		(width 0.4572)
		(layer "F.Cu")
		(net "GND")
	)
	(segment
		(start 48.53305 -179.324)
		(end 49.14265 -179.324)
		(width 0.4572)
		(layer "F.Cu")
		(net "GND")
	)
	(segment
		(start 17.358868 -19.136868)
		(end 17.5514 -19.3294)
		(width 0.4572)
		(layer "F.Cu")
		(net "GND")
	)
	(segment
		(start 19.093942 -106.737912)
		(end 19.754342 -106.737912)
		(width 0.4572)
		(layer "F.Cu")
		(net "GND")
	)
	(segment
		(start 16.920972 -291.5031)
		(end 17.530572 -291.5031)
		(width 0.4572)
		(layer "F.Cu")
		(net "GND")
	)
	(segment
		(start 29.353002 -193.329306)
		(end 29.353002 -192.802002)
		(width 0.4572)
		(layer "F.Cu")
		(net "GND")
	)
	(segment
		(start 42.3164 -99.5426)
		(end 41.529 -100.33)
		(width 0.4572)
		(layer "F.Cu")
		(net "GND")
	)
	(segment
		(start 18.955004 -130.358896)
		(end 18.955004 -130.83032)
		(width 0.1778)
		(layer "F.Cu")
		(net "GND")
	)
	(segment
		(start 3.53695 -314.833)
		(end 2.794 -314.833)
		(width 0.4572)
		(layer "F.Cu")
		(net "GND")
	)
	(segment
		(start 12.5095 -131.2545)
		(end 12.196064 -130.941064)
		(width 0.2794)
		(layer "F.Cu")
		(net "GND")
	)
	(segment
		(start 34.036 -127.762)
		(end 33.838896 -127.959104)
		(width 0.1778)
		(layer "F.Cu")
		(net "GND")
	)
	(segment
		(start 21.22805 -172.72)
		(end 21.844 -172.72)
		(width 0.4572)
		(layer "F.Cu")
		(net "GND")
	)
	(segment
		(start 28.829 -101.70795)
		(end 28.321 -101.19995)
		(width 0.4572)
		(layer "F.Cu")
		(net "GND")
	)
	(segment
		(start 32.507682 -187.003436)
		(end 32.507682 -187.075572)
		(width 0.3556)
		(layer "F.Cu")
		(net "GND")
	)
	(segment
		(start 32.722058 -211.963)
		(end 32.004 -211.963)
		(width 0.4572)
		(layer "F.Cu")
		(net "GND")
	)
	(segment
		(start 29.083 -32.258)
		(end 28.575 -31.75)
		(width 0.4572)
		(layer "F.Cu")
		(net "GND")
	)
	(segment
		(start 16.429482 -255.50495)
		(end 16.283432 -255.651)
		(width 0.4572)
		(layer "F.Cu")
		(net "GND")
	)
	(segment
		(start 32.894778 -114.046)
		(end 34.671 -114.046)
		(width 0.4572)
		(layer "F.Cu")
		(net "GND")
	)
	(segment
		(start 37.973 -216.027)
		(end 38.1 -216.027)
		(width 0.4572)
		(layer "F.Cu")
		(net "GND")
	)
	(segment
		(start 43.18 -128.143)
		(end 43.692064 -128.655064)
		(width 0.2794)
		(layer "F.Cu")
		(net "GND")
	)
	(segment
		(start 47.64405 -186.182)
		(end 48.915828 -186.182)
		(width 0.4572)
		(layer "F.Cu")
		(net "GND")
	)
	(segment
		(start 14.097 -98.95205)
		(end 15.34795 -98.95205)
		(width 0.4572)
		(layer "F.Cu")
		(net "GND")
	)
	(segment
		(start 33.6169 -202.169014)
		(end 33.6169 -201.483214)
		(width 0.4572)
		(layer "F.Cu")
		(net "GND")
	)
	(segment
		(start 21.971 -122.301)
		(end 22.225 -122.555)
		(width 0.4572)
		(layer "F.Cu")
		(net "GND")
	)
	(segment
		(start 37.48405 -249.047)
		(end 38.227 -249.047)
		(width 0.4572)
		(layer "F.Cu")
		(net "GND")
	)
	(segment
		(start 39.9161 -98.552)
		(end 39.520114 -98.156014)
		(width 0.4572)
		(layer "F.Cu")
		(net "GND")
	)
	(segment
		(start 31.76905 -16.891)
		(end 32.254444 -17.376394)
		(width 0.4572)
		(layer "F.Cu")
		(net "GND")
	)
	(segment
		(start 17.272 -143.49095)
		(end 17.272 -143.4338)
		(width 0.4572)
		(layer "F.Cu")
		(net "GND")
	)
	(segment
		(start 29.69895 -99.20605)
		(end 37.719 -99.20605)
		(width 0.4572)
		(layer "F.Cu")
		(net "GND")
	)
	(segment
		(start 18.1991 -115.330986)
		(end 17.394174 -116.135912)
		(width 0.4572)
		(layer "F.Cu")
		(net "GND")
	)
	(segment
		(start 20.004532 -28.259786)
		(end 18.1991 -28.259786)
		(width 0.4572)
		(layer "F.Cu")
		(net "GND")
	)
	(segment
		(start 21.22805 -180.213)
		(end 21.22805 -178.816)
		(width 0.4572)
		(layer "F.Cu")
		(net "GND")
	)
	(segment
		(start 3.40995 -130.937)
		(end 2.794 -130.937)
		(width 0.4572)
		(layer "F.Cu")
		(net "GND")
	)
	(segment
		(start 22.1361 -216.168986)
		(end 21.6916 -216.613486)
		(width 0.4572)
		(layer "F.Cu")
		(net "GND")
	)
	(segment
		(start 24.0411 -32.018986)
		(end 25.180036 -32.018986)
		(width 0.4572)
		(layer "F.Cu")
		(net "GND")
	)
	(segment
		(start 3.5179 -252.49505)
		(end 3.87985 -252.857)
		(width 0.4572)
		(layer "F.Cu")
		(net "GND")
	)
	(segment
		(start 20.338796 -28.59405)
		(end 20.004532 -28.259786)
		(width 0.4572)
		(layer "F.Cu")
		(net "GND")
	)
	(segment
		(start 19.05 -143.1798)
		(end 19.05 -143.49095)
		(width 0.4572)
		(layer "F.Cu")
		(net "GND")
	)
	(segment
		(start 41.529 -100.33)
		(end 40.3733 -100.33)
		(width 0.4572)
		(layer "F.Cu")
		(net "GND")
	)
	(segment
		(start 25.12695 -180.615082)
		(end 24.765 -180.977032)
		(width 0.4572)
		(layer "F.Cu")
		(net "GND")
	)
	(segment
		(start 14.775942 -208.435956)
		(end 15.436342 -208.435956)
		(width 0.4572)
		(layer "F.Cu")
		(net "GND")
	)
	(segment
		(start 34.378646 -119.037608)
		(end 34.378646 -119.037354)
		(width 0.4572)
		(layer "F.Cu")
		(net "GND")
	)
	(segment
		(start 19.104864 -13.571728)
		(end 19.104864 -14.310868)
		(width 0.4572)
		(layer "F.Cu")
		(net "GND")
	)
	(segment
		(start 8.382 -135.65505)
		(end 9.012936 -135.65505)
		(width 0.4572)
		(layer "F.Cu")
		(net "GND")
	)
	(segment
		(start 18.1991 -27.573986)
		(end 18.1991 -28.259786)
		(width 0.4572)
		(layer "F.Cu")
		(net "GND")
	)
	(segment
		(start 39.606982 -256.01295)
		(end 39.841932 -255.778)
		(width 0.4572)
		(layer "F.Cu")
		(net "GND")
	)
	(segment
		(start 22.098 -178.816)
		(end 21.22805 -178.816)
		(width 0.4572)
		(layer "F.Cu")
		(net "GND")
	)
	(segment
		(start 16.51 -304.81905)
		(end 18.67027 -304.81905)
		(width 0.4572)
		(layer "F.Cu")
		(net "GND")
	)
	(segment
		(start 18.81505 -185.166)
		(end 18.81505 -185.928)
		(width 0.4572)
		(layer "F.Cu")
		(net "GND")
	)
	(segment
		(start 24.23795 -185.445908)
		(end 24.23795 -185.674)
		(width 0.4572)
		(layer "F.Cu")
		(net "GND")
	)
	(segment
		(start 15.802864 -119.476012)
		(end 16.5735 -119.476012)
		(width 0.4572)
		(layer "F.Cu")
		(net "GND")
	)
	(segment
		(start 14.902942 -28.175458)
		(end 14.9098 -28.1686)
		(width 0.4572)
		(layer "F.Cu")
		(net "GND")
	)
	(segment
		(start 16.793972 -101.950012)
		(end 17.099788 -101.950012)
		(width 0.4572)
		(layer "F.Cu")
		(net "GND")
	)
	(segment
		(start 36.913058 -300.609)
		(end 36.195 -300.609)
		(width 0.4572)
		(layer "F.Cu")
		(net "GND")
	)
	(segment
		(start 42.3164 -98.806)
		(end 42.3164 -99.5426)
		(width 0.4572)
		(layer "F.Cu")
		(net "GND")
	)
	(segment
		(start 23.128986 -24.70404)
		(end 23.128986 -24.03602)
		(width 0.4572)
		(layer "F.Cu")
		(net "GND")
	)
	(segment
		(start 16.02105 -169.291)
		(end 16.63065 -169.291)
		(width 0.4572)
		(layer "F.Cu")
		(net "GND")
	)
	(segment
		(start 22.225 -122.555)
		(end 22.225 -122.91695)
		(width 0.4572)
		(layer "F.Cu")
		(net "GND")
	)
	(segment
		(start 37.719 -13.926058)
		(end 37.694108 -13.95095)
		(width 0.4572)
		(layer "F.Cu")
		(net "GND")
	)
	(segment
		(start 16.637 -170.561)
		(end 16.383 -170.815)
		(width 0.4572)
		(layer "F.Cu")
		(net "GND")
	)
	(segment
		(start 42.43705 -191.516)
		(end 42.43705 -192.151)
		(width 0.4572)
		(layer "F.Cu")
		(net "GND")
	)
	(segment
		(start 25.12695 -179.451)
		(end 25.12695 -180.594)
		(width 0.4572)
		(layer "F.Cu")
		(net "GND")
	)
	(segment
		(start 18.669 -142.7988)
		(end 19.05 -143.1798)
		(width 0.4572)
		(layer "F.Cu")
		(net "GND")
	)
	(segment
		(start 7.493 -186.817)
		(end 6.731 -186.055)
		(width 0.4572)
		(layer "F.Cu")
		(net "GND")
	)
	(segment
		(start 29.464 -133.87705)
		(end 29.464 -134.493)
		(width 0.4572)
		(layer "F.Cu")
		(net "GND")
	)
	(segment
		(start 32.87395 -103.632)
		(end 31.924244 -103.632)
		(width 0.4572)
		(layer "F.Cu")
		(net "GND")
	)
	(segment
		(start 44.667932 -70.904862)
		(end 44.06392 -70.904862)
		(width 0.4572)
		(layer "F.Cu")
		(net "GND")
	)
	(segment
		(start 11.845544 -71.412862)
		(end 12.080494 -71.177912)
		(width 0.4572)
		(layer "F.Cu")
		(net "GND")
	)
	(segment
		(start 42.129964 -217.02395)
		(end 40.894 -217.02395)
		(width 0.4572)
		(layer "F.Cu")
		(net "GND")
	)
	(segment
		(start 38.227 -249.047)
		(end 38.354 -249.174)
		(width 0.4572)
		(layer "F.Cu")
		(net "GND")
	)
	(segment
		(start 44.831 -135.90905)
		(end 45.466 -135.90905)
		(width 0.4572)
		(layer "F.Cu")
		(net "GND")
	)
	(segment
		(start 35.19805 -300.609)
		(end 35.179 -300.62805)
		(width 0.4572)
		(layer "F.Cu")
		(net "GND")
	)
	(segment
		(start 2.39395 -186.436)
		(end 1.53035 -186.436)
		(width 0.4572)
		(layer "F.Cu")
		(net "GND")
	)
	(segment
		(start 27.5209 -32.751014)
		(end 28.589986 -32.751014)
		(width 0.4572)
		(layer "F.Cu")
		(net "GND")
	)
	(segment
		(start 30.226 -121.51995)
		(end 31.623 -121.51995)
		(width 0.4572)
		(layer "F.Cu")
		(net "GND")
	)
	(segment
		(start 32.595058 -299.339)
		(end 32.50438 -299.339)
		(width 0.4572)
		(layer "F.Cu")
		(net "GND")
	)
	(segment
		(start 27.270964 -33.00095)
		(end 27.5209 -32.751014)
		(width 0.4572)
		(layer "F.Cu")
		(net "GND")
	)
	(segment
		(start 25.12695 -180.594)
		(end 25.12695 -180.615082)
		(width 0.4572)
		(layer "F.Cu")
		(net "GND")
	)
	(segment
		(start 35.998912 -210.531964)
		(end 34.90595 -211.624926)
		(width 0.4572)
		(layer "F.Cu")
		(net "GND")
	)
	(segment
		(start 32.61995 -208.308956)
		(end 31.877 -208.308956)
		(width 0.4572)
		(layer "F.Cu")
		(net "GND")
	)
	(segment
		(start 33.103058 -31.623)
		(end 33.103058 -31.071058)
		(width 0.4572)
		(layer "F.Cu")
		(net "GND")
	)
	(segment
		(start 14.775942 -112.706912)
		(end 15.436342 -112.706912)
		(width 0.4572)
		(layer "F.Cu")
		(net "GND")
	)
	(segment
		(start 34.417 -19.572986)
		(end 34.417 -17.892014)
		(width 0.4572)
		(layer "F.Cu")
		(net "GND")
	)
	(segment
		(start 3.40995 -181.61)
		(end 3.40995 -180.975)
		(width 0.4572)
		(layer "F.Cu")
		(net "GND")
	)
	(segment
		(start 39.09695 -217.02395)
		(end 40.894 -217.02395)
		(width 0.4572)
		(layer "F.Cu")
		(net "GND")
	)
	(segment
		(start 35.19805 -193.147696)
		(end 35.19805 -193.548)
		(width 0.4572)
		(layer "F.Cu")
		(net "GND")
	)
	(segment
		(start 32.468058 -27.362912)
		(end 32.468058 -26.840942)
		(width 0.4572)
		(layer "F.Cu")
		(net "GND")
	)
	(segment
		(start 34.666428 -253.294896)
		(end 35.27044 -253.294896)
		(width 0.4572)
		(layer "F.Cu")
		(net "GND")
	)
	(segment
		(start 39.520114 -98.156014)
		(end 39.0779 -98.156014)
		(width 0.4572)
		(layer "F.Cu")
		(net "GND")
	)
	(segment
		(start 21.22805 -176.784)
		(end 21.844 -176.784)
		(width 0.4572)
		(layer "F.Cu")
		(net "GND")
	)
	(segment
		(start 2.54 -67.894962)
		(end 3.248914 -67.894962)
		(width 0.4572)
		(layer "F.Cu")
		(net "GND")
	)
	(segment
		(start 27.305 -198.76262)
		(end 27.747214 -198.320406)
		(width 0.4572)
		(layer "F.Cu")
		(net "GND")
	)
	(segment
		(start 34.666428 -67.894962)
		(end 35.27044 -67.894962)
		(width 0.4572)
		(layer "F.Cu")
		(net "GND")
	)
	(segment
		(start 16.393922 -13.910818)
		(end 16.43634 -13.910818)
		(width 0.4572)
		(layer "F.Cu")
		(net "GND")
	)
	(segment
		(start 25.12695 -130.175)
		(end 25.12695 -129.413)
		(width 0.4572)
		(layer "F.Cu")
		(net "GND")
	)
	(segment
		(start 34.925 -118.491)
		(end 35.687 -118.491)
		(width 0.4572)
		(layer "F.Cu")
		(net "GND")
	)
	(segment
		(start 32.74695 -286.766)
		(end 32.131 -286.766)
		(width 0.4572)
		(layer "F.Cu")
		(net "GND")
	)
	(segment
		(start 31.924244 -103.632)
		(end 31.592012 -103.964232)
		(width 0.4572)
		(layer "F.Cu")
		(net "GND")
	)
	(segment
		(start 21.22805 -174.752)
		(end 21.844 -174.752)
		(width 0.4572)
		(layer "F.Cu")
		(net "GND")
	)
	(segment
		(start 33.6169 -17.892014)
		(end 34.417 -17.892014)
		(width 0.4572)
		(layer "F.Cu")
		(net "GND")
	)
	(segment
		(start 18.1991 -207.786986)
		(end 18.1991 -208.534)
		(width 0.4572)
		(layer "F.Cu")
		(net "GND")
	)
	(segment
		(start 24.23795 -189.23)
		(end 23.622 -189.23)
		(width 0.4572)
		(layer "F.Cu")
		(net "GND")
	)
	(segment
		(start 33.6169 -290.434014)
		(end 34.417 -290.434014)
		(width 0.4572)
		(layer "F.Cu")
		(net "GND")
	)
	(segment
		(start 13.35405 -74.422)
		(end 13.35405 -74.7522)
		(width 0.4572)
		(layer "F.Cu")
		(net "GND")
	)
	(segment
		(start 10.85596 -166.878)
		(end 11.49096 -166.878)
		(width 0.4572)
		(layer "F.Cu")
		(net "GND")
	)
	(segment
		(start 44.667932 -255.50495)
		(end 44.06392 -255.50495)
		(width 0.4572)
		(layer "F.Cu")
		(net "GND")
	)
	(segment
		(start 16.02105 -166.4716)
		(end 16.02105 -167.64)
		(width 0.4572)
		(layer "F.Cu")
		(net "GND")
	)
	(segment
		(start 20.828 -136.41705)
		(end 22.225 -136.41705)
		(width 0.4572)
		(layer "F.Cu")
		(net "GND")
	)
	(segment
		(start 33.590484 -105.29443)
		(end 32.845756 -105.29443)
		(width 0.4572)
		(layer "F.Cu")
		(net "GND")
	)
	(segment
		(start 26.4414 -30.734)
		(end 26.04135 -31.13405)
		(width 0.4572)
		(layer "F.Cu")
		(net "GND")
	)
	(segment
		(start 32.468058 -26.840942)
		(end 32.639 -26.67)
		(width 0.4572)
		(layer "F.Cu")
		(net "GND")
	)
	(segment
		(start 19.013678 -155.34005)
		(end 19.939 -155.34005)
		(width 0.254)
		(layer "F.Cu")
		(net "GND")
	)
	(segment
		(start 34.293556 -13.0556)
		(end 34.293556 -12.948158)
		(width 0.4572)
		(layer "F.Cu")
		(net "GND")
	)
	(segment
		(start 22.991064 -216.168986)
		(end 23.495 -215.66505)
		(width 0.4572)
		(layer "F.Cu")
		(net "GND")
	)
	(segment
		(start 3.248914 -252.49505)
		(end 3.5179 -252.49505)
		(width 0.4572)
		(layer "F.Cu")
		(net "GND")
	)
	(segment
		(start 31.623 -121.51995)
		(end 33.02 -121.51995)
		(width 0.4572)
		(layer "F.Cu")
		(net "GND")
	)
	(segment
		(start 10.85596 -164.084)
		(end 11.557 -164.084)
		(width 0.4572)
		(layer "F.Cu")
		(net "GND")
	)
	(segment
		(start 23.6093 -208.713578)
		(end 23.586186 -208.713578)
		(width 0.4572)
		(layer "F.Cu")
		(net "GND")
	)
	(segment
		(start 17.099788 -101.950012)
		(end 17.4498 -101.6)
		(width 0.4572)
		(layer "F.Cu")
		(net "GND")
	)
	(segment
		(start 44.06392 -255.50495)
		(end 43.91787 -255.651)
		(width 0.4572)
		(layer "F.Cu")
		(net "GND")
	)
	(segment
		(start 18.923 -120.65)
		(end 18.30705 -120.65)
		(width 0.4572)
		(layer "F.Cu")
		(net "GND")
	)
	(segment
		(start 33.7439 -109.205014)
		(end 34.544 -109.205014)
		(width 0.4572)
		(layer "F.Cu")
		(net "GND")
	)
	(segment
		(start 28.814014 -19.543014)
		(end 28.814014 -19.99996)
		(width 0.4572)
		(layer "F.Cu")
		(net "GND")
	)
	(segment
		(start 32.340042 -179.660042)
		(end 33.274 -179.660042)
		(width 0.3556)
		(layer "F.Cu")
		(net "GND")
	)
	(segment
		(start 36.01085 -13.5128)
		(end 36.449 -13.95095)
		(width 0.4572)
		(layer "F.Cu")
		(net "GND")
	)
	(segment
		(start 32.163512 -119.564912)
		(end 31.877 -119.2784)
		(width 0.4572)
		(layer "F.Cu")
		(net "GND")
	)
	(segment
		(start 28.956 -150.114)
		(end 28.69565 -150.114)
		(width 0.3556)
		(layer "F.Cu")
		(net "GND")
	)
	(segment
		(start 12.7381 -99.201986)
		(end 13.847064 -99.201986)
		(width 0.4572)
		(layer "F.Cu")
		(net "GND")
	)
	(segment
		(start 14.33195 -260.096)
		(end 14.097 -260.096)
		(width 0.4572)
		(layer "F.Cu")
		(net "GND")
	)
	(segment
		(start 19.093942 -19.098768)
		(end 19.093942 -19.812)
		(width 0.4572)
		(layer "F.Cu")
		(net "GND")
	)
	(segment
		(start 35.897058 -208.994756)
		(end 35.998912 -209.09661)
		(width 0.4572)
		(layer "F.Cu")
		(net "GND")
	)
	(segment
		(start 11.972544 -256.836926)
		(end 11.972544 -256.413)
		(width 0.4572)
		(layer "F.Cu")
		(net "GND")
	)
	(segment
		(start 19.431 -136.41705)
		(end 20.828 -136.41705)
		(width 0.4572)
		(layer "F.Cu")
		(net "GND")
	)
	(segment
		(start 21.1582 -158.5214)
		(end 20.5486 -159.131)
		(width 0.4572)
		(layer "F.Cu")
		(net "GND")
	)
	(segment
		(start 36.252658 -23.876)
		(end 36.913058 -23.876)
		(width 0.4572)
		(layer "F.Cu")
		(net "GND")
	)
	(segment
		(start 16.26997 -164.338)
		(end 16.650208 -163.957762)
		(width 0.4572)
		(layer "F.Cu")
		(net "GND")
	)
	(segment
		(start 35.897058 -286.639)
		(end 35.897058 -287.15208)
		(width 0.4572)
		(layer "F.Cu")
		(net "GND")
	)
	(segment
		(start 32.468058 -114.709956)
		(end 32.356044 -114.709956)
		(width 0.4572)
		(layer "F.Cu")
		(net "GND")
	)
	(segment
		(start 17.675606 -203.722986)
		(end 18.1991 -203.722986)
		(width 0.4572)
		(layer "F.Cu")
		(net "GND")
	)
	(segment
		(start 37.592 -63.246)
		(end 37.10305 -63.246)
		(width 0.4572)
		(layer "F.Cu")
		(net "GND")
	)
	(segment
		(start 15.929864 -32.217868)
		(end 15.929864 -32.903668)
		(width 0.4572)
		(layer "F.Cu")
		(net "GND")
	)
	(segment
		(start 19.177 -33.02)
		(end 19.177 -32.40405)
		(width 0.4572)
		(layer "F.Cu")
		(net "GND")
	)
	(segment
		(start 27.747214 -198.320406)
		(end 27.813 -198.320406)
		(width 0.4572)
		(layer "F.Cu")
		(net "GND")
	)
	(segment
		(start 5.69595 -63.881)
		(end 5.69595 -63.596012)
		(width 0.4572)
		(layer "F.Cu")
		(net "GND")
	)
	(segment
		(start 28.589986 -32.751014)
		(end 29.083 -32.258)
		(width 0.4572)
		(layer "F.Cu")
		(net "GND")
	)
	(segment
		(start 15.029942 -297.815)
		(end 15.494 -297.815)
		(width 0.4572)
		(layer "F.Cu")
		(net "GND")
	)
	(segment
		(start 36.913058 -20.279868)
		(end 36.252658 -20.279868)
		(width 0.4572)
		(layer "F.Cu")
		(net "GND")
	)
	(segment
		(start 22.1361 -216.168986)
		(end 22.991064 -216.168986)
		(width 0.4572)
		(layer "F.Cu")
		(net "GND")
	)
	(segment
		(start 23.586186 -208.713578)
		(end 23.128986 -208.256378)
		(width 0.4572)
		(layer "F.Cu")
		(net "GND")
	)
	(segment
		(start 26.347674 -126.198376)
		(end 25.92705 -126.619)
		(width 0.4572)
		(layer "F.Cu")
		(net "GND")
	)
	(segment
		(start 14.902942 -24.765)
		(end 15.621 -24.765)
		(width 0.4572)
		(layer "F.Cu")
		(net "GND")
	)
	(segment
		(start 17.033494 -255.50495)
		(end 16.429482 -255.50495)
		(width 0.4572)
		(layer "F.Cu")
		(net "GND")
	)
	(segment
		(start 26.162 -33.00095)
		(end 27.270964 -33.00095)
		(width 0.4572)
		(layer "F.Cu")
		(net "GND")
	)
	(segment
		(start 28.321 -100.584)
		(end 28.702 -100.203)
		(width 0.4572)
		(layer "F.Cu")
		(net "GND")
	)
	(segment
		(start 21.844 -172.72)
		(end 22.1488 -172.72)
		(width 0.4572)
		(layer "F.Cu")
		(net "GND")
	)
	(segment
		(start 25.12695 -132.461)
		(end 25.12695 -133.096)
		(width 0.4572)
		(layer "F.Cu")
		(net "GND")
	)
	(segment
		(start 8.309864 -66.475864)
		(end 8.128 -66.294)
		(width 0.4572)
		(layer "F.Cu")
		(net "GND")
	)
	(segment
		(start 5.69595 -63.596012)
		(end 6.15315 -63.138812)
		(width 0.4572)
		(layer "F.Cu")
		(net "GND")
	)
	(segment
		(start 26.855928 -126.198376)
		(end 26.347674 -126.198376)
		(width 0.4572)
		(layer "F.Cu")
		(net "GND")
	)
	(segment
		(start 34.77895 -27.391868)
		(end 34.16935 -27.391868)
		(width 0.4572)
		(layer "F.Cu")
		(net "GND")
	)
	(segment
		(start 32.131 -179.451)
		(end 32.340042 -179.660042)
		(width 0.3556)
		(layer "F.Cu")
		(net "GND")
	)
	(segment
		(start 32.50438 -299.339)
		(end 31.86176 -298.69638)
		(width 0.4572)
		(layer "F.Cu")
		(net "GND")
	)
	(segment
		(start 6.15315 -63.138812)
		(end 6.48843 -63.138812)
		(width 0.4572)
		(layer "F.Cu")
		(net "GND")
	)
	(segment
		(start 3.40995 -184.658)
		(end 1.524 -184.658)
		(width 0.4572)
		(layer "F.Cu")
		(net "GND")
	)
	(segment
		(start 36.913058 -105.086912)
		(end 36.913058 -105.791)
		(width 0.4572)
		(layer "F.Cu")
		(net "GND")
	)
	(segment
		(start 34.671 -114.046)
		(end 34.77895 -114.15395)
		(width 0.4572)
		(layer "F.Cu")
		(net "GND")
	)
	(segment
		(start 34.378646 -119.037354)
		(end 34.925 -118.491)
		(width 0.4572)
		(layer "F.Cu")
		(net "GND")
	)
	(segment
		(start 22.225 -136.41705)
		(end 23.622 -136.41705)
		(width 0.4572)
		(layer "F.Cu")
		(net "GND")
	)
	(segment
		(start 39.727378 -67.386962)
		(end 39.492428 -67.621912)
		(width 0.4572)
		(layer "F.Cu")
		(net "GND")
	)
	(segment
		(start 15.802864 -17.866868)
		(end 15.802864 -17.225264)
		(width 0.4572)
		(layer "F.Cu")
		(net "GND")
	)
	(segment
		(start 32.507682 -187.075572)
		(end 32.966152 -187.534042)
		(width 0.3556)
		(layer "F.Cu")
		(net "GND")
	)
	(segment
		(start 10.53338 -99.1616)
		(end 10.58418 -99.2124)
		(width 0.4572)
		(layer "F.Cu")
		(net "GND")
	)
	(segment
		(start 19.431 -189.611)
		(end 18.81505 -189.611)
		(width 0.4572)
		(layer "F.Cu")
		(net "GND")
	)
	(segment
		(start 15.802864 -17.225264)
		(end 15.5702 -16.9926)
		(width 0.4572)
		(layer "F.Cu")
		(net "GND")
	)
	(segment
		(start 36.220146 -192.1256)
		(end 35.19805 -193.147696)
		(width 0.4572)
		(layer "F.Cu")
		(net "GND")
	)
	(segment
		(start 39.727378 -252.786896)
		(end 39.492428 -253.021846)
		(width 0.4572)
		(layer "F.Cu")
		(net "GND")
	)
	(segment
		(start 39.868348 -175.777398)
		(end 39.243 -175.15205)
		(width 0.3556)
		(layer "F.Cu")
		(net "GND")
	)
	(segment
		(start 34.90595 -304.165)
		(end 34.29 -304.165)
		(width 0.4572)
		(layer "F.Cu")
		(net "GND")
	)
	(segment
		(start 35.897058 -287.15208)
		(end 36.090352 -287.345374)
		(width 0.4572)
		(layer "F.Cu")
		(net "GND")
	)
	(segment
		(start 16.656558 -70.654926)
		(end 16.906494 -70.904862)
		(width 0.4572)
		(layer "F.Cu")
		(net "GND")
	)
	(segment
		(start 14.775942 -116.135912)
		(end 15.436342 -116.135912)
		(width 0.4572)
		(layer "F.Cu")
		(net "GND")
	)
	(segment
		(start 16.02105 -172.466)
		(end 16.63065 -172.466)
		(width 0.4572)
		(layer "F.Cu")
		(net "GND")
	)
	(segment
		(start 16.383 -170.815)
		(end 16.02105 -170.815)
		(width 0.4572)
		(layer "F.Cu")
		(net "GND")
	)
	(segment
		(start 32.766 -286.74695)
		(end 32.74695 -286.766)
		(width 0.4572)
		(layer "F.Cu")
		(net "GND")
	)
	(segment
		(start 19.812 -98.806)
		(end 21.59 -100.584)
		(width 0.4572)
		(layer "F.Cu")
		(net "GND")
	)
	(segment
		(start 9.398 -99.1616)
		(end 10.53338 -99.1616)
		(width 0.4572)
		(layer "F.Cu")
		(net "GND")
	)
	(segment
		(start 34.90595 -119.564912)
		(end 34.378646 -119.037608)
		(width 0.4572)
		(layer "F.Cu")
		(net "GND")
	)
	(segment
		(start 27.813 -198.30796)
		(end 28.433014 -198.30796)
		(width 0.4572)
		(layer "F.Cu")
		(net "GND")
	)
	(segment
		(start 36.068 -116.179854)
		(end 35.897058 -116.008912)
		(width 0.4572)
		(layer "F.Cu")
		(net "GND")
	)
	(segment
		(start 19.079972 -290.2331)
		(end 19.689572 -290.2331)
		(width 0.4572)
		(layer "F.Cu")
		(net "GND")
	)
	(segment
		(start 32.468058 -207.01)
		(end 31.807658 -207.01)
		(width 0.4572)
		(layer "F.Cu")
		(net "GND")
	)
	(segment
		(start 32.966152 -187.534042)
		(end 33.401 -187.534042)
		(width 0.3556)
		(layer "F.Cu")
		(net "GND")
	)
	(segment
		(start 16.920972 -19.136868)
		(end 17.358868 -19.136868)
		(width 0.4572)
		(layer "F.Cu")
		(net "GND")
	)
	(segment
		(start 46.75505 -165.608)
		(end 47.5107 -165.608)
		(width 0.4572)
		(layer "F.Cu")
		(net "GND")
	)
	(segment
		(start 41.16705 -75.057508)
		(end 41.16705 -74.168)
		(width 0.4572)
		(layer "F.Cu")
		(net "GND")
	)
	(segment
		(start 41.275 -259.842)
		(end 41.275 -259.86105)
		(width 0.4572)
		(layer "F.Cu")
		(net "GND")
	)
	(segment
		(start 37.82695 -185.166)
		(end 37.084 -185.166)
		(width 0.4572)
		(layer "F.Cu")
		(net "GND")
	)
	(segment
		(start 2.39395 -189.992)
		(end 1.53035 -189.992)
		(width 0.4572)
		(layer "F.Cu")
		(net "GND")
	)
	(segment
		(start 47.102014 -313.7281)
		(end 46.416214 -313.7281)
		(width 0.4572)
		(layer "F.Cu")
		(net "GND")
	)
	(segment
		(start 39.9161 -99.8728)
		(end 39.9161 -98.552)
		(width 0.4572)
		(layer "F.Cu")
		(net "GND")
	)
	(segment
		(start 19.57705 -211.836)
		(end 19.562572 -211.850478)
		(width 0.4572)
		(layer "F.Cu")
		(net "GND")
	)
	(segment
		(start 10.58418 -99.2124)
		(end 12.727686 -99.2124)
		(width 0.4572)
		(layer "F.Cu")
		(net "GND")
	)
	(segment
		(start 19.9136 -12.762992)
		(end 19.104864 -13.571728)
		(width 0.4572)
		(layer "F.Cu")
		(net "GND")
	)
	(segment
		(start 33.7439 -105.141014)
		(end 33.590484 -105.29443)
		(width 0.4572)
		(layer "F.Cu")
		(net "GND")
	)
	(segment
		(start 28.829 -121.51995)
		(end 28.829 -120.904)
		(width 0.4572)
		(layer "F.Cu")
		(net "GND")
	)
	(segment
		(start 42.291 -137.68705)
		(end 42.926 -137.68705)
		(width 0.4572)
		(layer "F.Cu")
		(net "GND")
	)
	(segment
		(start 21.22805 -181.61)
		(end 21.22805 -180.213)
		(width 0.4572)
		(layer "F.Cu")
		(net "GND")
	)
	(segment
		(start 14.775942 -298.069)
		(end 15.029942 -297.815)
		(width 0.4572)
		(layer "F.Cu")
		(net "GND")
	)
	(segment
		(start 42.3799 -216.774014)
		(end 42.129964 -217.02395)
		(width 0.4572)
		(layer "F.Cu")
		(net "GND")
	)
	(segment
		(start 19.093942 -18.263108)
		(end 19.093942 -19.098768)
		(width 0.4572)
		(layer "F.Cu")
		(net "GND")
	)
	(segment
		(start 2.39395 -188.214)
		(end 1.53035 -188.214)
		(width 0.4572)
		(layer "F.Cu")
		(net "GND")
	)
	(segment
		(start 34.16935 -27.1272)
		(end 34.16935 -27.391868)
		(width 0.4572)
		(layer "F.Cu")
		(net "GND")
	)
	(segment
		(start 17.907 -142.7988)
		(end 18.669 -142.7988)
		(width 0.4572)
		(layer "F.Cu")
		(net "GND")
	)
	(segment
		(start 40.3733 -100.33)
		(end 39.9161 -99.8728)
		(width 0.4572)
		(layer "F.Cu")
		(net "GND")
	)
	(segment
		(start 3.40995 -128.651)
		(end 2.794 -128.651)
		(width 0.4572)
		(layer "F.Cu")
		(net "GND")
	)
	(segment
		(start 16.793972 -194.250056)
		(end 17.448276 -194.250056)
		(width 0.4572)
		(layer "F.Cu")
		(net "GND")
	)
	(segment
		(start 36.913058 -292.354)
		(end 36.252658 -292.354)
		(width 0.4572)
		(layer "F.Cu")
		(net "GND")
	)
	(segment
		(start 32.254444 -17.376394)
		(end 33.10128 -17.376394)
		(width 0.4572)
		(layer "F.Cu")
		(net "GND")
	)
	(segment
		(start 14.902942 -28.877768)
		(end 14.902942 -28.175458)
		(width 0.4572)
		(layer "F.Cu")
		(net "GND")
	)
	(segment
		(start 32.544512 -116.008912)
		(end 31.8008 -115.2652)
		(width 0.4572)
		(layer "F.Cu")
		(net "GND")
	)
	(segment
		(start 22.0218 -176.784)
		(end 22.479 -177.2412)
		(width 0.4572)
		(layer "F.Cu")
		(net "GND")
	)
	(segment
		(start 29.845 -193.821304)
		(end 29.353002 -193.329306)
		(width 0.4572)
		(layer "F.Cu")
		(net "GND")
	)
	(segment
		(start 43.692064 -128.655064)
		(end 43.692064 -129.521966)
		(width 0.2794)
		(layer "F.Cu")
		(net "GND")
	)
	(segment
		(start 21.463 -102.616)
		(end 20.447 -102.616)
		(width 0.4572)
		(layer "F.Cu")
		(net "GND")
	)
	(segment
		(start 33.6169 -294.498014)
		(end 33.6169 -293.812214)
		(width 0.4572)
		(layer "F.Cu")
		(net "GND")
	)
	(segment
		(start 20.0914 -32.2326)
		(end 20.9042 -32.2326)
		(width 0.4572)
		(layer "F.Cu")
		(net "GND")
	)
	(segment
		(start 19.044666 -111.139986)
		(end 18.1991 -111.139986)
		(width 0.4572)
		(layer "F.Cu")
		(net "GND")
	)
	(segment
		(start 46.75505 -168.529)
		(end 47.5107 -168.529)
		(width 0.4572)
		(layer "F.Cu")
		(net "GND")
	)
	(segment
		(start 35.897058 -101.784912)
		(end 35.897058 -101.092)
		(width 0.4572)
		(layer "F.Cu")
		(net "GND")
	)
	(segment
		(start 21.717 -28.59405)
		(end 20.338796 -28.59405)
		(width 0.4572)
		(layer "F.Cu")
		(net "GND")
	)
	(segment
		(start 16.02105 -164.338)
		(end 16.26997 -164.338)
		(width 0.4572)
		(layer "F.Cu")
		(net "GND")
	)
	(segment
		(start 34.99104 -32.386778)
		(end 35.15995 -32.217868)
		(width 0.4572)
		(layer "F.Cu")
		(net "GND")
	)
	(segment
		(start 39.606982 -71.412862)
		(end 39.841932 -71.177912)
		(width 0.4572)
		(layer "F.Cu")
		(net "GND")
	)
	(segment
		(start 48.66005 -132.334)
		(end 48.66005 -131.699)
		(width 0.4572)
		(layer "F.Cu")
		(net "GND")
	)
	(segment
		(start 33.6169 -20.373086)
		(end 34.417 -19.572986)
		(width 0.381)
		(layer "F.Cu")
		(net "GND")
	)
	(segment
		(start 14.775942 -300.144942)
		(end 14.605 -299.974)
		(width 0.4572)
		(layer "F.Cu")
		(net "GND")
	)
	(segment
		(start 32.49295 -29.972)
		(end 31.877 -29.972)
		(width 0.4572)
		(layer "F.Cu")
		(net "GND")
	)
	(segment
		(start 23.128986 -299.105574)
		(end 24.06142 -298.17314)
		(width 0.4572)
		(layer "F.Cu")
		(net "GND")
	)
	(segment
		(start 22.479 -178.435)
		(end 22.098 -178.816)
		(width 0.4572)
		(layer "F.Cu")
		(net "GND")
	)
	(segment
		(start 36.913058 -201.041)
		(end 36.252658 -201.041)
		(width 0.4572)
		(layer "F.Cu")
		(net "GND")
	)
	(segment
		(start 39.727378 -66.986912)
		(end 39.727378 -67.386962)
		(width 0.4572)
		(layer "F.Cu")
		(net "GND")
	)
	(segment
		(start 47.35195 -315.087)
		(end 46.609 -315.087)
		(width 0.4572)
		(layer "F.Cu")
		(net "GND")
	)
	(segment
		(start 11.845544 -71.812912)
		(end 11.845544 -71.412862)
		(width 0.4572)
		(layer "F.Cu")
		(net "GND")
	)
	(segment
		(start 33.5407 -198.155814)
		(end 33.8709 -198.155814)
		(width 0.4572)
		(layer "F.Cu")
		(net "GND")
	)
	(segment
		(start 27.813 -198.320406)
		(end 27.813 -198.30796)
		(width 0.4572)
		(layer "F.Cu")
		(net "GND")
	)
	(segment
		(start 36.068 -118.11)
		(end 36.068 -116.179854)
		(width 0.4572)
		(layer "F.Cu")
		(net "GND")
	)
	(segment
		(start 36.786058 -203.581)
		(end 36.479988 -203.27493)
		(width 0.4572)
		(layer "F.Cu")
		(net "GND")
	)
	(segment
		(start 16.650208 -163.957762)
		(end 16.02105 -163.328604)
		(width 0.4572)
		(layer "F.Cu")
		(net "GND")
	)
	(segment
		(start 28.34005 -149.7584)
		(end 28.34005 -149.098)
		(width 0.3556)
		(layer "F.Cu")
		(net "GND")
	)
	(segment
		(start 16.43634 -13.910818)
		(end 17.401032 -12.946126)
		(width 0.4572)
		(layer "F.Cu")
		(net "GND")
	)
	(segment
		(start 33.103058 -31.071058)
		(end 32.516064 -30.484064)
		(width 0.4572)
		(layer "F.Cu")
		(net "GND")
	)
	(segment
		(start 28.702 -100.203)
		(end 29.69895 -99.20605)
		(width 0.4572)
		(layer "F.Cu")
		(net "GND")
	)
	(segment
		(start 26.5684 -30.734)
		(end 26.4414 -30.734)
		(width 0.4572)
		(layer "F.Cu")
		(net "GND")
	)
	(segment
		(start 13.847064 -99.201986)
		(end 14.097 -98.95205)
		(width 0.4572)
		(layer "F.Cu")
		(net "GND")
	)
	(segment
		(start 34.036 -127.254)
		(end 34.036 -127.762)
		(width 0.1778)
		(layer "F.Cu")
		(net "GND")
	)
	(segment
		(start 33.10128 -17.376394)
		(end 33.6169 -17.892014)
		(width 0.4572)
		(layer "F.Cu")
		(net "GND")
	)
	(segment
		(start 24.14905 -215.66505)
		(end 23.495 -215.66505)
		(width 0.4572)
		(layer "F.Cu")
		(net "GND")
	)
	(segment
		(start 26.04135 -31.13405)
		(end 25.4 -31.13405)
		(width 0.4572)
		(layer "F.Cu")
		(net "GND")
	)
	(segment
		(start 6.36905 -249.301)
		(end 6.477 -249.19305)
		(width 0.4572)
		(layer "F.Cu")
		(net "GND")
	)
	(segment
		(start 36.195 -300.609)
		(end 35.19805 -300.609)
		(width 0.4572)
		(layer "F.Cu")
		(net "GND")
	)
	(segment
		(start 19.093942 -291.465)
		(end 19.754342 -291.465)
		(width 0.4572)
		(layer "F.Cu")
		(net "GND")
	)
	(segment
		(start 37.694108 -13.95095)
		(end 36.449 -13.95095)
		(width 0.4572)
		(layer "F.Cu")
		(net "GND")
	)
	(segment
		(start 19.104864 -286.6771)
		(end 19.765264 -286.6771)
		(width 0.4572)
		(layer "F.Cu")
		(net "GND")
	)
	(segment
		(start 32.468058 -304.292)
		(end 31.75 -304.292)
		(width 0.4572)
		(layer "F.Cu")
		(net "GND")
	)
	(segment
		(start 21.6916 -216.613486)
		(end 21.6916 -218.059)
		(width 0.4572)
		(layer "F.Cu")
		(net "GND")
	)
	(segment
		(start 41.275 -259.86105)
		(end 41.89095 -260.477)
		(width 0.4572)
		(layer "F.Cu")
		(net "GND")
	)
	(segment
		(start 28.69565 -150.114)
		(end 28.34005 -149.7584)
		(width 0.3556)
		(layer "F.Cu")
		(net "GND")
	)
	(segment
		(start 3.40995 -132.08)
		(end 2.794 -132.08)
		(width 0.4572)
		(layer "F.Cu")
		(net "GND")
	)
	(segment
		(start 18.034 -136.41705)
		(end 17.399 -136.41705)
		(width 0.4572)
		(layer "F.Cu")
		(net "GND")
	)
	(segment
		(start 19.91995 -32.40405)
		(end 20.0914 -32.2326)
		(width 0.4572)
		(layer "F.Cu")
		(net "GND")
	)
	(segment
		(start 22.1488 -170.688)
		(end 21.22805 -170.688)
		(width 0.4572)
		(layer "F.Cu")
		(net "GND")
	)
	(segment
		(start 33.103058 -31.623)
		(end 33.103058 -31.860236)
		(width 0.4572)
		(layer "F.Cu")
		(net "GND")
	)
	(segment
		(start 22.606 -171.1452)
		(end 22.1488 -170.688)
		(width 0.4572)
		(layer "F.Cu")
		(net "GND")
	)
	(segment
		(start 21.844 -176.784)
		(end 22.0218 -176.784)
		(width 0.4572)
		(layer "F.Cu")
		(net "GND")
	)
	(segment
		(start 19.104864 -194.250056)
		(end 19.765264 -194.250056)
		(width 0.4572)
		(layer "F.Cu")
		(net "GND")
	)
	(segment
		(start 24.765 -180.977032)
		(end 24.765 -184.918858)
		(width 0.4572)
		(layer "F.Cu")
		(net "GND")
	)
	(segment
		(start 19.093942 -199.037956)
		(end 19.529044 -199.037956)
		(width 0.4572)
		(layer "F.Cu")
		(net "GND")
	)
	(segment
		(start 38.1762 -100.33)
		(end 39.4589 -100.33)
		(width 0.4572)
		(layer "F.Cu")
		(net "GND")
	)
	(segment
		(start 28.560014 -105.59796)
		(end 28.560014 -106.282236)
		(width 0.4572)
		(layer "F.Cu")
		(net "GND")
	)
	(segment
		(start 25.146 -216.662)
		(end 24.14905 -215.66505)
		(width 0.4572)
		(layer "F.Cu")
		(net "GND")
	)
	(segment
		(start 20.447 -102.616)
		(end 19.781012 -101.950012)
		(width 0.4572)
		(layer "F.Cu")
		(net "GND")
	)
	(via
		(at 3.32232 -48.982122)
		(size 0.508)
		(drill 0.254)
		(layers "F.Cu" "B.Cu")
		(net "GND")
	)
	(via
		(at 50.936144 -37.860986)
		(size 0.508)
		(drill 0.254)
		(layers "F.Cu" "B.Cu")
		(net "GND")
	)
	(via
		(at 46.064932 -269.942056)
		(size 0.508)
		(drill 0.254)
		(layers "F.Cu" "B.Cu")
		(net "GND")
	)
	(via
		(at 2.794 -128.651)
		(size 0.508)
		(drill 0.254)
		(layers "F.Cu" "B.Cu")
		(net "GND")
	)
	(via
		(at 31.220918 -9.4742)
		(size 0.508)
		(drill 0.254)
		(layers "F.Cu" "B.Cu")
		(net "GND")
	)
	(via
		(at 50.936144 -129.300986)
		(size 0.508)
		(drill 0.254)
		(layers "F.Cu" "B.Cu")
		(net "GND")
	)
	(via
		(at 0.76327 -307.51145)
		(size 0.508)
		(drill 0.254)
		(layers "F.Cu" "B.Cu")
		(net "GND")
	)
	(via
		(at 19.939 -130.175)
		(size 0.508)
		(drill 0.254)
		(layers "F.Cu" "B.Cu")
		(net "GND")
	)
	(via
		(at 48.809656 -43.394122)
		(size 0.508)
		(drill 0.254)
		(layers "F.Cu" "B.Cu")
		(net "GND")
	)
	(via
		(at 18.955004 -130.83032)
		(size 0.508)
		(drill 0.254)
		(layers "F.Cu" "B.Cu")
		(net "GND")
	)
	(via
		(at 19.765264 -194.250056)
		(size 0.508)
		(drill 0.254)
		(layers "F.Cu" "B.Cu")
		(net "GND")
	)
	(via
		(at 19.9136 -8.4328)
		(size 0.508)
		(drill 0.254)
		(layers "F.Cu" "B.Cu")
		(net "GND")
	)
	(via
		(at 21.463 -102.616)
		(size 0.508)
		(drill 0.254)
		(layers "F.Cu" "B.Cu")
		(net "GND")
	)
	(via
		(at 0.76327 -175.43145)
		(size 0.508)
		(drill 0.254)
		(layers "F.Cu" "B.Cu")
		(net "GND")
	)
	(via
		(at 49.266856 -227.58781)
		(size 0.508)
		(drill 0.254)
		(layers "F.Cu" "B.Cu")
		(net "GND")
	)
	(via
		(at 19.413474 -278.01951)
		(size 0.508)
		(drill 0.254)
		(layers "F.Cu" "B.Cu")
		(net "GND")
	)
	(via
		(at 34.378646 -119.037608)
		(size 0.508)
		(drill 0.254)
		(layers "F.Cu" "B.Cu")
		(net "GND")
	)
	(via
		(at 35.41649 -253.148846)
		(size 0.508)
		(drill 0.254)
		(layers "F.Cu" "B.Cu")
		(net "GND")
	)
	(via
		(at 38.354 -249.174)
		(size 0.508)
		(drill 0.254)
		(layers "F.Cu" "B.Cu")
		(net "GND")
	)
	(via
		(at 33.142428 -72.701912)
		(size 0.508)
		(drill 0.254)
		(layers "F.Cu" "B.Cu")
		(net "GND")
	)
	(via
		(at 8.074914 -252.222)
		(size 0.508)
		(drill 0.254)
		(layers "F.Cu" "B.Cu")
		(net "GND")
	)
	(via
		(at 41.365932 -62.160912)
		(size 0.508)
		(drill 0.254)
		(layers "F.Cu" "B.Cu")
		(net "GND")
	)
	(via
		(at 14.902942 -197.0532)
		(size 0.508)
		(drill 0.254)
		(layers "F.Cu" "B.Cu")
		(net "GND")
	)
	(via
		(at 0.76327 -221.15145)
		(size 0.508)
		(drill 0.254)
		(layers "F.Cu" "B.Cu")
		(net "GND")
	)
	(via
		(at 46.526958 -238.7854)
		(size 0.508)
		(drill 0.254)
		(layers "F.Cu" "B.Cu")
		(net "GND")
	)
	(via
		(at 21.717 -11.938)
		(size 0.508)
		(drill 0.254)
		(layers "F.Cu" "B.Cu")
		(net "GND")
	)
	(via
		(at 49.266856 -226.82581)
		(size 0.508)
		(drill 0.254)
		(layers "F.Cu" "B.Cu")
		(net "GND")
	)
	(via
		(at 19.562572 -212.538056)
		(size 0.508)
		(drill 0.254)
		(layers "F.Cu" "B.Cu")
		(net "GND")
	)
	(via
		(at 46.826932 -269.256256)
		(size 0.508)
		(drill 0.254)
		(layers "F.Cu" "B.Cu")
		(net "GND")
	)
	(via
		(at 15.802864 -211.04225)
		(size 0.508)
		(drill 0.254)
		(layers "F.Cu" "B.Cu")
		(net "GND")
	)
	(via
		(at 21.717 -120.13565)
		(size 0.508)
		(drill 0.254)
		(layers "F.Cu" "B.Cu")
		(net "GND")
	)
	(via
		(at 46.064932 -269.256256)
		(size 0.508)
		(drill 0.254)
		(layers "F.Cu" "B.Cu")
		(net "GND")
	)
	(via
		(at 46.753018 -65.158112)
		(size 0.508)
		(drill 0.254)
		(layers "F.Cu" "B.Cu")
		(net "GND")
	)
	(via
		(at 26.87701 -124.079)
		(size 0.508)
		(drill 0.254)
		(layers "F.Cu" "B.Cu")
		(net "GND")
	)
	(via
		(at 32.512 -128.143)
		(size 0.508)
		(drill 0.254)
		(layers "F.Cu" "B.Cu")
		(net "GND")
	)
	(via
		(at 23.128986 -24.03602)
		(size 0.508)
		(drill 0.254)
		(layers "F.Cu" "B.Cu")
		(net "GND")
	)
	(via
		(at 4.318 -269.93088)
		(size 0.508)
		(drill 0.254)
		(layers "F.Cu" "B.Cu")
		(net "GND")
	)
	(via
		(at 30.48 -128.143)
		(size 0.508)
		(drill 0.254)
		(layers "F.Cu" "B.Cu")
		(net "GND")
	)
	(via
		(at 50.936144 -251.220986)
		(size 0.508)
		(drill 0.254)
		(layers "F.Cu" "B.Cu")
		(net "GND")
	)
	(via
		(at 2.846832 -44.181522)
		(size 0.508)
		(drill 0.254)
		(layers "F.Cu" "B.Cu")
		(net "GND")
	)
	(via
		(at 3.44932 -51.217322)
		(size 0.508)
		(drill 0.254)
		(layers "F.Cu" "B.Cu")
		(net "GND")
	)
	(via
		(at 21.971 -122.301)
		(size 0.508)
		(drill 0.254)
		(layers "F.Cu" "B.Cu")
		(net "GND")
	)
	(via
		(at 25.12695 -130.175)
		(size 0.508)
		(drill 0.254)
		(layers "F.Cu" "B.Cu")
		(net "GND")
	)
	(via
		(at 0.76327 -114.47145)
		(size 0.508)
		(drill 0.254)
		(layers "F.Cu" "B.Cu")
		(net "GND")
	)
	(via
		(at 46.629828 -54.413912)
		(size 0.508)
		(drill 0.254)
		(layers "F.Cu" "B.Cu")
		(net "GND")
	)
	(via
		(at 36.252658 -108.712)
		(size 0.508)
		(drill 0.254)
		(layers "F.Cu" "B.Cu")
		(net "GND")
	)
	(via
		(at 50.936144 -210.580986)
		(size 0.508)
		(drill 0.254)
		(layers "F.Cu" "B.Cu")
		(net "GND")
	)
	(via
		(at 34.544 -109.205014)
		(size 0.508)
		(drill 0.254)
		(layers "F.Cu" "B.Cu")
		(net "GND")
	)
	(via
		(at 47.488856 -49.921922)
		(size 0.508)
		(drill 0.254)
		(layers "F.Cu" "B.Cu")
		(net "GND")
	)
	(via
		(at 15.536418 -65.107312)
		(size 0.508)
		(drill 0.254)
		(layers "F.Cu" "B.Cu")
		(net "GND")
	)
	(via
		(at 0.76327 -277.03145)
		(size 0.508)
		(drill 0.254)
		(layers "F.Cu" "B.Cu")
		(net "GND")
	)
	(via
		(at 12.995656 -252.50521)
		(size 0.508)
		(drill 0.254)
		(layers "F.Cu" "B.Cu")
		(net "GND")
	)
	(via
		(at 16.603218 -253.0856)
		(size 0.508)
		(drill 0.254)
		(layers "F.Cu" "B.Cu")
		(net "GND")
	)
	(via
		(at 0.76327 -144.95145)
		(size 0.508)
		(drill 0.254)
		(layers "F.Cu" "B.Cu")
		(net "GND")
	)
	(via
		(at 5.842 -269.93088)
		(size 0.508)
		(drill 0.254)
		(layers "F.Cu" "B.Cu")
		(net "GND")
	)
	(via
		(at 12.995656 -251.74321)
		(size 0.508)
		(drill 0.254)
		(layers "F.Cu" "B.Cu")
		(net "GND")
	)
	(via
		(at 46.831758 -231.267)
		(size 0.508)
		(drill 0.254)
		(layers "F.Cu" "B.Cu")
		(net "GND")
	)
	(via
		(at 32.507682 -187.003436)
		(size 0.508)
		(drill 0.254)
		(layers "F.Cu" "B.Cu")
		(net "GND")
	)
	(via
		(at 46.416214 -313.7281)
		(size 0.508)
		(drill 0.254)
		(layers "F.Cu" "B.Cu")
		(net "GND")
	)
	(via
		(at 48.174656 -42.632122)
		(size 0.508)
		(drill 0.254)
		(layers "F.Cu" "B.Cu")
		(net "GND")
	)
	(via
		(at 4.068318 -336.23758)
		(size 0.508)
		(drill 0.254)
		(layers "F.Cu" "B.Cu")
		(net "GND")
	)
	(via
		(at 16.63065 -172.466)
		(size 0.508)
		(drill 0.254)
		(layers "F.Cu" "B.Cu")
		(net "GND")
	)
	(via
		(at 6.14299 -73.463912)
		(size 0.508)
		(drill 0.254)
		(layers "F.Cu" "B.Cu")
		(net "GND")
	)
	(via
		(at 31.807658 -207.01)
		(size 0.508)
		(drill 0.254)
		(layers "F.Cu" "B.Cu")
		(net "GND")
	)
	(via
		(at 15.536418 -69.145912)
		(size 0.508)
		(drill 0.254)
		(layers "F.Cu" "B.Cu")
		(net "GND")
	)
	(via
		(at 0.76327 -210.99145)
		(size 0.508)
		(drill 0.254)
		(layers "F.Cu" "B.Cu")
		(net "GND")
	)
	(via
		(at 50.936144 -119.140986)
		(size 0.508)
		(drill 0.254)
		(layers "F.Cu" "B.Cu")
		(net "GND")
	)
	(via
		(at 46.09465 -181.102)
		(size 0.508)
		(drill 0.254)
		(layers "F.Cu" "B.Cu")
		(net "GND")
	)
	(via
		(at 14.012418 -65.843912)
		(size 0.508)
		(drill 0.254)
		(layers "F.Cu" "B.Cu")
		(net "GND")
	)
	(via
		(at 18.9738 -89.154)
		(size 0.508)
		(drill 0.254)
		(layers "F.Cu" "B.Cu")
		(net "GND")
	)
	(via
		(at 21.717 -9.271)
		(size 0.508)
		(drill 0.254)
		(layers "F.Cu" "B.Cu")
		(net "GND")
	)
	(via
		(at 34.417 -17.892014)
		(size 0.508)
		(drill 0.254)
		(layers "F.Cu" "B.Cu")
		(net "GND")
	)
	(via
		(at 18.1991 -28.259786)
		(size 0.508)
		(drill 0.254)
		(layers "F.Cu" "B.Cu")
		(net "GND")
	)
	(via
		(at 50.936144 -246.140986)
		(size 0.508)
		(drill 0.254)
		(layers "F.Cu" "B.Cu")
		(net "GND")
	)
	(via
		(at 47.588932 -269.942056)
		(size 0.508)
		(drill 0.254)
		(layers "F.Cu" "B.Cu")
		(net "GND")
	)
	(via
		(at 15.079218 -253.0856)
		(size 0.508)
		(drill 0.254)
		(layers "F.Cu" "B.Cu")
		(net "GND")
	)
	(via
		(at 31.877 -119.2784)
		(size 0.508)
		(drill 0.254)
		(layers "F.Cu" "B.Cu")
		(net "GND")
	)
	(via
		(at 50.936144 -88.660986)
		(size 0.508)
		(drill 0.254)
		(layers "F.Cu" "B.Cu")
		(net "GND")
	)
	(via
		(at 37.079428 -68.144898)
		(size 0.508)
		(drill 0.254)
		(layers "F.Cu" "B.Cu")
		(net "GND")
	)
	(via
		(at 34.260028 -258.0386)
		(size 0.508)
		(drill 0.254)
		(layers "F.Cu" "B.Cu")
		(net "GND")
	)
	(via
		(at 6.90499 -72.701912)
		(size 0.508)
		(drill 0.254)
		(layers "F.Cu" "B.Cu")
		(net "GND")
	)
	(via
		(at 19.9136 -11.0998)
		(size 0.508)
		(drill 0.254)
		(layers "F.Cu" "B.Cu")
		(net "GND")
	)
	(via
		(at 32.380428 -72.701912)
		(size 0.508)
		(drill 0.254)
		(layers "F.Cu" "B.Cu")
		(net "GND")
	)
	(via
		(at 6.731 -186.055)
		(size 0.508)
		(drill 0.254)
		(layers "F.Cu" "B.Cu")
		(net "GND")
	)
	(via
		(at 46.30039 -249.4788)
		(size 0.508)
		(drill 0.254)
		(layers "F.Cu" "B.Cu")
		(net "GND")
	)
	(via
		(at 0.76327 -12.87145)
		(size 0.508)
		(drill 0.254)
		(layers "F.Cu" "B.Cu")
		(net "GND")
	)
	(via
		(at 0.76327 -322.75145)
		(size 0.508)
		(drill 0.254)
		(layers "F.Cu" "B.Cu")
		(net "GND")
	)
	(via
		(at 46.09465 -187.96)
		(size 0.508)
		(drill 0.254)
		(layers "F.Cu" "B.Cu")
		(net "GND")
	)
	(via
		(at 49.657 -309.88)
		(size 0.508)
		(drill 0.254)
		(layers "F.Cu" "B.Cu")
		(net "GND")
	)
	(via
		(at 32.380428 -73.463912)
		(size 0.508)
		(drill 0.254)
		(layers "F.Cu" "B.Cu")
		(net "GND")
	)
	(via
		(at 21.717 -11.049)
		(size 0.508)
		(drill 0.254)
		(layers "F.Cu" "B.Cu")
		(net "GND")
	)
	(via
		(at 5.08 -85.325712)
		(size 0.508)
		(drill 0.254)
		(layers "F.Cu" "B.Cu")
		(net "GND")
	)
	(via
		(at 13.951204 -75.349354)
		(size 0.508)
		(drill 0.254)
		(layers "F.Cu" "B.Cu")
		(net "GND")
	)
	(via
		(at 31.592012 -103.964232)
		(size 0.508)
		(drill 0.254)
		(layers "F.Cu" "B.Cu")
		(net "GND")
	)
	(via
		(at 31.86176 -298.69638)
		(size 0.508)
		(drill 0.254)
		(layers "F.Cu" "B.Cu")
		(net "GND")
	)
	(via
		(at 0.76327 -7.79145)
		(size 0.508)
		(drill 0.254)
		(layers "F.Cu" "B.Cu")
		(net "GND")
	)
	(via
		(at 44.958 -132.588)
		(size 0.508)
		(drill 0.254)
		(layers "F.Cu" "B.Cu")
		(net "GND")
	)
	(via
		(at 30.48 -130.175)
		(size 0.508)
		(drill 0.254)
		(layers "F.Cu" "B.Cu")
		(net "GND")
	)
	(via
		(at 12.995656 -250.98121)
		(size 0.508)
		(drill 0.254)
		(layers "F.Cu" "B.Cu")
		(net "GND")
	)
	(via
		(at 6.48843 -63.138812)
		(size 0.508)
		(drill 0.254)
		(layers "F.Cu" "B.Cu")
		(net "GND")
	)
	(via
		(at 0.76327 -48.43145)
		(size 0.508)
		(drill 0.254)
		(layers "F.Cu" "B.Cu")
		(net "GND")
	)
	(via
		(at 50.936144 -53.100986)
		(size 0.508)
		(drill 0.254)
		(layers "F.Cu" "B.Cu")
		(net "GND")
	)
	(via
		(at 12.5095 -131.2545)
		(size 0.508)
		(drill 0.254)
		(layers "F.Cu" "B.Cu")
		(net "GND")
	)
	(via
		(at 37.084 -185.166)
		(size 0.508)
		(drill 0.254)
		(layers "F.Cu" "B.Cu")
		(net "GND")
	)
	(via
		(at 42.112946 -0.762508)
		(size 0.508)
		(drill 0.254)
		(layers "F.Cu" "B.Cu")
		(net "GND")
	)
	(via
		(at 46.039532 -68.460112)
		(size 0.508)
		(drill 0.254)
		(layers "F.Cu" "B.Cu")
		(net "GND")
	)
	(via
		(at 43.18 -128.143)
		(size 0.508)
		(drill 0.254)
		(layers "F.Cu" "B.Cu")
		(net "GND")
	)
	(via
		(at 50.57648 -2.515362)
		(size 0.508)
		(drill 0.254)
		(layers "F.Cu" "B.Cu")
		(net "GND")
	)
	(via
		(at 9.021318 -336.23758)
		(size 0.508)
		(drill 0.254)
		(layers "F.Cu" "B.Cu")
		(net "GND")
	)
	(via
		(at 47.515018 -65.158112)
		(size 0.508)
		(drill 0.254)
		(layers "F.Cu" "B.Cu")
		(net "GND")
	)
	(via
		(at 21.1582 -158.5214)
		(size 0.508)
		(drill 0.254)
		(layers "F.Cu" "B.Cu")
		(net "GND")
	)
	(via
		(at 45.787056 -228.32441)
		(size 0.508)
		(drill 0.254)
		(layers "F.Cu" "B.Cu")
		(net "GND")
	)
	(via
		(at 23.128986 -115.00104)
		(size 0.508)
		(drill 0.254)
		(layers "F.Cu" "B.Cu")
		(net "GND")
	)
	(via
		(at 4.61899 -73.463912)
		(size 0.508)
		(drill 0.254)
		(layers "F.Cu" "B.Cu")
		(net "GND")
	)
	(via
		(at 50.936144 -307.100986)
		(size 0.508)
		(drill 0.254)
		(layers "F.Cu" "B.Cu")
		(net "GND")
	)
	(via
		(at 46.141132 -253.492)
		(size 0.508)
		(drill 0.254)
		(layers "F.Cu" "B.Cu")
		(net "GND")
	)
	(via
		(at 48.809656 -42.632122)
		(size 0.508)
		(drill 0.254)
		(layers "F.Cu" "B.Cu")
		(net "GND")
	)
	(via
		(at 5.08 -269.93088)
		(size 0.508)
		(drill 0.254)
		(layers "F.Cu" "B.Cu")
		(net "GND")
	)
	(via
		(at 11.49096 -170.053)
		(size 0.508)
		(drill 0.254)
		(layers "F.Cu" "B.Cu")
		(net "GND")
	)
	(via
		(at 50.936144 -93.740986)
		(size 0.508)
		(drill 0.254)
		(layers "F.Cu" "B.Cu")
		(net "GND")
	)
	(via
		(at 45.074332 -85.300312)
		(size 0.508)
		(drill 0.254)
		(layers "F.Cu" "B.Cu")
		(net "GND")
	)
	(via
		(at 19.939 -104.14)
		(size 0.508)
		(drill 0.254)
		(layers "F.Cu" "B.Cu")
		(net "GND")
	)
	(via
		(at 2.601214 -313.4741)
		(size 0.508)
		(drill 0.254)
		(layers "F.Cu" "B.Cu")
		(net "GND")
	)
	(via
		(at 18.9738 -87.884)
		(size 0.508)
		(drill 0.254)
		(layers "F.Cu" "B.Cu")
		(net "GND")
	)
	(via
		(at 14.605 -299.974)
		(size 0.508)
		(drill 0.254)
		(layers "F.Cu" "B.Cu")
		(net "GND")
	)
	(via
		(at 46.831758 -234.823)
		(size 0.508)
		(drill 0.254)
		(layers "F.Cu" "B.Cu")
		(net "GND")
	)
	(via
		(at 23.6093 -208.713578)
		(size 0.508)
		(drill 0.254)
		(layers "F.Cu" "B.Cu")
		(net "GND")
	)
	(via
		(at 45.787056 -226.80041)
		(size 0.508)
		(drill 0.254)
		(layers "F.Cu" "B.Cu")
		(net "GND")
	)
	(via
		(at 32.736028 -258.0386)
		(size 0.508)
		(drill 0.254)
		(layers "F.Cu" "B.Cu")
		(net "GND")
	)
	(via
		(at 48.350932 -269.942056)
		(size 0.508)
		(drill 0.254)
		(layers "F.Cu" "B.Cu")
		(net "GND")
	)
	(via
		(at 4.31419 -261.3152)
		(size 0.508)
		(drill 0.254)
		(layers "F.Cu" "B.Cu")
		(net "GND")
	)
	(via
		(at 48.174656 -41.870122)
		(size 0.508)
		(drill 0.254)
		(layers "F.Cu" "B.Cu")
		(net "GND")
	)
	(via
		(at 48.174656 -43.394122)
		(size 0.508)
		(drill 0.254)
		(layers "F.Cu" "B.Cu")
		(net "GND")
	)
	(via
		(at 38.4302 -192.1256)
		(size 0.508)
		(drill 0.254)
		(layers "F.Cu" "B.Cu")
		(net "GND")
	)
	(via
		(at 32.131 -286.766)
		(size 0.508)
		(drill 0.254)
		(layers "F.Cu" "B.Cu")
		(net "GND")
	)
	(via
		(at 4.318 -85.325712)
		(size 0.508)
		(drill 0.254)
		(layers "F.Cu" "B.Cu")
		(net "GND")
	)
	(via
		(at 47.488856 -47.254922)
		(size 0.508)
		(drill 0.254)
		(layers "F.Cu" "B.Cu")
		(net "GND")
	)
	(via
		(at 0.76327 -58.59145)
		(size 0.508)
		(drill 0.254)
		(layers "F.Cu" "B.Cu")
		(net "GND")
	)
	(via
		(at 50.936144 -185.180986)
		(size 0.508)
		(drill 0.254)
		(layers "F.Cu" "B.Cu")
		(net "GND")
	)
	(via
		(at 0.76327 -94.15145)
		(size 0.508)
		(drill 0.254)
		(layers "F.Cu" "B.Cu")
		(net "GND")
	)
	(via
		(at 3.061462 -237.304072)
		(size 0.508)
		(drill 0.254)
		(layers "F.Cu" "B.Cu")
		(net "GND")
	)
	(via
		(at 28.702 -100.203)
		(size 0.508)
		(drill 0.254)
		(layers "F.Cu" "B.Cu")
		(net "GND")
	)
	(via
		(at 46.727618 -64.446912)
		(size 0.508)
		(drill 0.254)
		(layers "F.Cu" "B.Cu")
		(net "GND")
	)
	(via
		(at 48.350932 -269.256256)
		(size 0.508)
		(drill 0.254)
		(layers "F.Cu" "B.Cu")
		(net "GND")
	)
	(via
		(at 15.621 -24.765)
		(size 0.508)
		(drill 0.254)
		(layers "F.Cu" "B.Cu")
		(net "GND")
	)
	(via
		(at 6.731 -253.365)
		(size 0.508)
		(drill 0.254)
		(layers "F.Cu" "B.Cu")
		(net "GND")
	)
	(via
		(at 47.489618 -64.446912)
		(size 0.508)
		(drill 0.254)
		(layers "F.Cu" "B.Cu")
		(net "GND")
	)
	(via
		(at 50.936144 -281.700986)
		(size 0.508)
		(drill 0.254)
		(layers "F.Cu" "B.Cu")
		(net "GND")
	)
	(via
		(at 2.9718 -235.141262)
		(size 0.508)
		(drill 0.254)
		(layers "F.Cu" "B.Cu")
		(net "GND")
	)
	(via
		(at 3.015996 -39.342822)
		(size 0.508)
		(drill 0.254)
		(layers "F.Cu" "B.Cu")
		(net "GND")
	)
	(via
		(at 12.360656 -251.74321)
		(size 0.508)
		(drill 0.254)
		(layers "F.Cu" "B.Cu")
		(net "GND")
	)
	(via
		(at 0.76327 -190.67145)
		(size 0.508)
		(drill 0.254)
		(layers "F.Cu" "B.Cu")
		(net "GND")
	)
	(via
		(at 15.494 -297.815)
		(size 0.508)
		(drill 0.254)
		(layers "F.Cu" "B.Cu")
		(net "GND")
	)
	(via
		(at 2.794 -132.08)
		(size 0.508)
		(drill 0.254)
		(layers "F.Cu" "B.Cu")
		(net "GND")
	)
	(via
		(at 19.013678 -155.34005)
		(size 0.508)
		(drill 0.254)
		(layers "F.Cu" "B.Cu")
		(net "GND")
	)
	(via
		(at 15.536418 -65.843912)
		(size 0.508)
		(drill 0.254)
		(layers "F.Cu" "B.Cu")
		(net "GND")
	)
	(via
		(at 18.0721 -296.037)
		(size 0.508)
		(drill 0.254)
		(layers "F.Cu" "B.Cu")
		(net "GND")
	)
	(via
		(at 36.090352 -287.345374)
		(size 0.508)
		(drill 0.254)
		(layers "F.Cu" "B.Cu")
		(net "GND")
	)
	(via
		(at 0.76327 -195.75145)
		(size 0.508)
		(drill 0.254)
		(layers "F.Cu" "B.Cu")
		(net "GND")
	)
	(via
		(at 0.76327 -271.95145)
		(size 0.508)
		(drill 0.254)
		(layers "F.Cu" "B.Cu")
		(net "GND")
	)
	(via
		(at 33.6169 -201.483214)
		(size 0.508)
		(drill 0.254)
		(layers "F.Cu" "B.Cu")
		(net "GND")
	)
	(via
		(at 32.131 -179.451)
		(size 0.508)
		(drill 0.254)
		(layers "F.Cu" "B.Cu")
		(net "GND")
	)
	(via
		(at 50.936144 -235.980986)
		(size 0.508)
		(drill 0.254)
		(layers "F.Cu" "B.Cu")
		(net "GND")
	)
	(via
		(at 42.610532 -248.031)
		(size 0.508)
		(drill 0.254)
		(layers "F.Cu" "B.Cu")
		(net "GND")
	)
	(via
		(at 34.29 -304.165)
		(size 0.508)
		(drill 0.254)
		(layers "F.Cu" "B.Cu")
		(net "GND")
	)
	(via
		(at 3.44932 -50.455322)
		(size 0.508)
		(drill 0.254)
		(layers "F.Cu" "B.Cu")
		(net "GND")
	)
	(via
		(at 47.192946 -0.762508)
		(size 0.508)
		(drill 0.254)
		(layers "F.Cu" "B.Cu")
		(net "GND")
	)
	(via
		(at 3.061462 -238.066072)
		(size 0.508)
		(drill 0.254)
		(layers "F.Cu" "B.Cu")
		(net "GND")
	)
	(via
		(at 19.9136 -10.2108)
		(size 0.508)
		(drill 0.254)
		(layers "F.Cu" "B.Cu")
		(net "GND")
	)
	(via
		(at 18.1991 -23.941786)
		(size 0.508)
		(drill 0.254)
		(layers "F.Cu" "B.Cu")
		(net "GND")
	)
	(via
		(at 37.206428 -76.638912)
		(size 0.508)
		(drill 0.254)
		(layers "F.Cu" "B.Cu")
		(net "GND")
	)
	(via
		(at 8.871458 -0.763524)
		(size 0.508)
		(drill 0.254)
		(layers "F.Cu" "B.Cu")
		(net "GND")
	)
	(via
		(at 0.76327 -297.35145)
		(size 0.508)
		(drill 0.254)
		(layers "F.Cu" "B.Cu")
		(net "GND")
	)
	(via
		(at 4.572 -124.841)
		(size 0.508)
		(drill 0.254)
		(layers "F.Cu" "B.Cu")
		(net "GND")
	)
	(via
		(at 3.267456 -223.34601)
		(size 0.508)
		(drill 0.254)
		(layers "F.Cu" "B.Cu")
		(net "GND")
	)
	(via
		(at 19.765264 -286.6771)
		(size 0.508)
		(drill 0.254)
		(layers "F.Cu" "B.Cu")
		(net "GND")
	)
	(via
		(at 50.936144 -286.780986)
		(size 0.508)
		(drill 0.254)
		(layers "F.Cu" "B.Cu")
		(net "GND")
	)
	(via
		(at 3.87985 -252.857)
		(size 0.508)
		(drill 0.254)
		(layers "F.Cu" "B.Cu")
		(net "GND")
	)
	(via
		(at 11.49096 -166.878)
		(size 0.508)
		(drill 0.254)
		(layers "F.Cu" "B.Cu")
		(net "GND")
	)
	(via
		(at 5.07619 -261.3152)
		(size 0.508)
		(drill 0.254)
		(layers "F.Cu" "B.Cu")
		(net "GND")
	)
	(via
		(at 47.5107 -168.529)
		(size 0.508)
		(drill 0.254)
		(layers "F.Cu" "B.Cu")
		(net "GND")
	)
	(via
		(at 46.09465 -182.88)
		(size 0.508)
		(drill 0.254)
		(layers "F.Cu" "B.Cu")
		(net "GND")
	)
	(via
		(at 19.308318 -336.23758)
		(size 0.508)
		(drill 0.254)
		(layers "F.Cu" "B.Cu")
		(net "GND")
	)
	(via
		(at 3.267456 -221.82201)
		(size 0.508)
		(drill 0.254)
		(layers "F.Cu" "B.Cu")
		(net "GND")
	)
	(via
		(at 18.669 -142.7988)
		(size 0.508)
		(drill 0.254)
		(layers "F.Cu" "B.Cu")
		(net "GND")
	)
	(via
		(at 32.4866 -93.4466)
		(size 0.508)
		(drill 0.254)
		(layers "F.Cu" "B.Cu")
		(net "GND")
	)
	(via
		(at 15.494 -205.74)
		(size 0.508)
		(drill 0.254)
		(layers "F.Cu" "B.Cu")
		(net "GND")
	)
	(via
		(at 50.936144 -332.500986)
		(size 0.508)
		(drill 0.254)
		(layers "F.Cu" "B.Cu")
		(net "GND")
	)
	(via
		(at 30.752288 -278.638)
		(size 0.508)
		(drill 0.254)
		(layers "F.Cu" "B.Cu")
		(net "GND")
	)
	(via
		(at 28.956 -150.114)
		(size 0.508)
		(drill 0.254)
		(layers "F.Cu" "B.Cu")
		(net "GND")
	)
	(via
		(at 19.431 -189.611)
		(size 0.508)
		(drill 0.254)
		(layers "F.Cu" "B.Cu")
		(net "GND")
	)
	(via
		(at 6.60019 -258.0132)
		(size 0.508)
		(drill 0.254)
		(layers "F.Cu" "B.Cu")
		(net "GND")
	)
	(via
		(at 42.926 -132.588)
		(size 0.508)
		(drill 0.254)
		(layers "F.Cu" "B.Cu")
		(net "GND")
	)
	(via
		(at 50.936144 -276.620986)
		(size 0.508)
		(drill 0.254)
		(layers "F.Cu" "B.Cu")
		(net "GND")
	)
	(via
		(at 50.936144 -225.820986)
		(size 0.508)
		(drill 0.254)
		(layers "F.Cu" "B.Cu")
		(net "GND")
	)
	(via
		(at 50.936144 -22.620986)
		(size 0.508)
		(drill 0.254)
		(layers "F.Cu" "B.Cu")
		(net "GND")
	)
	(via
		(at 20.828 -211.72805)
		(size 0.508)
		(drill 0.254)
		(layers "F.Cu" "B.Cu")
		(net "GND")
	)
	(via
		(at 19.754342 -291.465)
		(size 0.508)
		(drill 0.254)
		(layers "F.Cu" "B.Cu")
		(net "GND")
	)
	(via
		(at 10.761218 -247.0912)
		(size 0.508)
		(drill 0.254)
		(layers "F.Cu" "B.Cu")
		(net "GND")
	)
	(via
		(at 50.936144 -175.020986)
		(size 0.508)
		(drill 0.254)
		(layers "F.Cu" "B.Cu")
		(net "GND")
	)
	(via
		(at 48.895 -308.61)
		(size 0.508)
		(drill 0.254)
		(layers "F.Cu" "B.Cu")
		(net "GND")
	)
	(via
		(at 46.903132 -253.492)
		(size 0.508)
		(drill 0.254)
		(layers "F.Cu" "B.Cu")
		(net "GND")
	)
	(via
		(at 14.774418 -69.145912)
		(size 0.508)
		(drill 0.254)
		(layers "F.Cu" "B.Cu")
		(net "GND")
	)
	(via
		(at 41.848532 -248.031)
		(size 0.508)
		(drill 0.254)
		(layers "F.Cu" "B.Cu")
		(net "GND")
	)
	(via
		(at 37.968428 -261.239)
		(size 0.508)
		(drill 0.254)
		(layers "F.Cu" "B.Cu")
		(net "GND")
	)
	(via
		(at 0.76327 -73.83145)
		(size 0.508)
		(drill 0.254)
		(layers "F.Cu" "B.Cu")
		(net "GND")
	)
	(via
		(at 0.76327 -236.39145)
		(size 0.508)
		(drill 0.254)
		(layers "F.Cu" "B.Cu")
		(net "GND")
	)
	(via
		(at 31.982918 -11.3792)
		(size 0.508)
		(drill 0.254)
		(layers "F.Cu" "B.Cu")
		(net "GND")
	)
	(via
		(at 50.936144 -42.940986)
		(size 0.508)
		(drill 0.254)
		(layers "F.Cu" "B.Cu")
		(net "GND")
	)
	(via
		(at 36.252658 -20.279868)
		(size 0.508)
		(drill 0.254)
		(layers "F.Cu" "B.Cu")
		(net "GND")
	)
	(via
		(at 32.512 -88.4682)
		(size 0.508)
		(drill 0.254)
		(layers "F.Cu" "B.Cu")
		(net "GND")
	)
	(via
		(at 45.229018 -65.158112)
		(size 0.508)
		(drill 0.254)
		(layers "F.Cu" "B.Cu")
		(net "GND")
	)
	(via
		(at 19.939 -128.143)
		(size 0.508)
		(drill 0.254)
		(layers "F.Cu" "B.Cu")
		(net "GND")
	)
	(via
		(at 23.622 -189.23)
		(size 0.508)
		(drill 0.254)
		(layers "F.Cu" "B.Cu")
		(net "GND")
	)
	(via
		(at 0.76327 -216.07145)
		(size 0.508)
		(drill 0.254)
		(layers "F.Cu" "B.Cu")
		(net "GND")
	)
	(via
		(at 46.609 -315.087)
		(size 0.508)
		(drill 0.254)
		(layers "F.Cu" "B.Cu")
		(net "GND")
	)
	(via
		(at 50.936144 -108.980986)
		(size 0.508)
		(drill 0.254)
		(layers "F.Cu" "B.Cu")
		(net "GND")
	)
	(via
		(at 35.897058 -208.994756)
		(size 0.508)
		(drill 0.254)
		(layers "F.Cu" "B.Cu")
		(net "GND")
	)
	(via
		(at 2.9718 -233.363262)
		(size 0.508)
		(drill 0.254)
		(layers "F.Cu" "B.Cu")
		(net "GND")
	)
	(via
		(at 42.290746 -70.226682)
		(size 0.508)
		(drill 0.254)
		(layers "F.Cu" "B.Cu")
		(net "GND")
	)
	(via
		(at 9.948418 -62.160912)
		(size 0.508)
		(drill 0.254)
		(layers "F.Cu" "B.Cu")
		(net "GND")
	)
	(via
		(at 0.76327 -139.87145)
		(size 0.508)
		(drill 0.254)
		(layers "F.Cu" "B.Cu")
		(net "GND")
	)
	(via
		(at 0.76327 -43.35145)
		(size 0.508)
		(drill 0.254)
		(layers "F.Cu" "B.Cu")
		(net "GND")
	)
	(via
		(at 33.904428 -72.701912)
		(size 0.508)
		(drill 0.254)
		(layers "F.Cu" "B.Cu")
		(net "GND")
	)
	(via
		(at 49.266856 -228.34981)
		(size 0.508)
		(drill 0.254)
		(layers "F.Cu" "B.Cu")
		(net "GND")
	)
	(via
		(at 5.83819 -257.2512)
		(size 0.508)
		(drill 0.254)
		(layers "F.Cu" "B.Cu")
		(net "GND")
	)
	(via
		(at 8.509 -176.38395)
		(size 0.508)
		(drill 0.254)
		(layers "F.Cu" "B.Cu")
		(net "GND")
	)
	(via
		(at 37.968428 -76.638912)
		(size 0.508)
		(drill 0.254)
		(layers "F.Cu" "B.Cu")
		(net "GND")
	)
	(via
		(at 47.665132 -252.73)
		(size 0.508)
		(drill 0.254)
		(layers "F.Cu" "B.Cu")
		(net "GND")
	)
	(via
		(at 5.38099 -73.463912)
		(size 0.508)
		(drill 0.254)
		(layers "F.Cu" "B.Cu")
		(net "GND")
	)
	(via
		(at 50.936144 -149.620986)
		(size 0.508)
		(drill 0.254)
		(layers "F.Cu" "B.Cu")
		(net "GND")
	)
	(via
		(at 33.498028 -258.0386)
		(size 0.508)
		(drill 0.254)
		(layers "F.Cu" "B.Cu")
		(net "GND")
	)
	(via
		(at 3.978656 -222.58401)
		(size 0.508)
		(drill 0.254)
		(layers "F.Cu" "B.Cu")
		(net "GND")
	)
	(via
		(at 47.82439 -249.4788)
		(size 0.508)
		(drill 0.254)
		(layers "F.Cu" "B.Cu")
		(net "GND")
	)
	(via
		(at 50.936144 -322.340986)
		(size 0.508)
		(drill 0.254)
		(layers "F.Cu" "B.Cu")
		(net "GND")
	)
	(via
		(at 0.76327 -205.91145)
		(size 0.508)
		(drill 0.254)
		(layers "F.Cu" "B.Cu")
		(net "GND")
	)
	(via
		(at 1.524 -184.658)
		(size 0.508)
		(drill 0.254)
		(layers "F.Cu" "B.Cu")
		(net "GND")
	)
	(via
		(at 26.855928 -126.198376)
		(size 0.508)
		(drill 0.254)
		(layers "F.Cu" "B.Cu")
		(net "GND")
	)
	(via
		(at 18.81505 -185.928)
		(size 0.508)
		(drill 0.254)
		(layers "F.Cu" "B.Cu")
		(net "GND")
	)
	(via
		(at 9.012936 -135.65505)
		(size 0.508)
		(drill 0.254)
		(layers "F.Cu" "B.Cu")
		(net "GND")
	)
	(via
		(at 44.708318 -336.23758)
		(size 0.508)
		(drill 0.254)
		(layers "F.Cu" "B.Cu")
		(net "GND")
	)
	(via
		(at 35.41649 -67.748912)
		(size 0.508)
		(drill 0.254)
		(layers "F.Cu" "B.Cu")
		(net "GND")
	)
	(via
		(at 31.220918 -11.3792)
		(size 0.508)
		(drill 0.254)
		(layers "F.Cu" "B.Cu")
		(net "GND")
	)
	(via
		(at 12.080494 -71.177912)
		(size 0.508)
		(drill 0.254)
		(layers "F.Cu" "B.Cu")
		(net "GND")
	)
	(via
		(at 49.204626 -40.002206)
		(size 0.508)
		(drill 0.254)
		(layers "F.Cu" "B.Cu")
		(net "GND")
	)
	(via
		(at 45.277532 -68.460112)
		(size 0.508)
		(drill 0.254)
		(layers "F.Cu" "B.Cu")
		(net "GND")
	)
	(via
		(at 46.598332 -85.300312)
		(size 0.508)
		(drill 0.254)
		(layers "F.Cu" "B.Cu")
		(net "GND")
	)
	(via
		(at 50.936144 -240.552986)
		(size 0.508)
		(drill 0.254)
		(layers "F.Cu" "B.Cu")
		(net "GND")
	)
	(via
		(at 47.5107 -167.513)
		(size 0.508)
		(drill 0.254)
		(layers "F.Cu" "B.Cu")
		(net "GND")
	)
	(via
		(at 36.252658 -292.354)
		(size 0.508)
		(drill 0.254)
		(layers "F.Cu" "B.Cu")
		(net "GND")
	)
	(via
		(at 42.926 -137.68705)
		(size 0.508)
		(drill 0.254)
		(layers "F.Cu" "B.Cu")
		(net "GND")
	)
	(via
		(at 19.812 -198.755)
		(size 0.508)
		(drill 0.254)
		(layers "F.Cu" "B.Cu")
		(net "GND")
	)
	(via
		(at 32.736028 -257.2766)
		(size 0.508)
		(drill 0.254)
		(layers "F.Cu" "B.Cu")
		(net "GND")
	)
	(via
		(at 2.846832 -43.419522)
		(size 0.508)
		(drill 0.254)
		(layers "F.Cu" "B.Cu")
		(net "GND")
	)
	(via
		(at 19.437604 -273.26463)
		(size 0.508)
		(drill 0.254)
		(layers "F.Cu" "B.Cu")
		(net "GND")
	)
	(via
		(at 46.831758 -237.363)
		(size 0.508)
		(drill 0.254)
		(layers "F.Cu" "B.Cu")
		(net "GND")
	)
	(via
		(at 50.936144 -215.660986)
		(size 0.508)
		(drill 0.254)
		(layers "F.Cu" "B.Cu")
		(net "GND")
	)
	(via
		(at 50.936144 -83.580986)
		(size 0.508)
		(drill 0.254)
		(layers "F.Cu" "B.Cu")
		(net "GND")
	)
	(via
		(at 45.836332 -85.300312)
		(size 0.508)
		(drill 0.254)
		(layers "F.Cu" "B.Cu")
		(net "GND")
	)
	(via
		(at 18.6182 -86.5124)
		(size 0.508)
		(drill 0.254)
		(layers "F.Cu" "B.Cu")
		(net "GND")
	)
	(via
		(at 37.079428 -253.544832)
		(size 0.508)
		(drill 0.254)
		(layers "F.Cu" "B.Cu")
		(net "GND")
	)
	(via
		(at 47.665132 -253.492)
		(size 0.508)
		(drill 0.254)
		(layers "F.Cu" "B.Cu")
		(net "GND")
	)
	(via
		(at 5.07619 -258.0132)
		(size 0.508)
		(drill 0.254)
		(layers "F.Cu" "B.Cu")
		(net "GND")
	)
	(via
		(at 14.012418 -69.145912)
		(size 0.508)
		(drill 0.254)
		(layers "F.Cu" "B.Cu")
		(net "GND")
	)
	(via
		(at 0.76327 -256.71145)
		(size 0.508)
		(drill 0.254)
		(layers "F.Cu" "B.Cu")
		(net "GND")
	)
	(via
		(at 45.787056 -226.03841)
		(size 0.508)
		(drill 0.254)
		(layers "F.Cu" "B.Cu")
		(net "GND")
	)
	(via
		(at 0.76327 -180.51145)
		(size 0.508)
		(drill 0.254)
		(layers "F.Cu" "B.Cu")
		(net "GND")
	)
	(via
		(at 3.756914 -52.585112)
		(size 0.508)
		(drill 0.254)
		(layers "F.Cu" "B.Cu")
		(net "GND")
	)
	(via
		(at 49.53 -124.587)
		(size 0.508)
		(drill 0.254)
		(layers "F.Cu" "B.Cu")
		(net "GND")
	)
	(via
		(at 50.936144 -27.700986)
		(size 0.508)
		(drill 0.254)
		(layers "F.Cu" "B.Cu")
		(net "GND")
	)
	(via
		(at 50.936144 -164.860986)
		(size 0.508)
		(drill 0.254)
		(layers "F.Cu" "B.Cu")
		(net "GND")
	)
	(via
		(at 0.76327 -89.07145)
		(size 0.508)
		(drill 0.254)
		(layers "F.Cu" "B.Cu")
		(net "GND")
	)
	(via
		(at 19.421856 -272.528538)
		(size 0.508)
		(drill 0.254)
		(layers "F.Cu" "B.Cu")
		(net "GND")
	)
	(via
		(at 17.530572 -291.5031)
		(size 0.508)
		(drill 0.254)
		(layers "F.Cu" "B.Cu")
		(net "GND")
	)
	(via
		(at 50.936144 -296.940986)
		(size 0.508)
		(drill 0.254)
		(layers "F.Cu" "B.Cu")
		(net "GND")
	)
	(via
		(at 50.936144 -327.420986)
		(size 0.508)
		(drill 0.254)
		(layers "F.Cu" "B.Cu")
		(net "GND")
	)
	(via
		(at 0.76327 -68.75145)
		(size 0.508)
		(drill 0.254)
		(layers "F.Cu" "B.Cu")
		(net "GND")
	)
	(via
		(at 39.628318 -336.23758)
		(size 0.508)
		(drill 0.254)
		(layers "F.Cu" "B.Cu")
		(net "GND")
	)
	(via
		(at 50.936144 -58.180986)
		(size 0.508)
		(drill 0.254)
		(layers "F.Cu" "B.Cu")
		(net "GND")
	)
	(via
		(at 6.604 -85.325712)
		(size 0.508)
		(drill 0.254)
		(layers "F.Cu" "B.Cu")
		(net "GND")
	)
	(via
		(at 14.012418 -65.107312)
		(size 0.508)
		(drill 0.254)
		(layers "F.Cu" "B.Cu")
		(net "GND")
	)
	(via
		(at 50.936144 -159.780986)
		(size 0.508)
		(drill 0.254)
		(layers "F.Cu" "B.Cu")
		(net "GND")
	)
	(via
		(at 50.936144 -195.340986)
		(size 0.508)
		(drill 0.254)
		(layers "F.Cu" "B.Cu")
		(net "GND")
	)
	(via
		(at 28.687014 -291.14496)
		(size 0.508)
		(drill 0.254)
		(layers "F.Cu" "B.Cu")
		(net "GND")
	)
	(via
		(at 34.036 -127.254)
		(size 0.508)
		(drill 0.254)
		(layers "F.Cu" "B.Cu")
		(net "GND")
	)
	(via
		(at 17.448276 -194.250056)
		(size 0.508)
		(drill 0.254)
		(layers "F.Cu" "B.Cu")
		(net "GND")
	)
	(via
		(at 34.16935 -207.038956)
		(size 0.508)
		(drill 0.254)
		(layers "F.Cu" "B.Cu")
		(net "GND")
	)
	(via
		(at 18.904712 -94.107)
		(size 0.508)
		(drill 0.254)
		(layers "F.Cu" "B.Cu")
		(net "GND")
	)
	(via
		(at 43.91787 -71.050912)
		(size 0.508)
		(drill 0.254)
		(layers "F.Cu" "B.Cu")
		(net "GND")
	)
	(via
		(at 0.76327 -38.27145)
		(size 0.508)
		(drill 0.254)
		(layers "F.Cu" "B.Cu")
		(net "GND")
	)
	(via
		(at 0.76327 -231.31145)
		(size 0.508)
		(drill 0.254)
		(layers "F.Cu" "B.Cu")
		(net "GND")
	)
	(via
		(at 2.9718 -232.601262)
		(size 0.508)
		(drill 0.254)
		(layers "F.Cu" "B.Cu")
		(net "GND")
	)
	(via
		(at 39.841932 -255.778)
		(size 0.508)
		(drill 0.254)
		(layers "F.Cu" "B.Cu")
		(net "GND")
	)
	(via
		(at 3.32232 -45.553122)
		(size 0.508)
		(drill 0.254)
		(layers "F.Cu" "B.Cu")
		(net "GND")
	)
	(via
		(at 37.27196 -0.766064)
		(size 0.508)
		(drill 0.254)
		(layers "F.Cu" "B.Cu")
		(net "GND")
	)
	(via
		(at 50.936144 -98.820986)
		(size 0.508)
		(drill 0.254)
		(layers "F.Cu" "B.Cu")
		(net "GND")
	)
	(via
		(at 10.710418 -62.160912)
		(size 0.508)
		(drill 0.254)
		(layers "F.Cu" "B.Cu")
		(net "GND")
	)
	(via
		(at 48.809656 -41.870122)
		(size 0.508)
		(drill 0.254)
		(layers "F.Cu" "B.Cu")
		(net "GND")
	)
	(via
		(at 15.5702 -16.9926)
		(size 0.508)
		(drill 0.254)
		(layers "F.Cu" "B.Cu")
		(net "GND")
	)
	(via
		(at 45.466 -135.90905)
		(size 0.508)
		(drill 0.254)
		(layers "F.Cu" "B.Cu")
		(net "GND")
	)
	(via
		(at 19.754342 -106.737912)
		(size 0.508)
		(drill 0.254)
		(layers "F.Cu" "B.Cu")
		(net "GND")
	)
	(via
		(at 28.575 -19.304)
		(size 0.508)
		(drill 0.254)
		(layers "F.Cu" "B.Cu")
		(net "GND")
	)
	(via
		(at 44.958 -130.556)
		(size 0.508)
		(drill 0.254)
		(layers "F.Cu" "B.Cu")
		(net "GND")
	)
	(via
		(at 42.254932 -255.255014)
		(size 0.508)
		(drill 0.254)
		(layers "F.Cu" "B.Cu")
		(net "GND")
	)
	(via
		(at 21.844 -174.752)
		(size 0.508)
		(drill 0.254)
		(layers "F.Cu" "B.Cu")
		(net "GND")
	)
	(via
		(at 50.936144 -220.740986)
		(size 0.508)
		(drill 0.254)
		(layers "F.Cu" "B.Cu")
		(net "GND")
	)
	(via
		(at 30.752288 -272.415)
		(size 0.508)
		(drill 0.254)
		(layers "F.Cu" "B.Cu")
		(net "GND")
	)
	(via
		(at 21.717 -8.382)
		(size 0.508)
		(drill 0.254)
		(layers "F.Cu" "B.Cu")
		(net "GND")
	)
	(via
		(at 47.588932 -269.256256)
		(size 0.508)
		(drill 0.254)
		(layers "F.Cu" "B.Cu")
		(net "GND")
	)
	(via
		(at 33.0708 -86.3346)
		(size 0.508)
		(drill 0.254)
		(layers "F.Cu" "B.Cu")
		(net "GND")
	)
	(via
		(at 9.44499 -76.638912)
		(size 0.508)
		(drill 0.254)
		(layers "F.Cu" "B.Cu")
		(net "GND")
	)
	(via
		(at 5.83819 -261.3152)
		(size 0.508)
		(drill 0.254)
		(layers "F.Cu" "B.Cu")
		(net "GND")
	)
	(via
		(at 42.43705 -192.151)
		(size 0.508)
		(drill 0.254)
		(layers "F.Cu" "B.Cu")
		(net "GND")
	)
	(via
		(at 36.252658 -23.876)
		(size 0.508)
		(drill 0.254)
		(layers "F.Cu" "B.Cu")
		(net "GND")
	)
	(via
		(at 50.936144 -139.460986)
		(size 0.508)
		(drill 0.254)
		(layers "F.Cu" "B.Cu")
		(net "GND")
	)
	(via
		(at 2.794 -308.61)
		(size 0.508)
		(drill 0.254)
		(layers "F.Cu" "B.Cu")
		(net "GND")
	)
	(via
		(at 50.936144 -12.460986)
		(size 0.508)
		(drill 0.254)
		(layers "F.Cu" "B.Cu")
		(net "GND")
	)
	(via
		(at 30.752288 -277.368)
		(size 0.508)
		(drill 0.254)
		(layers "F.Cu" "B.Cu")
		(net "GND")
	)
	(via
		(at 0.76327 -155.11145)
		(size 0.508)
		(drill 0.254)
		(layers "F.Cu" "B.Cu")
		(net "GND")
	)
	(via
		(at 6.477 -248.285)
		(size 0.508)
		(drill 0.254)
		(layers "F.Cu" "B.Cu")
		(net "GND")
	)
	(via
		(at 45.965618 -64.446912)
		(size 0.508)
		(drill 0.254)
		(layers "F.Cu" "B.Cu")
		(net "GND")
	)
	(via
		(at 0.76327 -282.11145)
		(size 0.508)
		(drill 0.254)
		(layers "F.Cu" "B.Cu")
		(net "GND")
	)
	(via
		(at 3.481832 -43.419522)
		(size 0.508)
		(drill 0.254)
		(layers "F.Cu" "B.Cu")
		(net "GND")
	)
	(via
		(at 1.53035 -188.214)
		(size 0.508)
		(drill 0.254)
		(layers "F.Cu" "B.Cu")
		(net "GND")
	)
	(via
		(at 3.556 -269.93088)
		(size 0.508)
		(drill 0.254)
		(layers "F.Cu" "B.Cu")
		(net "GND")
	)
	(via
		(at 46.526958 -239.5474)
		(size 0.508)
		(drill 0.254)
		(layers "F.Cu" "B.Cu")
		(net "GND")
	)
	(via
		(at 9.525 -132.207)
		(size 0.508)
		(drill 0.254)
		(layers "F.Cu" "B.Cu")
		(net "GND")
	)
	(via
		(at 15.841218 -253.0856)
		(size 0.508)
		(drill 0.254)
		(layers "F.Cu" "B.Cu")
		(net "GND")
	)
	(via
		(at 18.1991 -208.534)
		(size 0.508)
		(drill 0.254)
		(layers "F.Cu" "B.Cu")
		(net "GND")
	)
	(via
		(at 17.4498 -101.6)
		(size 0.508)
		(drill 0.254)
		(layers "F.Cu" "B.Cu")
		(net "GND")
	)
	(via
		(at 1.53035 -186.436)
		(size 0.508)
		(drill 0.254)
		(layers "F.Cu" "B.Cu")
		(net "GND")
	)
	(via
		(at 37.206428 -261.239)
		(size 0.508)
		(drill 0.254)
		(layers "F.Cu" "B.Cu")
		(net "GND")
	)
	(via
		(at 31.877 -208.308956)
		(size 0.508)
		(drill 0.254)
		(layers "F.Cu" "B.Cu")
		(net "GND")
	)
	(via
		(at 50.936144 -317.260986)
		(size 0.508)
		(drill 0.254)
		(layers "F.Cu" "B.Cu")
		(net "GND")
	)
	(via
		(at 32.19704 -272.039842)
		(size 0.508)
		(drill 0.254)
		(layers "F.Cu" "B.Cu")
		(net "GND")
	)
	(via
		(at 39.868348 -175.777398)
		(size 0.508)
		(drill 0.254)
		(layers "F.Cu" "B.Cu")
		(net "GND")
	)
	(via
		(at 0.76327 -160.19145)
		(size 0.508)
		(drill 0.254)
		(layers "F.Cu" "B.Cu")
		(net "GND")
	)
	(via
		(at 16.637 -170.561)
		(size 0.508)
		(drill 0.254)
		(layers "F.Cu" "B.Cu")
		(net "GND")
	)
	(via
		(at 31.877 -29.972)
		(size 0.508)
		(drill 0.254)
		(layers "F.Cu" "B.Cu")
		(net "GND")
	)
	(via
		(at 14.40942 -70.654926)
		(size 0.508)
		(drill 0.254)
		(layers "F.Cu" "B.Cu")
		(net "GND")
	)
	(via
		(at 49.266856 -225.30181)
		(size 0.508)
		(drill 0.254)
		(layers "F.Cu" "B.Cu")
		(net "GND")
	)
	(via
		(at 5.969 -314.198)
		(size 0.508)
		(drill 0.254)
		(layers "F.Cu" "B.Cu")
		(net "GND")
	)
	(via
		(at 39.841932 -71.177912)
		(size 0.508)
		(drill 0.254)
		(layers "F.Cu" "B.Cu")
		(net "GND")
	)
	(via
		(at 18.904712 -93.472)
		(size 0.508)
		(drill 0.254)
		(layers "F.Cu" "B.Cu")
		(net "GND")
	)
	(via
		(at 7.493 -132.207)
		(size 0.508)
		(drill 0.254)
		(layers "F.Cu" "B.Cu")
		(net "GND")
	)
	(via
		(at 47.488856 -48.016922)
		(size 0.508)
		(drill 0.254)
		(layers "F.Cu" "B.Cu")
		(net "GND")
	)
	(via
		(at 35.978846 -289.941)
		(size 0.508)
		(drill 0.254)
		(layers "F.Cu" "B.Cu")
		(net "GND")
	)
	(via
		(at 36.786058 -193.93154)
		(size 0.508)
		(drill 0.254)
		(layers "F.Cu" "B.Cu")
		(net "GND")
	)
	(via
		(at 50.936144 -32.780986)
		(size 0.508)
		(drill 0.254)
		(layers "F.Cu" "B.Cu")
		(net "GND")
	)
	(via
		(at 18.875502 -299.353986)
		(size 0.508)
		(drill 0.254)
		(layers "F.Cu" "B.Cu")
		(net "GND")
	)
	(via
		(at 0.76327 -226.23145)
		(size 0.508)
		(drill 0.254)
		(layers "F.Cu" "B.Cu")
		(net "GND")
	)
	(via
		(at 19.9136 -9.3218)
		(size 0.508)
		(drill 0.254)
		(layers "F.Cu" "B.Cu")
		(net "GND")
	)
	(via
		(at 2.9718 -229.807262)
		(size 0.508)
		(drill 0.254)
		(layers "F.Cu" "B.Cu")
		(net "GND")
	)
	(via
		(at 0.76327 -33.19145)
		(size 0.508)
		(drill 0.254)
		(layers "F.Cu" "B.Cu")
		(net "GND")
	)
	(via
		(at 32.4866 -87.6554)
		(size 0.508)
		(drill 0.254)
		(layers "F.Cu" "B.Cu")
		(net "GND")
	)
	(via
		(at 30.752288 -278.003)
		(size 0.508)
		(drill 0.254)
		(layers "F.Cu" "B.Cu")
		(net "GND")
	)
	(via
		(at 8.128 -66.294)
		(size 0.508)
		(drill 0.254)
		(layers "F.Cu" "B.Cu")
		(net "GND")
	)
	(via
		(at 19.044666 -111.139986)
		(size 0.508)
		(drill 0.254)
		(layers "F.Cu" "B.Cu")
		(net "GND")
	)
	(via
		(at 32.205422 -271.230852)
		(size 0.508)
		(drill 0.254)
		(layers "F.Cu" "B.Cu")
		(net "GND")
	)
	(via
		(at 0.76327 -109.39145)
		(size 0.508)
		(drill 0.254)
		(layers "F.Cu" "B.Cu")
		(net "GND")
	)
	(via
		(at 4.61899 -72.701912)
		(size 0.508)
		(drill 0.254)
		(layers "F.Cu" "B.Cu")
		(net "GND")
	)
	(via
		(at 5.07619 -257.2512)
		(size 0.508)
		(drill 0.254)
		(layers "F.Cu" "B.Cu")
		(net "GND")
	)
	(via
		(at 39.492428 -67.621912)
		(size 0.508)
		(drill 0.254)
		(layers "F.Cu" "B.Cu")
		(net "GND")
	)
	(via
		(at 18.904712 -92.837)
		(size 0.508)
		(drill 0.254)
		(layers "F.Cu" "B.Cu")
		(net "GND")
	)
	(via
		(at 19.276822 -269.529052)
		(size 0.508)
		(drill 0.254)
		(layers "F.Cu" "B.Cu")
		(net "GND")
	)
	(via
		(at 34.548318 -336.23758)
		(size 0.508)
		(drill 0.254)
		(layers "F.Cu" "B.Cu")
		(net "GND")
	)
	(via
		(at 0.76327 -241.47145)
		(size 0.508)
		(drill 0.254)
		(layers "F.Cu" "B.Cu")
		(net "GND")
	)
	(via
		(at 34.666428 -72.701912)
		(size 0.508)
		(drill 0.254)
		(layers "F.Cu" "B.Cu")
		(net "GND")
	)
	(via
		(at 31.220918 -10.1092)
		(size 0.508)
		(drill 0.254)
		(layers "F.Cu" "B.Cu")
		(net "GND")
	)
	(via
		(at 16.283432 -255.651)
		(size 0.508)
		(drill 0.254)
		(layers "F.Cu" "B.Cu")
		(net "GND")
	)
	(via
		(at 34.260028 -257.2766)
		(size 0.508)
		(drill 0.254)
		(layers "F.Cu" "B.Cu")
		(net "GND")
	)
	(via
		(at 31.982918 -12.6492)
		(size 0.508)
		(drill 0.254)
		(layers "F.Cu" "B.Cu")
		(net "GND")
	)
	(via
		(at 19.093942 -19.812)
		(size 0.508)
		(drill 0.254)
		(layers "F.Cu" "B.Cu")
		(net "GND")
	)
	(via
		(at 31.220918 -12.6492)
		(size 0.508)
		(drill 0.254)
		(layers "F.Cu" "B.Cu")
		(net "GND")
	)
	(via
		(at 2.032 -310.515)
		(size 0.508)
		(drill 0.254)
		(layers "F.Cu" "B.Cu")
		(net "GND")
	)
	(via
		(at 0.76327 -104.31145)
		(size 0.508)
		(drill 0.254)
		(layers "F.Cu" "B.Cu")
		(net "GND")
	)
	(via
		(at 17.530572 -106.776012)
		(size 0.508)
		(drill 0.254)
		(layers "F.Cu" "B.Cu")
		(net "GND")
	)
	(via
		(at 48.300132 -252.73)
		(size 0.508)
		(drill 0.254)
		(layers "F.Cu" "B.Cu")
		(net "GND")
	)
	(via
		(at 31.982918 -12.0142)
		(size 0.508)
		(drill 0.254)
		(layers "F.Cu" "B.Cu")
		(net "GND")
	)
	(via
		(at 47.488856 -50.683922)
		(size 0.508)
		(drill 0.254)
		(layers "F.Cu" "B.Cu")
		(net "GND")
	)
	(via
		(at 0.76327 -332.91145)
		(size 0.508)
		(drill 0.254)
		(layers "F.Cu" "B.Cu")
		(net "GND")
	)
	(via
		(at 29.468318 -336.23758)
		(size 0.508)
		(drill 0.254)
		(layers "F.Cu" "B.Cu")
		(net "GND")
	)
	(via
		(at 0.76327 -53.51145)
		(size 0.508)
		(drill 0.254)
		(layers "F.Cu" "B.Cu")
		(net "GND")
	)
	(via
		(at 32.845756 -105.29443)
		(size 0.508)
		(drill 0.254)
		(layers "F.Cu" "B.Cu")
		(net "GND")
	)
	(via
		(at 2.54 -67.894962)
		(size 0.508)
		(drill 0.254)
		(layers "F.Cu" "B.Cu")
		(net "GND")
	)
	(via
		(at 36.195 -300.609)
		(size 0.508)
		(drill 0.254)
		(layers "F.Cu" "B.Cu")
		(net "GND")
	)
	(via
		(at 30.752288 -273.685)
		(size 0.508)
		(drill 0.254)
		(layers "F.Cu" "B.Cu")
		(net "GND")
	)
	(via
		(at 47.438056 -53.020722)
		(size 0.508)
		(drill 0.254)
		(layers "F.Cu" "B.Cu")
		(net "GND")
	)
	(via
		(at 19.429222 -277.172166)
		(size 0.508)
		(drill 0.254)
		(layers "F.Cu" "B.Cu")
		(net "GND")
	)
	(via
		(at 33.6169 -293.812214)
		(size 0.508)
		(drill 0.254)
		(layers "F.Cu" "B.Cu")
		(net "GND")
	)
	(via
		(at 3.978656 -221.82201)
		(size 0.508)
		(drill 0.254)
		(layers "F.Cu" "B.Cu")
		(net "GND")
	)
	(via
		(at 48.66005 -131.699)
		(size 0.508)
		(drill 0.254)
		(layers "F.Cu" "B.Cu")
		(net "GND")
	)
	(via
		(at 28.560014 -106.282236)
		(size 0.508)
		(drill 0.254)
		(layers "F.Cu" "B.Cu")
		(net "GND")
	)
	(via
		(at 50.936144 -312.180986)
		(size 0.508)
		(drill 0.254)
		(layers "F.Cu" "B.Cu")
		(net "GND")
	)
	(via
		(at 30.734 -286.61995)
		(size 0.508)
		(drill 0.254)
		(layers "F.Cu" "B.Cu")
		(net "GND")
	)
	(via
		(at 0.76327 -327.83145)
		(size 0.508)
		(drill 0.254)
		(layers "F.Cu" "B.Cu")
		(net "GND")
	)
	(via
		(at 12.360656 -250.98121)
		(size 0.508)
		(drill 0.254)
		(layers "F.Cu" "B.Cu")
		(net "GND")
	)
	(via
		(at 0.76327 -124.63145)
		(size 0.508)
		(drill 0.254)
		(layers "F.Cu" "B.Cu")
		(net "GND")
	)
	(via
		(at 29.353002 -192.802002)
		(size 0.508)
		(drill 0.254)
		(layers "F.Cu" "B.Cu")
		(net "GND")
	)
	(via
		(at 45.203618 -64.446912)
		(size 0.508)
		(drill 0.254)
		(layers "F.Cu" "B.Cu")
		(net "GND")
	)
	(via
		(at 13.951458 -0.763524)
		(size 0.508)
		(drill 0.254)
		(layers "F.Cu" "B.Cu")
		(net "GND")
	)
	(via
		(at 31.974028 -258.0386)
		(size 0.508)
		(drill 0.254)
		(layers "F.Cu" "B.Cu")
		(net "GND")
	)
	(via
		(at 43.91787 -255.651)
		(size 0.508)
		(drill 0.254)
		(layers "F.Cu" "B.Cu")
		(net "GND")
	)
	(via
		(at 19.421856 -274.111974)
		(size 0.508)
		(drill 0.254)
		(layers "F.Cu" "B.Cu")
		(net "GND")
	)
	(via
		(at 31.8008 -115.2652)
		(size 0.508)
		(drill 0.254)
		(layers "F.Cu" "B.Cu")
		(net "GND")
	)
	(via
		(at 16.5735 -119.476012)
		(size 0.508)
		(drill 0.254)
		(layers "F.Cu" "B.Cu")
		(net "GND")
	)
	(via
		(at 18.923 -120.65)
		(size 0.508)
		(drill 0.254)
		(layers "F.Cu" "B.Cu")
		(net "GND")
	)
	(via
		(at 4.31419 -257.2512)
		(size 0.508)
		(drill 0.254)
		(layers "F.Cu" "B.Cu")
		(net "GND")
	)
	(via
		(at 0.76327 -317.67145)
		(size 0.508)
		(drill 0.254)
		(layers "F.Cu" "B.Cu")
		(net "GND")
	)
	(via
		(at 0.76327 -99.23145)
		(size 0.508)
		(drill 0.254)
		(layers "F.Cu" "B.Cu")
		(net "GND")
	)
	(via
		(at 31.220918 -12.0142)
		(size 0.508)
		(drill 0.254)
		(layers "F.Cu" "B.Cu")
		(net "GND")
	)
	(via
		(at 3.2512 -221.1324)
		(size 0.508)
		(drill 0.254)
		(layers "F.Cu" "B.Cu")
		(net "GND")
	)
	(via
		(at 6.60019 -261.3152)
		(size 0.508)
		(drill 0.254)
		(layers "F.Cu" "B.Cu")
		(net "GND")
	)
	(via
		(at 6.60019 -257.2512)
		(size 0.508)
		(drill 0.254)
		(layers "F.Cu" "B.Cu")
		(net "GND")
	)
	(via
		(at 24.388318 -336.23758)
		(size 0.508)
		(drill 0.254)
		(layers "F.Cu" "B.Cu")
		(net "GND")
	)
	(via
		(at 0.76327 -129.71145)
		(size 0.508)
		(drill 0.254)
		(layers "F.Cu" "B.Cu")
		(net "GND")
	)
	(via
		(at 35.897058 -29.347668)
		(size 0.508)
		(drill 0.254)
		(layers "F.Cu" "B.Cu")
		(net "GND")
	)
	(via
		(at 16.63065 -173.99)
		(size 0.508)
		(drill 0.254)
		(layers "F.Cu" "B.Cu")
		(net "GND")
	)
	(via
		(at 31.982918 -9.4742)
		(size 0.508)
		(drill 0.254)
		(layers "F.Cu" "B.Cu")
		(net "GND")
	)
	(via
		(at 21.971 -130.175)
		(size 0.508)
		(drill 0.254)
		(layers "F.Cu" "B.Cu")
		(net "GND")
	)
	(via
		(at 45.991018 -65.158112)
		(size 0.508)
		(drill 0.254)
		(layers "F.Cu" "B.Cu")
		(net "GND")
	)
	(via
		(at 50.936144 -17.540986)
		(size 0.508)
		(drill 0.254)
		(layers "F.Cu" "B.Cu")
		(net "GND")
	)
	(via
		(at 50.936144 -271.540986)
		(size 0.508)
		(drill 0.254)
		(layers "F.Cu" "B.Cu")
		(net "GND")
	)
	(via
		(at 46.831758 -232.029)
		(size 0.508)
		(drill 0.254)
		(layers "F.Cu" "B.Cu")
		(net "GND")
	)
	(via
		(at 14.224 -305.631342)
		(size 0.508)
		(drill 0.254)
		(layers "F.Cu" "B.Cu")
		(net "GND")
	)
	(via
		(at 5.207 -126.365)
		(size 0.508)
		(drill 0.254)
		(layers "F.Cu" "B.Cu")
		(net "GND")
	)
	(via
		(at 46.831758 -234.061)
		(size 0.508)
		(drill 0.254)
		(layers "F.Cu" "B.Cu")
		(net "GND")
	)
	(via
		(at 23.62835 -187.452)
		(size 0.508)
		(drill 0.254)
		(layers "F.Cu" "B.Cu")
		(net "GND")
	)
	(via
		(at 2.9718 -230.569262)
		(size 0.508)
		(drill 0.254)
		(layers "F.Cu" "B.Cu")
		(net "GND")
	)
	(via
		(at 2.794 -314.833)
		(size 0.508)
		(drill 0.254)
		(layers "F.Cu" "B.Cu")
		(net "GND")
	)
	(via
		(at 14.774418 -65.107312)
		(size 0.508)
		(drill 0.254)
		(layers "F.Cu" "B.Cu")
		(net "GND")
	)
	(via
		(at 49.657 -310.515)
		(size 0.508)
		(drill 0.254)
		(layers "F.Cu" "B.Cu")
		(net "GND")
	)
	(via
		(at 2.262632 -41.463722)
		(size 0.508)
		(drill 0.254)
		(layers "F.Cu" "B.Cu")
		(net "GND")
	)
	(via
		(at 31.982918 -10.7442)
		(size 0.508)
		(drill 0.254)
		(layers "F.Cu" "B.Cu")
		(net "GND")
	)
	(via
		(at 50.936144 -256.300986)
		(size 0.508)
		(drill 0.254)
		(layers "F.Cu" "B.Cu")
		(net "GND")
	)
	(via
		(at 3.32232 -48.220122)
		(size 0.508)
		(drill 0.254)
		(layers "F.Cu" "B.Cu")
		(net "GND")
	)
	(via
		(at 50.936144 -154.700986)
		(size 0.508)
		(drill 0.254)
		(layers "F.Cu" "B.Cu")
		(net "GND")
	)
	(via
		(at 25.146 -216.662)
		(size 0.508)
		(drill 0.254)
		(layers "F.Cu" "B.Cu")
		(net "GND")
	)
	(via
		(at 50.936144 -114.060986)
		(size 0.508)
		(drill 0.254)
		(layers "F.Cu" "B.Cu")
		(net "GND")
	)
	(via
		(at 37.973 -216.027)
		(size 0.508)
		(drill 0.254)
		(layers "F.Cu" "B.Cu")
		(net "GND")
	)
	(via
		(at 42.926 -130.556)
		(size 0.508)
		(drill 0.254)
		(layers "F.Cu" "B.Cu")
		(net "GND")
	)
	(via
		(at 4.030472 -0.76454)
		(size 0.508)
		(drill 0.254)
		(layers "F.Cu" "B.Cu")
		(net "GND")
	)
	(via
		(at 49.14265 -179.324)
		(size 0.508)
		(drill 0.254)
		(layers "F.Cu" "B.Cu")
		(net "GND")
	)
	(via
		(at 34.16935 -27.391868)
		(size 0.508)
		(drill 0.254)
		(layers "F.Cu" "B.Cu")
		(net "GND")
	)
	(via
		(at 0.76327 -246.55145)
		(size 0.508)
		(drill 0.254)
		(layers "F.Cu" "B.Cu")
		(net "GND")
	)
	(via
		(at 42.127932 -62.160912)
		(size 0.508)
		(drill 0.254)
		(layers "F.Cu" "B.Cu")
		(net "GND")
	)
	(via
		(at 12.360656 -250.21921)
		(size 0.508)
		(drill 0.254)
		(layers "F.Cu" "B.Cu")
		(net "GND")
	)
	(via
		(at 0.76327 -119.55145)
		(size 0.508)
		(drill 0.254)
		(layers "F.Cu" "B.Cu")
		(net "GND")
	)
	(via
		(at 14.317218 -253.0856)
		(size 0.508)
		(drill 0.254)
		(layers "F.Cu" "B.Cu")
		(net "GND")
	)
	(via
		(at 50.936144 -169.940986)
		(size 0.508)
		(drill 0.254)
		(layers "F.Cu" "B.Cu")
		(net "GND")
	)
	(via
		(at 13.250418 -65.843912)
		(size 0.508)
		(drill 0.254)
		(layers "F.Cu" "B.Cu")
		(net "GND")
	)
	(via
		(at 21.844 -172.72)
		(size 0.508)
		(drill 0.254)
		(layers "F.Cu" "B.Cu")
		(net "GND")
	)
	(via
		(at 18.9738 -88.519)
		(size 0.508)
		(drill 0.254)
		(layers "F.Cu" "B.Cu")
		(net "GND")
	)
	(via
		(at 0.76327 -83.99145)
		(size 0.508)
		(drill 0.254)
		(layers "F.Cu" "B.Cu")
		(net "GND")
	)
	(via
		(at 14.774418 -65.843912)
		(size 0.508)
		(drill 0.254)
		(layers "F.Cu" "B.Cu")
		(net "GND")
	)
	(via
		(at 50.936144 -291.860986)
		(size 0.508)
		(drill 0.254)
		(layers "F.Cu" "B.Cu")
		(net "GND")
	)
	(via
		(at 41.731184 -75.621642)
		(size 0.508)
		(drill 0.254)
		(layers "F.Cu" "B.Cu")
		(net "GND")
	)
	(via
		(at 15.436342 -116.135912)
		(size 0.508)
		(drill 0.254)
		(layers "F.Cu" "B.Cu")
		(net "GND")
	)
	(via
		(at 9.525 -130.175)
		(size 0.508)
		(drill 0.254)
		(layers "F.Cu" "B.Cu")
		(net "GND")
	)
	(via
		(at 3.481832 -44.181522)
		(size 0.508)
		(drill 0.254)
		(layers "F.Cu" "B.Cu")
		(net "GND")
	)
	(via
		(at 50.936144 -302.020986)
		(size 0.508)
		(drill 0.254)
		(layers "F.Cu" "B.Cu")
		(net "GND")
	)
	(via
		(at 27.305 -198.76262)
		(size 0.508)
		(drill 0.254)
		(layers "F.Cu" "B.Cu")
		(net "GND")
	)
	(via
		(at 48.174656 -44.156122)
		(size 0.508)
		(drill 0.254)
		(layers "F.Cu" "B.Cu")
		(net "GND")
	)
	(via
		(at 49.266856 -226.06381)
		(size 0.508)
		(drill 0.254)
		(layers "F.Cu" "B.Cu")
		(net "GND")
	)
	(via
		(at 7.493 -130.175)
		(size 0.508)
		(drill 0.254)
		(layers "F.Cu" "B.Cu")
		(net "GND")
	)
	(via
		(at 3.40995 -180.975)
		(size 0.508)
		(drill 0.254)
		(layers "F.Cu" "B.Cu")
		(net "GND")
	)
	(via
		(at 50.936144 -124.220986)
		(size 0.508)
		(drill 0.254)
		(layers "F.Cu" "B.Cu")
		(net "GND")
	)
	(via
		(at 0.76327 -200.83145)
		(size 0.508)
		(drill 0.254)
		(layers "F.Cu" "B.Cu")
		(net "GND")
	)
	(via
		(at 5.207 -125.73)
		(size 0.508)
		(drill 0.254)
		(layers "F.Cu" "B.Cu")
		(net "GND")
	)
	(via
		(at 31.75 -304.292)
		(size 0.508)
		(drill 0.254)
		(layers "F.Cu" "B.Cu")
		(net "GND")
	)
	(via
		(at 10.20699 -76.638912)
		(size 0.508)
		(drill 0.254)
		(layers "F.Cu" "B.Cu")
		(net "GND")
	)
	(via
		(at 19.437604 -271.681194)
		(size 0.508)
		(drill 0.254)
		(layers "F.Cu" "B.Cu")
		(net "GND")
	)
	(via
		(at 45.53839 -249.4788)
		(size 0.508)
		(drill 0.254)
		(layers "F.Cu" "B.Cu")
		(net "GND")
	)
	(via
		(at 29.083 -32.258)
		(size 0.508)
		(drill 0.254)
		(layers "F.Cu" "B.Cu")
		(net "GND")
	)
	(via
		(at 2.262632 -40.701722)
		(size 0.508)
		(drill 0.254)
		(layers "F.Cu" "B.Cu")
		(net "GND")
	)
	(via
		(at 36.252658 -201.041)
		(size 0.508)
		(drill 0.254)
		(layers "F.Cu" "B.Cu")
		(net "GND")
	)
	(via
		(at 32.4866 -89.3572)
		(size 0.508)
		(drill 0.254)
		(layers "F.Cu" "B.Cu")
		(net "GND")
	)
	(via
		(at 50.936144 -144.540986)
		(size 0.508)
		(drill 0.254)
		(layers "F.Cu" "B.Cu")
		(net "GND")
	)
	(via
		(at 3.756914 -53.347112)
		(size 0.508)
		(drill 0.254)
		(layers "F.Cu" "B.Cu")
		(net "GND")
	)
	(via
		(at 50.936144 -7.380986)
		(size 0.508)
		(drill 0.254)
		(layers "F.Cu" "B.Cu")
		(net "GND")
	)
	(via
		(at 50.936144 -48.020986)
		(size 0.508)
		(drill 0.254)
		(layers "F.Cu" "B.Cu")
		(net "GND")
	)
	(via
		(at 0.76327 -23.03145)
		(size 0.508)
		(drill 0.254)
		(layers "F.Cu" "B.Cu")
		(net "GND")
	)
	(via
		(at 50.936144 -261.380986)
		(size 0.508)
		(drill 0.254)
		(layers "F.Cu" "B.Cu")
		(net "GND")
	)
	(via
		(at 36.913058 -105.791)
		(size 0.508)
		(drill 0.254)
		(layers "F.Cu" "B.Cu")
		(net "GND")
	)
	(via
		(at 34.293556 -12.948158)
		(size 0.508)
		(drill 0.254)
		(layers "F.Cu" "B.Cu")
		(net "GND")
	)
	(via
		(at 24.06142 -298.17314)
		(size 0.508)
		(drill 0.254)
		(layers "F.Cu" "B.Cu")
		(net "GND")
	)
	(via
		(at 17.401032 -12.946126)
		(size 0.508)
		(drill 0.254)
		(layers "F.Cu" "B.Cu")
		(net "GND")
	)
	(via
		(at 12.360656 -252.50521)
		(size 0.508)
		(drill 0.254)
		(layers "F.Cu" "B.Cu")
		(net "GND")
	)
	(via
		(at 47.360332 -85.300312)
		(size 0.508)
		(drill 0.254)
		(layers "F.Cu" "B.Cu")
		(net "GND")
	)
	(via
		(at 33.498028 -257.2766)
		(size 0.508)
		(drill 0.254)
		(layers "F.Cu" "B.Cu")
		(net "GND")
	)
	(via
		(at 47.563532 -68.460112)
		(size 0.508)
		(drill 0.254)
		(layers "F.Cu" "B.Cu")
		(net "GND")
	)
	(via
		(at 5.842 -85.325712)
		(size 0.508)
		(drill 0.254)
		(layers "F.Cu" "B.Cu")
		(net "GND")
	)
	(via
		(at 41.275 -259.842)
		(size 0.508)
		(drill 0.254)
		(layers "F.Cu" "B.Cu")
		(net "GND")
	)
	(via
		(at 19.177 -33.02)
		(size 0.508)
		(drill 0.254)
		(layers "F.Cu" "B.Cu")
		(net "GND")
	)
	(via
		(at 50.936144 -73.420986)
		(size 0.508)
		(drill 0.254)
		(layers "F.Cu" "B.Cu")
		(net "GND")
	)
	(via
		(at 0.76327 -170.35145)
		(size 0.508)
		(drill 0.254)
		(layers "F.Cu" "B.Cu")
		(net "GND")
	)
	(via
		(at 0.76327 -251.63145)
		(size 0.508)
		(drill 0.254)
		(layers "F.Cu" "B.Cu")
		(net "GND")
	)
	(via
		(at 2.032 -309.88)
		(size 0.508)
		(drill 0.254)
		(layers "F.Cu" "B.Cu")
		(net "GND")
	)
	(via
		(at 21.971 -128.143)
		(size 0.508)
		(drill 0.254)
		(layers "F.Cu" "B.Cu")
		(net "GND")
	)
	(via
		(at 21.844 -176.784)
		(size 0.508)
		(drill 0.254)
		(layers "F.Cu" "B.Cu")
		(net "GND")
	)
	(via
		(at 0.76327 -63.67145)
		(size 0.508)
		(drill 0.254)
		(layers "F.Cu" "B.Cu")
		(net "GND")
	)
	(via
		(at 47.5107 -165.608)
		(size 0.508)
		(drill 0.254)
		(layers "F.Cu" "B.Cu")
		(net "GND")
	)
	(via
		(at 46.826932 -269.942056)
		(size 0.508)
		(drill 0.254)
		(layers "F.Cu" "B.Cu")
		(net "GND")
	)
	(via
		(at 14.9098 -28.1686)
		(size 0.508)
		(drill 0.254)
		(layers "F.Cu" "B.Cu")
		(net "GND")
	)
	(via
		(at 16.650208 -163.957762)
		(size 0.508)
		(drill 0.254)
		(layers "F.Cu" "B.Cu")
		(net "GND")
	)
	(via
		(at 0.76327 -302.43145)
		(size 0.508)
		(drill 0.254)
		(layers "F.Cu" "B.Cu")
		(net "GND")
	)
	(via
		(at 14.228318 -336.23758)
		(size 0.508)
		(drill 0.254)
		(layers "F.Cu" "B.Cu")
		(net "GND")
	)
	(via
		(at 15.802864 -289.5473)
		(size 0.508)
		(drill 0.254)
		(layers "F.Cu" "B.Cu")
		(net "GND")
	)
	(via
		(at 50.936144 -78.500986)
		(size 0.508)
		(drill 0.254)
		(layers "F.Cu" "B.Cu")
		(net "GND")
	)
	(via
		(at 47.06239 -249.4788)
		(size 0.508)
		(drill 0.254)
		(layers "F.Cu" "B.Cu")
		(net "GND")
	)
	(via
		(at 0.76327 -165.27145)
		(size 0.508)
		(drill 0.254)
		(layers "F.Cu" "B.Cu")
		(net "GND")
	)
	(via
		(at 32.94507 -197.560184)
		(size 0.508)
		(drill 0.254)
		(layers "F.Cu" "B.Cu")
		(net "GND")
	)
	(via
		(at 32.4866 -92.5322)
		(size 0.508)
		(drill 0.254)
		(layers "F.Cu" "B.Cu")
		(net "GND")
	)
	(via
		(at 31.974028 -257.2766)
		(size 0.508)
		(drill 0.254)
		(layers "F.Cu" "B.Cu")
		(net "GND")
	)
	(via
		(at 35.897058 -101.092)
		(size 0.508)
		(drill 0.254)
		(layers "F.Cu" "B.Cu")
		(net "GND")
	)
	(via
		(at 7.089648 -68.751704)
		(size 0.508)
		(drill 0.254)
		(layers "F.Cu" "B.Cu")
		(net "GND")
	)
	(via
		(at 46.831758 -236.601)
		(size 0.508)
		(drill 0.254)
		(layers "F.Cu" "B.Cu")
		(net "GND")
	)
	(via
		(at 16.8656 -166.4716)
		(size 0.508)
		(drill 0.254)
		(layers "F.Cu" "B.Cu")
		(net "GND")
	)
	(via
		(at 19.9136 -11.9888)
		(size 0.508)
		(drill 0.254)
		(layers "F.Cu" "B.Cu")
		(net "GND")
	)
	(via
		(at 36.066222 -203.27493)
		(size 0.508)
		(drill 0.254)
		(layers "F.Cu" "B.Cu")
		(net "GND")
	)
	(via
		(at 48.569626 -40.002206)
		(size 0.508)
		(drill 0.254)
		(layers "F.Cu" "B.Cu")
		(net "GND")
	)
	(via
		(at 16.298418 -69.145912)
		(size 0.508)
		(drill 0.254)
		(layers "F.Cu" "B.Cu")
		(net "GND")
	)
	(via
		(at 11.557 -164.084)
		(size 0.508)
		(drill 0.254)
		(layers "F.Cu" "B.Cu")
		(net "GND")
	)
	(via
		(at 17.5514 -19.3294)
		(size 0.508)
		(drill 0.254)
		(layers "F.Cu" "B.Cu")
		(net "GND")
	)
	(via
		(at 17.409922 -286.6771)
		(size 0.508)
		(drill 0.254)
		(layers "F.Cu" "B.Cu")
		(net "GND")
	)
	(via
		(at 3.556 -85.325712)
		(size 0.508)
		(drill 0.254)
		(layers "F.Cu" "B.Cu")
		(net "GND")
	)
	(via
		(at 3.9624 -221.1324)
		(size 0.508)
		(drill 0.254)
		(layers "F.Cu" "B.Cu")
		(net "GND")
	)
	(via
		(at 49.395634 -335.758028)
		(size 0.508)
		(drill 0.254)
		(layers "F.Cu" "B.Cu")
		(net "GND")
	)
	(via
		(at 13.462 -259.461)
		(size 0.508)
		(drill 0.254)
		(layers "F.Cu" "B.Cu")
		(net "GND")
	)
	(via
		(at 12.995656 -250.21921)
		(size 0.508)
		(drill 0.254)
		(layers "F.Cu" "B.Cu")
		(net "GND")
	)
	(via
		(at 50.936144 -68.340986)
		(size 0.508)
		(drill 0.254)
		(layers "F.Cu" "B.Cu")
		(net "GND")
	)
	(via
		(at 34.18205 -167.386)
		(size 0.508)
		(drill 0.254)
		(layers "F.Cu" "B.Cu")
		(net "GND")
	)
	(via
		(at 50.936144 -190.260986)
		(size 0.508)
		(drill 0.254)
		(layers "F.Cu" "B.Cu")
		(net "GND")
	)
	(via
		(at 3.978656 -223.34601)
		(size 0.508)
		(drill 0.254)
		(layers "F.Cu" "B.Cu")
		(net "GND")
	)
	(via
		(at 0.76327 -292.27145)
		(size 0.508)
		(drill 0.254)
		(layers "F.Cu" "B.Cu")
		(net "GND")
	)
	(via
		(at 50.936144 -200.420986)
		(size 0.508)
		(drill 0.254)
		(layers "F.Cu" "B.Cu")
		(net "GND")
	)
	(via
		(at 48.915828 -186.182)
		(size 0.508)
		(drill 0.254)
		(layers "F.Cu" "B.Cu")
		(net "GND")
	)
	(via
		(at 0.76327 -312.59145)
		(size 0.508)
		(drill 0.254)
		(layers "F.Cu" "B.Cu")
		(net "GND")
	)
	(via
		(at 18.6182 -85.8774)
		(size 0.508)
		(drill 0.254)
		(layers "F.Cu" "B.Cu")
		(net "GND")
	)
	(via
		(at 48.809656 -44.156122)
		(size 0.508)
		(drill 0.254)
		(layers "F.Cu" "B.Cu")
		(net "GND")
	)
	(via
		(at 5.83819 -258.0132)
		(size 0.508)
		(drill 0.254)
		(layers "F.Cu" "B.Cu")
		(net "GND")
	)
	(via
		(at 15.436342 -112.706912)
		(size 0.508)
		(drill 0.254)
		(layers "F.Cu" "B.Cu")
		(net "GND")
	)
	(via
		(at 15.697708 -6.585458)
		(size 0.508)
		(drill 0.254)
		(layers "F.Cu" "B.Cu")
		(net "GND")
	)
	(via
		(at 17.530572 -199.076056)
		(size 0.508)
		(drill 0.254)
		(layers "F.Cu" "B.Cu")
		(net "GND")
	)
	(via
		(at 50.936144 -180.100986)
		(size 0.508)
		(drill 0.254)
		(layers "F.Cu" "B.Cu")
		(net "GND")
	)
	(via
		(at 39.492428 -253.021846)
		(size 0.508)
		(drill 0.254)
		(layers "F.Cu" "B.Cu")
		(net "GND")
	)
	(via
		(at 3.267456 -222.58401)
		(size 0.508)
		(drill 0.254)
		(layers "F.Cu" "B.Cu")
		(net "GND")
	)
	(via
		(at 0.76327 -78.91145)
		(size 0.508)
		(drill 0.254)
		(layers "F.Cu" "B.Cu")
		(net "GND")
	)
	(via
		(at 0.76327 -28.11145)
		(size 0.508)
		(drill 0.254)
		(layers "F.Cu" "B.Cu")
		(net "GND")
	)
	(via
		(at 1.53035 -189.992)
		(size 0.508)
		(drill 0.254)
		(layers "F.Cu" "B.Cu")
		(net "GND")
	)
	(via
		(at 15.929864 -32.903668)
		(size 0.508)
		(drill 0.254)
		(layers "F.Cu" "B.Cu")
		(net "GND")
	)
	(via
		(at 13.250418 -65.107312)
		(size 0.508)
		(drill 0.254)
		(layers "F.Cu" "B.Cu")
		(net "GND")
	)
	(via
		(at 25.12695 -133.096)
		(size 0.508)
		(drill 0.254)
		(layers "F.Cu" "B.Cu")
		(net "GND")
	)
	(via
		(at 11.49096 -173.228)
		(size 0.508)
		(drill 0.254)
		(layers "F.Cu" "B.Cu")
		(net "GND")
	)
	(via
		(at 2.794 -130.937)
		(size 0.508)
		(drill 0.254)
		(layers "F.Cu" "B.Cu")
		(net "GND")
	)
	(via
		(at 9.999218 -247.0912)
		(size 0.508)
		(drill 0.254)
		(layers "F.Cu" "B.Cu")
		(net "GND")
	)
	(via
		(at 0.76327 -134.79145)
		(size 0.508)
		(drill 0.254)
		(layers "F.Cu" "B.Cu")
		(net "GND")
	)
	(via
		(at 50.936144 -266.460986)
		(size 0.508)
		(drill 0.254)
		(layers "F.Cu" "B.Cu")
		(net "GND")
	)
	(via
		(at 5.38099 -72.701912)
		(size 0.508)
		(drill 0.254)
		(layers "F.Cu" "B.Cu")
		(net "GND")
	)
	(via
		(at 19.689572 -290.2331)
		(size 0.508)
		(drill 0.254)
		(layers "F.Cu" "B.Cu")
		(net "GND")
	)
	(via
		(at 29.464 -134.493)
		(size 0.508)
		(drill 0.254)
		(layers "F.Cu" "B.Cu")
		(net "GND")
	)
	(via
		(at 36.003992 -6.838188)
		(size 0.508)
		(drill 0.254)
		(layers "F.Cu" "B.Cu")
		(net "GND")
	)
	(via
		(at 0.76327 -261.79145)
		(size 0.508)
		(drill 0.254)
		(layers "F.Cu" "B.Cu")
		(net "GND")
	)
	(via
		(at 10.30097 -260.900672)
		(size 0.508)
		(drill 0.254)
		(layers "F.Cu" "B.Cu")
		(net "GND")
	)
	(via
		(at 21.717 -10.16)
		(size 0.508)
		(drill 0.254)
		(layers "F.Cu" "B.Cu")
		(net "GND")
	)
	(via
		(at 45.787056 -227.56241)
		(size 0.508)
		(drill 0.254)
		(layers "F.Cu" "B.Cu")
		(net "GND")
	)
	(via
		(at 49.657 -126.365)
		(size 0.508)
		(drill 0.254)
		(layers "F.Cu" "B.Cu")
		(net "GND")
	)
	(via
		(at 31.982918 -10.1092)
		(size 0.508)
		(drill 0.254)
		(layers "F.Cu" "B.Cu")
		(net "GND")
	)
	(via
		(at 6.604 -269.93088)
		(size 0.508)
		(drill 0.254)
		(layers "F.Cu" "B.Cu")
		(net "GND")
	)
	(via
		(at 0.76327 -185.59145)
		(size 0.508)
		(drill 0.254)
		(layers "F.Cu" "B.Cu")
		(net "GND")
	)
	(via
		(at 30.752288 -273.05)
		(size 0.508)
		(drill 0.254)
		(layers "F.Cu" "B.Cu")
		(net "GND")
	)
	(via
		(at 9.53897 -260.900672)
		(size 0.508)
		(drill 0.254)
		(layers "F.Cu" "B.Cu")
		(net "GND")
	)
	(via
		(at 28.829 -120.904)
		(size 0.508)
		(drill 0.254)
		(layers "F.Cu" "B.Cu")
		(net "GND")
	)
	(via
		(at 12.19327 -257.057652)
		(size 0.508)
		(drill 0.254)
		(layers "F.Cu" "B.Cu")
		(net "GND")
	)
	(via
		(at 14.28623 -255.016)
		(size 0.508)
		(drill 0.254)
		(layers "F.Cu" "B.Cu")
		(net "GND")
	)
	(via
		(at 4.31419 -258.0132)
		(size 0.508)
		(drill 0.254)
		(layers "F.Cu" "B.Cu")
		(net "GND")
	)
	(via
		(at 0.76327 -150.03145)
		(size 0.508)
		(drill 0.254)
		(layers "F.Cu" "B.Cu")
		(net "GND")
	)
	(via
		(at 19.26844 -270.338042)
		(size 0.508)
		(drill 0.254)
		(layers "F.Cu" "B.Cu")
		(net "GND")
	)
	(via
		(at 15.436342 -208.435956)
		(size 0.508)
		(drill 0.254)
		(layers "F.Cu" "B.Cu")
		(net "GND")
	)
	(via
		(at 49.657 -125.73)
		(size 0.508)
		(drill 0.254)
		(layers "F.Cu" "B.Cu")
		(net "GND")
	)
	(via
		(at 32.4612 -94.2086)
		(size 0.508)
		(drill 0.254)
		(layers "F.Cu" "B.Cu")
		(net "GND")
	)
	(via
		(at 23.622 -185.674)
		(size 0.508)
		(drill 0.254)
		(layers "F.Cu" "B.Cu")
		(net "GND")
	)
	(via
		(at 15.802864 -104.820212)
		(size 0.508)
		(drill 0.254)
		(layers "F.Cu" "B.Cu")
		(net "GND")
	)
	(via
		(at 31.220918 -10.7442)
		(size 0.508)
		(drill 0.254)
		(layers "F.Cu" "B.Cu")
		(net "GND")
	)
	(via
		(at 47.438056 -52.258722)
		(size 0.508)
		(drill 0.254)
		(layers "F.Cu" "B.Cu")
		(net "GND")
	)
	(via
		(at 46.801532 -68.460112)
		(size 0.508)
		(drill 0.254)
		(layers "F.Cu" "B.Cu")
		(net "GND")
	)
	(via
		(at 50.936144 -63.260986)
		(size 0.508)
		(drill 0.254)
		(layers "F.Cu" "B.Cu")
		(net "GND")
	)
	(via
		(at 17.399 -136.41705)
		(size 0.508)
		(drill 0.254)
		(layers "F.Cu" "B.Cu")
		(net "GND")
	)
	(via
		(at 46.629828 -55.175912)
		(size 0.508)
		(drill 0.254)
		(layers "F.Cu" "B.Cu")
		(net "GND")
	)
	(via
		(at 34.417 -290.434014)
		(size 0.508)
		(drill 0.254)
		(layers "F.Cu" "B.Cu")
		(net "GND")
	)
	(via
		(at 46.09465 -189.738)
		(size 0.508)
		(drill 0.254)
		(layers "F.Cu" "B.Cu")
		(net "GND")
	)
	(via
		(at 2.9718 -235.903262)
		(size 0.508)
		(drill 0.254)
		(layers "F.Cu" "B.Cu")
		(net "GND")
	)
	(via
		(at 3.32232 -46.315122)
		(size 0.508)
		(drill 0.254)
		(layers "F.Cu" "B.Cu")
		(net "GND")
	)
	(via
		(at 0.76327 -266.87145)
		(size 0.508)
		(drill 0.254)
		(layers "F.Cu" "B.Cu")
		(net "GND")
	)
	(via
		(at 33.0708 -85.6996)
		(size 0.508)
		(drill 0.254)
		(layers "F.Cu" "B.Cu")
		(net "GND")
	)
	(via
		(at 50.936144 -134.380986)
		(size 0.508)
		(drill 0.254)
		(layers "F.Cu" "B.Cu")
		(net "GND")
	)
	(via
		(at 37.846 -63.5)
		(size 0.508)
		(drill 0.254)
		(layers "F.Cu" "B.Cu")
		(net "GND")
	)
	(via
		(at 50.936144 -103.900986)
		(size 0.508)
		(drill 0.254)
		(layers "F.Cu" "B.Cu")
		(net "GND")
	)
	(via
		(at 0.76327 -287.19145)
		(size 0.508)
		(drill 0.254)
		(layers "F.Cu" "B.Cu")
		(net "GND")
	)
	(via
		(at 18.67027 -304.81905)
		(size 0.508)
		(drill 0.254)
		(layers "F.Cu" "B.Cu")
		(net "GND")
	)
	(via
		(at 17.394174 -203.441554)
		(size 0.508)
		(drill 0.254)
		(layers "F.Cu" "B.Cu")
		(net "GND")
	)
	(via
		(at 32.512 -130.175)
		(size 0.508)
		(drill 0.254)
		(layers "F.Cu" "B.Cu")
		(net "GND")
	)
	(via
		(at 50.936144 -205.500986)
		(size 0.508)
		(drill 0.254)
		(layers "F.Cu" "B.Cu")
		(net "GND")
	)
	(via
		(at 46.141132 -252.73)
		(size 0.508)
		(drill 0.254)
		(layers "F.Cu" "B.Cu")
		(net "GND")
	)
	(via
		(at 6.90499 -73.463912)
		(size 0.508)
		(drill 0.254)
		(layers "F.Cu" "B.Cu")
		(net "GND")
	)
	(via
		(at 48.300132 -253.492)
		(size 0.508)
		(drill 0.254)
		(layers "F.Cu" "B.Cu")
		(net "GND")
	)
	(via
		(at 6.14299 -72.701912)
		(size 0.508)
		(drill 0.254)
		(layers "F.Cu" "B.Cu")
		(net "GND")
	)
	(via
		(at 16.63065 -169.291)
		(size 0.508)
		(drill 0.254)
		(layers "F.Cu" "B.Cu")
		(net "GND")
	)
	(via
		(at 33.142428 -73.463912)
		(size 0.508)
		(drill 0.254)
		(layers "F.Cu" "B.Cu")
		(net "GND")
	)
	(via
		(at 33.904428 -73.463912)
		(size 0.508)
		(drill 0.254)
		(layers "F.Cu" "B.Cu")
		(net "GND")
	)
	(via
		(at 0.76327 -17.95145)
		(size 0.508)
		(drill 0.254)
		(layers "F.Cu" "B.Cu")
		(net "GND")
	)
	(via
		(at 34.666428 -73.463912)
		(size 0.508)
		(drill 0.254)
		(layers "F.Cu" "B.Cu")
		(net "GND")
	)
	(via
		(at 50.936144 -230.900986)
		(size 0.508)
		(drill 0.254)
		(layers "F.Cu" "B.Cu")
		(net "GND")
	)
	(via
		(at 32.004 -211.963)
		(size 0.508)
		(drill 0.254)
		(layers "F.Cu" "B.Cu")
		(net "GND")
	)
	(via
		(at 46.903132 -252.73)
		(size 0.508)
		(drill 0.254)
		(layers "F.Cu" "B.Cu")
		(net "GND")
	)
	(segment
		(start 37.517578 -62.25413)
		(end 37.714428 -62.729618)
		(width 0.1778)
		(layer "B.Cu")
		(net "GND")
	)
	(segment
		(start 35.433 -65.237106)
		(end 36.449 -65.237106)
		(width 0.4572)
		(layer "B.Cu")
		(net "GND")
	)
	(segment
		(start 41.29405 -127.762)
		(end 41.29405 -128.905)
		(width 0.4572)
		(layer "B.Cu")
		(net "GND")
	)
	(segment
		(start 10.30605 -173.863)
		(end 10.30605 -172.847)
		(width 0.4572)
		(layer "B.Cu")
		(net "GND")
	)
	(segment
		(start 42.418 -73.571862)
		(end 41.529 -73.571862)
		(width 0.4572)
		(layer "B.Cu")
		(net "GND")
	)
	(segment
		(start 32.380428 -65.227962)
		(end 33.391856 -65.227962)
		(width 0.4572)
		(layer "B.Cu")
		(net "GND")
	)
	(segment
		(start 6.62305 -65.405)
		(end 6.790944 -65.237106)
		(width 0.4572)
		(layer "B.Cu")
		(net "GND")
	)
	(segment
		(start 6.731 -253.365)
		(end 6.731 -252.999494)
		(width 0.3302)
		(layer "B.Cu")
		(net "GND")
	)
	(segment
		(start 39.73068 -73.562718)
		(end 40.757856 -73.562718)
		(width 0.4572)
		(layer "B.Cu")
		(net "GND")
	)
	(segment
		(start 15.367 -258.17195)
		(end 14.351 -258.17195)
		(width 0.4572)
		(layer "B.Cu")
		(net "GND")
	)
	(segment
		(start 6.62305 -250.29795)
		(end 6.62305 -250.063)
		(width 0.4572)
		(layer "B.Cu")
		(net "GND")
	)
	(segment
		(start 18.12798 -135.68807)
		(end 17.399 -136.41705)
		(width 0.4572)
		(layer "B.Cu")
		(net "GND")
	)
	(segment
		(start 10.30605 -171.831)
		(end 10.30605 -172.847)
		(width 0.4572)
		(layer "B.Cu")
		(net "GND")
	)
	(segment
		(start 10.30605 -169.799)
		(end 10.30605 -168.783)
		(width 0.4572)
		(layer "B.Cu")
		(net "GND")
	)
	(segment
		(start 6.62305 -64.389)
		(end 6.62305 -65.405)
		(width 0.4572)
		(layer "B.Cu")
		(net "GND")
	)
	(segment
		(start 2.784856 -65.227962)
		(end 2.794 -65.237106)
		(width 0.4572)
		(layer "B.Cu")
		(net "GND")
	)
	(segment
		(start 37.719 -73.562718)
		(end 38.71468 -73.562718)
		(width 0.4572)
		(layer "B.Cu")
		(net "GND")
	)
	(segment
		(start 12.7 -258.17195)
		(end 13.462 -258.17195)
		(width 0.4572)
		(layer "B.Cu")
		(net "GND")
	)
	(segment
		(start 38.354 -249.174)
		(end 38.1 -249.428)
		(width 0.4572)
		(layer "B.Cu")
		(net "GND")
	)
	(segment
		(start 37.877242 -248.696988)
		(end 37.517578 -247.827292)
		(width 0.1778)
		(layer "B.Cu")
		(net "GND")
	)
	(segment
		(start 11.368786 -166.755826)
		(end 11.49096 -166.878)
		(width 0.4572)
		(layer "B.Cu")
		(net "GND")
	)
	(segment
		(start 10.30605 -169.799)
		(end 11.23696 -169.799)
		(width 0.4572)
		(layer "B.Cu")
		(net "GND")
	)
	(segment
		(start 14.239494 -255.016)
		(end 14.00048 -255.255014)
		(width 0.3302)
		(layer "B.Cu")
		(net "GND")
	)
	(segment
		(start 41.29405 -131.191)
		(end 41.29405 -132.334)
		(width 0.4572)
		(layer "B.Cu")
		(net "GND")
	)
	(segment
		(start 9.779 -249.82805)
		(end 10.795 -249.82805)
		(width 0.4572)
		(layer "B.Cu")
		(net "GND")
	)
	(segment
		(start 37.714428 -62.729618)
		(end 37.714428 -63.368428)
		(width 0.1778)
		(layer "B.Cu")
		(net "GND")
	)
	(segment
		(start 39.47668 -258.162806)
		(end 40.503856 -258.162806)
		(width 0.4572)
		(layer "B.Cu")
		(net "GND")
	)
	(segment
		(start 16.283432 -254.878078)
		(end 16.283432 -255.651)
		(width 0.4572)
		(layer "B.Cu")
		(net "GND")
	)
	(segment
		(start 14.351 -258.17195)
		(end 13.462 -258.17195)
		(width 0.4572)
		(layer "B.Cu")
		(net "GND")
	)
	(segment
		(start 10.30605 -171.831)
		(end 10.30605 -170.815)
		(width 0.4572)
		(layer "B.Cu")
		(net "GND")
	)
	(segment
		(start 41.29405 -132.334)
		(end 41.29405 -133.477)
		(width 0.4572)
		(layer "B.Cu")
		(net "GND")
	)
	(segment
		(start 43.91787 -70.27799)
		(end 43.91787 -71.050912)
		(width 0.4572)
		(layer "B.Cu")
		(net "GND")
	)
	(segment
		(start 7.747 -249.82805)
		(end 8.763 -249.82805)
		(width 0.4572)
		(layer "B.Cu")
		(net "GND")
	)
	(segment
		(start 38.1 -249.428)
		(end 38.1 -250.63704)
		(width 0.4572)
		(layer "B.Cu")
		(net "GND")
	)
	(segment
		(start 17.287494 -73.571862)
		(end 16.129 -73.571862)
		(width 0.4572)
		(layer "B.Cu")
		(net "GND")
	)
	(segment
		(start 47.117 -258.17195)
		(end 46.101 -258.17195)
		(width 0.4572)
		(layer "B.Cu")
		(net "GND")
	)
	(segment
		(start 9.710166 -65.237106)
		(end 8.694166 -65.237106)
		(width 0.4572)
		(layer "B.Cu")
		(net "GND")
	)
	(segment
		(start 10.746486 -65.237106)
		(end 9.710166 -65.237106)
		(width 0.4572)
		(layer "B.Cu")
		(net "GND")
	)
	(segment
		(start 14.28623 -255.016)
		(end 14.239494 -255.016)
		(width 0.3302)
		(layer "B.Cu")
		(net "GND")
	)
	(segment
		(start 13.335 -74.676)
		(end 13.951204 -75.292204)
		(width 0.4572)
		(layer "B.Cu")
		(net "GND")
	)
	(segment
		(start 36.449 -65.237106)
		(end 37.465 -65.237106)
		(width 0.4572)
		(layer "B.Cu")
		(net "GND")
	)
	(segment
		(start 38.227 -63.881)
		(end 38.227 -65.237106)
		(width 0.4572)
		(layer "B.Cu")
		(net "GND")
	)
	(segment
		(start 10.30605 -167.787828)
		(end 10.322052 -167.771826)
		(width 0.4572)
		(layer "B.Cu")
		(net "GND")
	)
	(segment
		(start 41.29405 -133.477)
		(end 41.29405 -134.62)
		(width 0.4572)
		(layer "B.Cu")
		(net "GND")
	)
	(segment
		(start 43.91787 -254.878078)
		(end 43.91787 -255.651)
		(width 0.4572)
		(layer "B.Cu")
		(net "GND")
	)
	(segment
		(start 4.699 -249.82805)
		(end 4.699 -249.891042)
		(width 0.4572)
		(layer "B.Cu")
		(net "GND")
	)
	(segment
		(start 4.560062 -68.844922)
		(end 4.560062 -72.642984)
		(width 0.4572)
		(layer "B.Cu")
		(net "GND")
	)
	(segment
		(start 6.62305 -248.43105)
		(end 6.62305 -249.047)
		(width 0.4572)
		(layer "B.Cu")
		(net "GND")
	)
	(segment
		(start 6.985508 -68.647564)
		(end 6.985508 -68.144898)
		(width 0.3302)
		(layer "B.Cu")
		(net "GND")
	)
	(segment
		(start 13.951204 -75.292204)
		(end 13.951204 -75.349354)
		(width 0.4572)
		(layer "B.Cu")
		(net "GND")
	)
	(segment
		(start 10.322052 -167.771826)
		(end 10.322052 -166.755826)
		(width 0.4572)
		(layer "B.Cu")
		(net "GND")
	)
	(segment
		(start 45.085 -258.17195)
		(end 44.069 -258.17195)
		(width 0.4572)
		(layer "B.Cu")
		(net "GND")
	)
	(segment
		(start 38.989 -250.63704)
		(end 40.11168 -250.63704)
		(width 0.4572)
		(layer "B.Cu")
		(net "GND")
	)
	(segment
		(start 39.116 -65.237106)
		(end 40.23868 -65.237106)
		(width 0.4572)
		(layer "B.Cu")
		(net "GND")
	)
	(segment
		(start 7.747 -249.82805)
		(end 7.51205 -250.063)
		(width 0.4572)
		(layer "B.Cu")
		(net "GND")
	)
	(segment
		(start 10.30605 -172.847)
		(end 11.10996 -172.847)
		(width 0.4572)
		(layer "B.Cu")
		(net "GND")
	)
	(segment
		(start 5.544058 -250.7361)
		(end 6.1849 -250.7361)
		(width 0.381)
		(layer "B.Cu")
		(net "GND")
	)
	(segment
		(start 41.529 -73.571862)
		(end 41.529 -75.419458)
		(width 0.4572)
		(layer "B.Cu")
		(net "GND")
	)
	(segment
		(start 6.100064 -247.056148)
		(end 6.100064 -245.945152)
		(width 0.1778)
		(layer "B.Cu")
		(net "GND")
	)
	(segment
		(start 40.11168 -250.63704)
		(end 41.12768 -250.63704)
		(width 0.4572)
		(layer "B.Cu")
		(net "GND")
	)
	(segment
		(start 38.354 -249.174)
		(end 37.877242 -248.696988)
		(width 0.1778)
		(layer "B.Cu")
		(net "GND")
	)
	(segment
		(start 5.8166 -313.182)
		(end 5.8166 -314.0456)
		(width 0.4572)
		(layer "B.Cu")
		(net "GND")
	)
	(segment
		(start 6.296914 -62.947296)
		(end 6.48843 -63.138812)
		(width 0.1778)
		(layer "B.Cu")
		(net "GND")
	)
	(segment
		(start 11.23696 -169.799)
		(end 11.49096 -170.053)
		(width 0.4572)
		(layer "B.Cu")
		(net "GND")
	)
	(segment
		(start 38.403022 -253.544832)
		(end 37.079428 -253.544832)
		(width 0.3302)
		(layer "B.Cu")
		(net "GND")
	)
	(segment
		(start 6.100064 -61.345064)
		(end 6.100064 -62.236604)
		(width 0.1778)
		(layer "B.Cu")
		(net "GND")
	)
	(segment
		(start 37.211 -250.63704)
		(end 38.1 -250.63704)
		(width 0.4572)
		(layer "B.Cu")
		(net "GND")
	)
	(segment
		(start 45.466 -73.571862)
		(end 44.45 -73.571862)
		(width 0.4572)
		(layer "B.Cu")
		(net "GND")
	)
	(segment
		(start 41.275 -258.17195)
		(end 42.037 -258.17195)
		(width 0.4572)
		(layer "B.Cu")
		(net "GND")
	)
	(segment
		(start 38.46068 -258.162806)
		(end 39.47668 -258.162806)
		(width 0.4572)
		(layer "B.Cu")
		(net "GND")
	)
	(segment
		(start 3.81 -65.237106)
		(end 4.826 -65.237106)
		(width 0.4572)
		(layer "B.Cu")
		(net "GND")
	)
	(segment
		(start 41.25468 -65.237106)
		(end 40.23868 -65.237106)
		(width 0.4572)
		(layer "B.Cu")
		(net "GND")
	)
	(segment
		(start 13.335 -73.56475)
		(end 13.335 -74.676)
		(width 0.4572)
		(layer "B.Cu")
		(net "GND")
	)
	(segment
		(start 6.62305 -63.318136)
		(end 6.48843 -63.183516)
		(width 0.4572)
		(layer "B.Cu")
		(net "GND")
	)
	(segment
		(start 45.971714 -314.1726)
		(end 46.416214 -313.7281)
		(width 0.4572)
		(layer "B.Cu")
		(net "GND")
	)
	(segment
		(start 43.434 -73.571862)
		(end 42.418 -73.571862)
		(width 0.4572)
		(layer "B.Cu")
		(net "GND")
	)
	(segment
		(start 10.30605 -170.815)
		(end 10.30605 -169.799)
		(width 0.4572)
		(layer "B.Cu")
		(net "GND")
	)
	(segment
		(start 4.560062 -72.642984)
		(end 4.61899 -72.701912)
		(width 0.4572)
		(layer "B.Cu")
		(net "GND")
	)
	(segment
		(start 14.182344 -262.054848)
		(end 14.182344 -260.562344)
		(width 0.1778)
		(layer "B.Cu")
		(net "GND")
	)
	(segment
		(start 6.62305 -64.389)
		(end 6.62305 -63.318136)
		(width 0.4572)
		(layer "B.Cu")
		(net "GND")
	)
	(segment
		(start 14.089888 -73.56475)
		(end 13.335 -73.56475)
		(width 0.4572)
		(layer "B.Cu")
		(net "GND")
	)
	(segment
		(start 40.503856 -258.162806)
		(end 40.513 -258.17195)
		(width 0.4572)
		(layer "B.Cu")
		(net "GND")
	)
	(segment
		(start 40.513 -258.17195)
		(end 41.275 -258.17195)
		(width 0.4572)
		(layer "B.Cu")
		(net "GND")
	)
	(segment
		(start 4.699 -249.891042)
		(end 5.544058 -250.7361)
		(width 0.381)
		(layer "B.Cu")
		(net "GND")
	)
	(segment
		(start 40.757856 -73.562718)
		(end 40.767 -73.571862)
		(width 0.4572)
		(layer "B.Cu")
		(net "GND")
	)
	(segment
		(start 7.089648 -68.751704)
		(end 6.985508 -68.647564)
		(width 0.3302)
		(layer "B.Cu")
		(net "GND")
	)
	(segment
		(start 19.573494 -73.571862)
		(end 18.430494 -73.571862)
		(width 0.4572)
		(layer "B.Cu")
		(net "GND")
	)
	(segment
		(start 35.41649 -253.921768)
		(end 35.41649 -253.148846)
		(width 0.4572)
		(layer "B.Cu")
		(net "GND")
	)
	(segment
		(start 37.846 -63.5)
		(end 38.227 -63.881)
		(width 0.4572)
		(layer "B.Cu")
		(net "GND")
	)
	(segment
		(start 42.27068 -65.237106)
		(end 41.25468 -65.237106)
		(width 0.4572)
		(layer "B.Cu")
		(net "GND")
	)
	(segment
		(start 33.147 -250.63704)
		(end 32.131 -250.63704)
		(width 0.4572)
		(layer "B.Cu")
		(net "GND")
	)
	(segment
		(start 14.182344 -260.562344)
		(end 13.462 -259.842)
		(width 0.1778)
		(layer "B.Cu")
		(net "GND")
	)
	(segment
		(start 8.694166 -65.237106)
		(end 7.62 -65.237106)
		(width 0.4572)
		(layer "B.Cu")
		(net "GND")
	)
	(segment
		(start 1.778 -65.227962)
		(end 2.784856 -65.227962)
		(width 0.4572)
		(layer "B.Cu")
		(net "GND")
	)
	(segment
		(start 35.41649 -68.521834)
		(end 35.41649 -67.748912)
		(width 0.4572)
		(layer "B.Cu")
		(net "GND")
	)
	(segment
		(start 19.446494 -258.17195)
		(end 18.430494 -258.17195)
		(width 0.4572)
		(layer "B.Cu")
		(net "GND")
	)
	(segment
		(start 33.401 -65.237106)
		(end 34.417 -65.237106)
		(width 0.4572)
		(layer "B.Cu")
		(net "GND")
	)
	(segment
		(start 14.097 -73.571862)
		(end 14.089888 -73.56475)
		(width 0.4572)
		(layer "B.Cu")
		(net "GND")
	)
	(segment
		(start 6.477 -248.285)
		(end 6.354826 -247.671844)
		(width 0.1778)
		(layer "B.Cu")
		(net "GND")
	)
	(segment
		(start 4.560062 -253.352808)
		(end 4.064254 -252.857)
		(width 0.4572)
		(layer "B.Cu")
		(net "GND")
	)
	(segment
		(start 37.517578 -61.345064)
		(end 37.517578 -62.25413)
		(width 0.1778)
		(layer "B.Cu")
		(net "GND")
	)
	(segment
		(start 39.116 -65.237106)
		(end 38.227 -65.237106)
		(width 0.4572)
		(layer "B.Cu")
		(net "GND")
	)
	(segment
		(start 13.951712 -76.012802)
		(end 14.055344 -76.262484)
		(width 0.1778)
		(layer "B.Cu")
		(net "GND")
	)
	(segment
		(start 46.482 -73.571862)
		(end 47.498 -73.571862)
		(width 0.4572)
		(layer "B.Cu")
		(net "GND")
	)
	(segment
		(start 41.29405 -128.905)
		(end 41.29405 -130.048)
		(width 0.4572)
		(layer "B.Cu")
		(net "GND")
	)
	(segment
		(start 18.430494 -73.571862)
		(end 17.287494 -73.571862)
		(width 0.4572)
		(layer "B.Cu")
		(net "GND")
	)
	(segment
		(start 38.71468 -73.562718)
		(end 39.73068 -73.562718)
		(width 0.4572)
		(layer "B.Cu")
		(net "GND")
	)
	(segment
		(start 9.667494 -258.162806)
		(end 10.699242 -258.162806)
		(width 0.4572)
		(layer "B.Cu")
		(net "GND")
	)
	(segment
		(start 18.05305 -131.953)
		(end 18.05305 -133.096)
		(width 0.4572)
		(layer "B.Cu")
		(net "GND")
	)
	(segment
		(start 15.367 -258.17195)
		(end 16.383 -258.17195)
		(width 0.4572)
		(layer "B.Cu")
		(net "GND")
	)
	(segment
		(start 37.714428 -63.368428)
		(end 37.846 -63.5)
		(width 0.1778)
		(layer "B.Cu")
		(net "GND")
	)
	(segment
		(start 2.794 -65.237106)
		(end 3.81 -65.237106)
		(width 0.4572)
		(layer "B.Cu")
		(net "GND")
	)
	(segment
		(start 18.05305 -126.238)
		(end 18.05305 -127.381)
		(width 0.4572)
		(layer "B.Cu")
		(net "GND")
	)
	(segment
		(start 34.163 -250.63704)
		(end 35.179 -250.63704)
		(width 0.4572)
		(layer "B.Cu")
		(net "GND")
	)
	(segment
		(start 16.156432 -70.27799)
		(end 14.786356 -70.27799)
		(width 0.4572)
		(layer "B.Cu")
		(net "GND")
	)
	(segment
		(start 10.699242 -258.162806)
		(end 11.715242 -258.162806)
		(width 0.4572)
		(layer "B.Cu")
		(net "GND")
	)
	(segment
		(start 3.683 -249.82805)
		(end 2.667 -249.82805)
		(width 0.4572)
		(layer "B.Cu")
		(net "GND")
	)
	(segment
		(start 18.05305 -134.239)
		(end 18.12798 -134.31393)
		(width 0.4572)
		(layer "B.Cu")
		(net "GND")
	)
	(segment
		(start 40.931338 -255.255014)
		(end 42.254932 -255.255014)
		(width 0.3302)
		(layer "B.Cu")
		(net "GND")
	)
	(segment
		(start 33.391856 -65.227962)
		(end 33.401 -65.237106)
		(width 0.4572)
		(layer "B.Cu")
		(net "GND")
	)
	(segment
		(start 11.715242 -258.162806)
		(end 12.690856 -258.162806)
		(width 0.4572)
		(layer "B.Cu")
		(net "GND")
	)
	(segment
		(start 37.474144 -258.162806)
		(end 37.465 -258.17195)
		(width 0.4572)
		(layer "B.Cu")
		(net "GND")
	)
	(segment
		(start 14.00048 -255.255014)
		(end 13.2969 -255.255014)
		(width 0.3302)
		(layer "B.Cu")
		(net "GND")
	)
	(segment
		(start 4.826 -65.531746)
		(end 4.826 -65.237106)
		(width 0.4572)
		(layer "B.Cu")
		(net "GND")
	)
	(segment
		(start 44.069 -258.17195)
		(end 43.053 -258.17195)
		(width 0.4572)
		(layer "B.Cu")
		(net "GND")
	)
	(segment
		(start 41.12768 -250.63704)
		(end 42.164 -250.63704)
		(width 0.4572)
		(layer "B.Cu")
		(net "GND")
	)
	(segment
		(start 18.05305 -127.381)
		(end 18.05305 -128.524)
		(width 0.4572)
		(layer "B.Cu")
		(net "GND")
	)
	(segment
		(start 41.816782 -75.828398)
		(end 41.816782 -77.45476)
		(width 0.1778)
		(layer "B.Cu")
		(net "GND")
	)
	(segment
		(start 8.763 -249.82805)
		(end 9.779 -249.82805)
		(width 0.4572)
		(layer "B.Cu")
		(net "GND")
	)
	(segment
		(start 40.767 -73.571862)
		(end 41.529 -73.571862)
		(width 0.4572)
		(layer "B.Cu")
		(net "GND")
	)
	(segment
		(start 41.862502 -70.654926)
		(end 42.290746 -70.226682)
		(width 0.3302)
		(layer "B.Cu")
		(net "GND")
	)
	(segment
		(start 10.445242 -73.562718)
		(end 11.461242 -73.562718)
		(width 0.4572)
		(layer "B.Cu")
		(net "GND")
	)
	(segment
		(start 41.29405 -136.0551)
		(end 42.926 -137.68705)
		(width 0.4572)
		(layer "B.Cu")
		(net "GND")
	)
	(segment
		(start 14.786356 -70.27799)
		(end 14.40942 -70.654926)
		(width 0.4572)
		(layer "B.Cu")
		(net "GND")
	)
	(segment
		(start 41.816782 -260.935978)
		(end 41.426638 -259.993638)
		(width 0.1778)
		(layer "B.Cu")
		(net "GND")
	)
	(segment
		(start 9.413494 -73.562718)
		(end 10.445242 -73.562718)
		(width 0.4572)
		(layer "B.Cu")
		(net "GND")
	)
	(segment
		(start 38.46068 -258.162806)
		(end 37.474144 -258.162806)
		(width 0.4572)
		(layer "B.Cu")
		(net "GND")
	)
	(segment
		(start 46.101 -258.17195)
		(end 45.085 -258.17195)
		(width 0.4572)
		(layer "B.Cu")
		(net "GND")
	)
	(segment
		(start 34.163 -250.63704)
		(end 33.147 -250.63704)
		(width 0.4572)
		(layer "B.Cu")
		(net "GND")
	)
	(segment
		(start 36.195 -250.63704)
		(end 37.211 -250.63704)
		(width 0.4572)
		(layer "B.Cu")
		(net "GND")
	)
	(segment
		(start 35.179 -250.63704)
		(end 36.195 -250.63704)
		(width 0.4572)
		(layer "B.Cu")
		(net "GND")
	)
	(segment
		(start 5.8166 -314.0456)
		(end 5.969 -314.198)
		(width 0.4572)
		(layer "B.Cu")
		(net "GND")
	)
	(segment
		(start 6.731 -252.999494)
		(end 6.985508 -252.744986)
		(width 0.3302)
		(layer "B.Cu")
		(net "GND")
	)
	(segment
		(start 6.1849 -250.7361)
		(end 6.62305 -250.29795)
		(width 0.381)
		(layer "B.Cu")
		(net "GND")
	)
	(segment
		(start 43.053 -258.17195)
		(end 42.037 -258.17195)
		(width 0.4572)
		(layer "B.Cu")
		(net "GND")
	)
	(segment
		(start 12.690856 -258.162806)
		(end 12.7 -258.17195)
		(width 0.4572)
		(layer "B.Cu")
		(net "GND")
	)
	(segment
		(start 6.62305 -65.405)
		(end 6.62305 -65.632838)
		(width 0.4572)
		(layer "B.Cu")
		(net "GND")
	)
	(segment
		(start 6.790944 -65.237106)
		(end 7.62 -65.237106)
		(width 0.4572)
		(layer "B.Cu")
		(net "GND")
	)
	(segment
		(start 41.426638 -259.993638)
		(end 41.275 -259.842)
		(width 0.1778)
		(layer "B.Cu")
		(net "GND")
	)
	(segment
		(start 38.1 -250.63704)
		(end 38.989 -250.63704)
		(width 0.4572)
		(layer "B.Cu")
		(net "GND")
	)
	(segment
		(start 6.62305 -65.632838)
		(end 6.177788 -66.0781)
		(width 0.4572)
		(layer "B.Cu")
		(net "GND")
	)
	(segment
		(start 16.383 -258.17195)
		(end 17.414494 -258.17195)
		(width 0.4572)
		(layer "B.Cu")
		(net "GND")
	)
	(segment
		(start 37.517578 -247.827292)
		(end 37.517578 -246.744998)
		(width 0.1778)
		(layer "B.Cu")
		(net "GND")
	)
	(segment
		(start 41.29405 -134.62)
		(end 41.29405 -136.0551)
		(width 0.4572)
		(layer "B.Cu")
		(net "GND")
	)
	(segment
		(start 44.45 -73.571862)
		(end 43.434 -73.571862)
		(width 0.4572)
		(layer "B.Cu")
		(net "GND")
	)
	(segment
		(start 41.275 -259.842)
		(end 41.275 -258.17195)
		(width 0.4572)
		(layer "B.Cu")
		(net "GND")
	)
	(segment
		(start 18.05305 -129.667)
		(end 18.05305 -130.81)
		(width 0.4572)
		(layer "B.Cu")
		(net "GND")
	)
	(segment
		(start 6.48843 -63.183516)
		(end 6.48843 -63.138812)
		(width 0.4572)
		(layer "B.Cu")
		(net "GND")
	)
	(segment
		(start 6.477 -248.285)
		(end 6.62305 -248.43105)
		(width 0.4572)
		(layer "B.Cu")
		(net "GND")
	)
	(segment
		(start 13.462 -259.842)
		(end 13.462 -259.461)
		(width 0.1778)
		(layer "B.Cu")
		(net "GND")
	)
	(segment
		(start 41.529 -75.419458)
		(end 41.731184 -75.621642)
		(width 0.4572)
		(layer "B.Cu")
		(net "GND")
	)
	(segment
		(start 6.18998 -62.689232)
		(end 6.296914 -62.947296)
		(width 0.1778)
		(layer "B.Cu")
		(net "GND")
	)
	(segment
		(start 11.10996 -172.847)
		(end 11.49096 -173.228)
		(width 0.4572)
		(layer "B.Cu")
		(net "GND")
	)
	(segment
		(start 18.05305 -130.81)
		(end 18.05305 -131.953)
		(width 0.4572)
		(layer "B.Cu")
		(net "GND")
	)
	(segment
		(start 5.372354 -66.0781)
		(end 4.826 -65.531746)
		(width 0.4572)
		(layer "B.Cu")
		(net "GND")
	)
	(segment
		(start 6.177788 -66.0781)
		(end 5.372354 -66.0781)
		(width 0.4572)
		(layer "B.Cu")
		(net "GND")
	)
	(segment
		(start 18.12798 -134.31393)
		(end 18.12798 -135.68807)
		(width 0.4572)
		(layer "B.Cu")
		(net "GND")
	)
	(segment
		(start 13.951204 -75.349354)
		(end 13.951712 -76.012802)
		(width 0.1778)
		(layer "B.Cu")
		(net "GND")
	)
	(segment
		(start 38.403022 -68.144898)
		(end 37.079428 -68.144898)
		(width 0.3302)
		(layer "B.Cu")
		(net "GND")
	)
	(segment
		(start 14.055344 -76.262484)
		(end 14.055344 -77.45476)
		(width 0.1778)
		(layer "B.Cu")
		(net "GND")
	)
	(segment
		(start 18.430494 -258.17195)
		(end 17.414494 -258.17195)
		(width 0.4572)
		(layer "B.Cu")
		(net "GND")
	)
	(segment
		(start 45.466 -73.571862)
		(end 46.482 -73.571862)
		(width 0.4572)
		(layer "B.Cu")
		(net "GND")
	)
	(segment
		(start 13.1699 -70.654926)
		(end 14.40942 -70.654926)
		(width 0.3302)
		(layer "B.Cu")
		(net "GND")
	)
	(segment
		(start 41.29405 -126.619)
		(end 41.29405 -127.762)
		(width 0.4572)
		(layer "B.Cu")
		(net "GND")
	)
	(segment
		(start 6.354826 -247.671844)
		(end 6.100064 -247.056148)
		(width 0.1778)
		(layer "B.Cu")
		(net "GND")
	)
	(segment
		(start 11.461242 -73.562718)
		(end 12.443968 -73.562718)
		(width 0.4572)
		(layer "B.Cu")
		(net "GND")
	)
	(segment
		(start 2.667 -249.82805)
		(end 1.651 -249.82805)
		(width 0.4572)
		(layer "B.Cu")
		(net "GND")
	)
	(segment
		(start 41.731184 -75.621642)
		(end 41.816782 -75.828398)
		(width 0.1778)
		(layer "B.Cu")
		(net "GND")
	)
	(segment
		(start 41.816782 -262.054848)
		(end 41.816782 -260.935978)
		(width 0.1778)
		(layer "B.Cu")
		(net "GND")
	)
	(segment
		(start 4.064254 -252.857)
		(end 3.87985 -252.857)
		(width 0.4572)
		(layer "B.Cu")
		(net "GND")
	)
	(segment
		(start 40.931338 -70.654926)
		(end 41.862502 -70.654926)
		(width 0.3302)
		(layer "B.Cu")
		(net "GND")
	)
	(segment
		(start 18.05305 -133.096)
		(end 18.05305 -134.239)
		(width 0.4572)
		(layer "B.Cu")
		(net "GND")
	)
	(segment
		(start 41.29405 -130.048)
		(end 41.29405 -131.191)
		(width 0.4572)
		(layer "B.Cu")
		(net "GND")
	)
	(segment
		(start 13.462 -259.461)
		(end 13.462 -258.17195)
		(width 0.4572)
		(layer "B.Cu")
		(net "GND")
	)
	(segment
		(start 37.465 -65.237106)
		(end 38.227 -65.237106)
		(width 0.4572)
		(layer "B.Cu")
		(net "GND")
	)
	(segment
		(start 7.51205 -250.063)
		(end 6.62305 -250.063)
		(width 0.4572)
		(layer "B.Cu")
		(net "GND")
	)
	(segment
		(start 12.443968 -73.562718)
		(end 12.446 -73.56475)
		(width 0.4572)
		(layer "B.Cu")
		(net "GND")
	)
	(segment
		(start 6.100064 -62.236604)
		(end 6.18998 -62.689232)
		(width 0.1778)
		(layer "B.Cu")
		(net "GND")
	)
	(segment
		(start 12.446 -73.56475)
		(end 13.335 -73.56475)
		(width 0.4572)
		(layer "B.Cu")
		(net "GND")
	)
	(segment
		(start 16.129 -73.571862)
		(end 15.113 -73.571862)
		(width 0.4572)
		(layer "B.Cu")
		(net "GND")
	)
	(segment
		(start 10.30605 -168.783)
		(end 10.30605 -167.787828)
		(width 0.4572)
		(layer "B.Cu")
		(net "GND")
	)
	(segment
		(start 18.05305 -128.524)
		(end 18.05305 -129.667)
		(width 0.4572)
		(layer "B.Cu")
		(net "GND")
	)
	(segment
		(start 4.560062 -253.629922)
		(end 4.560062 -253.352808)
		(width 0.4572)
		(layer "B.Cu")
		(net "GND")
	)
	(segment
		(start 6.62305 -250.063)
		(end 6.62305 -249.047)
		(width 0.4572)
		(layer "B.Cu")
		(net "GND")
	)
	(segment
		(start 44.704 -314.1726)
		(end 45.971714 -314.1726)
		(width 0.4572)
		(layer "B.Cu")
		(net "GND")
	)
	(segment
		(start 15.113 -73.571862)
		(end 14.097 -73.571862)
		(width 0.4572)
		(layer "B.Cu")
		(net "GND")
	)
	(segment
		(start 3.683 -249.82805)
		(end 4.699 -249.82805)
		(width 0.4572)
		(layer "B.Cu")
		(net "GND")
	)
	(segment
		(start 10.322052 -166.755826)
		(end 11.368786 -166.755826)
		(width 0.4572)
		(layer "B.Cu")
		(net "GND")
	)
	(segment
		(start 34.417 -65.237106)
		(end 35.433 -65.237106)
		(width 0.4572)
		(layer "B.Cu")
		(net "GND")
	)
	(segment
		(start 42.799 -259.842)
		(end 43.053 -259.588)
		(width 0.2794)
		(layer "B.Cu")
		(net "FAN_0_TIMER")
	)
	(segment
		(start 42.616628 -261.406894)
		(end 42.799 -260.966458)
		(width 0.1016)
		(layer "B.Cu")
		(net "FAN_0_TIMER")
	)
	(segment
		(start 42.616628 -262.054848)
		(end 42.616628 -261.406894)
		(width 0.1016)
		(layer "B.Cu")
		(net "FAN_0_TIMER")
	)
	(segment
		(start 42.799 -260.966458)
		(end 42.799 -259.842)
		(width 0.1016)
		(layer "B.Cu")
		(net "FAN_0_TIMER")
	)
	(segment
		(start 43.053 -259.588)
		(end 43.45305 -259.588)
		(width 0.2794)
		(layer "B.Cu")
		(net "FAN_0_TIMER")
	)
	(segment
		(start 43.45305 -259.588)
		(end 44.069 -258.97205)
		(width 0.2794)
		(layer "B.Cu")
		(net "FAN_0_TIMER")
	)
	(via
		(at 41.111932 -79.086202)
		(size 0.508)
		(drill 0.254)
		(layers "F.Cu" "B.Cu")
		(net "P52V_HSC")
	)
	(via
		(at 8.095234 -243.67871)
		(size 0.508)
		(drill 0.254)
		(layers "F.Cu" "B.Cu")
		(net "P52V_HSC")
	)
	(via
		(at 32.380428 -80.067912)
		(size 0.508)
		(drill 0.254)
		(layers "F.Cu" "B.Cu")
		(net "P52V_HSC")
	)
	(via
		(at 46.318932 -57.741312)
		(size 0.508)
		(drill 0.254)
		(layers "F.Cu" "B.Cu")
		(net "P52V_HSC")
	)
	(via
		(at 12.705334 -79.721202)
		(size 0.508)
		(drill 0.254)
		(layers "F.Cu" "B.Cu")
		(net "P52V_HSC")
	)
	(via
		(at 6.90499 -79.305912)
		(size 0.762)
		(drill 0.254)
		(layers "F.Cu" "B.Cu")
		(net "P52V_HSC")
	)
	(via
		(at 47.080932 -58.503312)
		(size 0.762)
		(drill 0.254)
		(layers "F.Cu" "B.Cu")
		(net "P52V_HSC")
	)
	(via
		(at 9.44499 -80.321912)
		(size 0.508)
		(drill 0.254)
		(layers "F.Cu" "B.Cu")
		(net "P52V_HSC")
	)
	(via
		(at 13.350494 -79.721202)
		(size 0.508)
		(drill 0.254)
		(layers "F.Cu" "B.Cu")
		(net "P52V_HSC")
	)
	(via
		(at 6.26999 -264.6172)
		(size 0.508)
		(drill 0.254)
		(layers "F.Cu" "B.Cu")
		(net "P52V_HSC")
	)
	(via
		(at 6.804914 -243.67871)
		(size 0.508)
		(drill 0.254)
		(layers "F.Cu" "B.Cu")
		(net "P52V_HSC")
	)
	(via
		(at 39.821612 -263.68629)
		(size 0.508)
		(drill 0.254)
		(layers "F.Cu" "B.Cu")
		(net "P52V_HSC")
	)
	(via
		(at 33.142428 -80.067912)
		(size 0.508)
		(drill 0.254)
		(layers "F.Cu" "B.Cu")
		(net "P52V_HSC")
	)
	(via
		(at 38.867588 -59.078622)
		(size 0.508)
		(drill 0.254)
		(layers "F.Cu" "B.Cu")
		(net "P52V_HSC")
	)
	(via
		(at 12.060174 -79.721202)
		(size 0.508)
		(drill 0.254)
		(layers "F.Cu" "B.Cu")
		(net "P52V_HSC")
	)
	(via
		(at 12.352274 -245.010178)
		(size 0.508)
		(drill 0.254)
		(layers "F.Cu" "B.Cu")
		(net "P52V_HSC")
	)
	(via
		(at 28.326588 -10.7442)
		(size 0.508)
		(drill 0.254)
		(layers "F.Cu" "B.Cu")
		(net "P52V_HSC")
	)
	(via
		(at 37.206428 -80.321912)
		(size 0.508)
		(drill 0.254)
		(layers "F.Cu" "B.Cu")
		(net "P52V_HSC")
	)
	(via
		(at 41.873932 -244.2972)
		(size 0.508)
		(drill 0.254)
		(layers "F.Cu" "B.Cu")
		(net "P52V_HSC")
	)
	(via
		(at 28.326588 -12.0142)
		(size 0.508)
		(drill 0.254)
		(layers "F.Cu" "B.Cu")
		(net "P52V_HSC")
	)
	(via
		(at 6.804914 -59.078622)
		(size 0.508)
		(drill 0.254)
		(layers "F.Cu" "B.Cu")
		(net "P52V_HSC")
	)
	(via
		(at 45.556932 -57.741312)
		(size 0.508)
		(drill 0.254)
		(layers "F.Cu" "B.Cu")
		(net "P52V_HSC")
	)
	(via
		(at 6.804914 -59.713622)
		(size 0.508)
		(drill 0.254)
		(layers "F.Cu" "B.Cu")
		(net "P52V_HSC")
	)
	(via
		(at 12.377674 -247.600978)
		(size 0.508)
		(drill 0.254)
		(layers "F.Cu" "B.Cu")
		(net "P52V_HSC")
	)
	(via
		(at 47.411132 -242.8494)
		(size 0.508)
		(drill 0.254)
		(layers "F.Cu" "B.Cu")
		(net "P52V_HSC")
	)
	(via
		(at 6.14299 -80.067912)
		(size 0.508)
		(drill 0.254)
		(layers "F.Cu" "B.Cu")
		(net "P52V_HSC")
	)
	(via
		(at 37.968428 -264.922)
		(size 0.508)
		(drill 0.254)
		(layers "F.Cu" "B.Cu")
		(net "P52V_HSC")
	)
	(via
		(at 12.377674 -243.079778)
		(size 0.508)
		(drill 0.254)
		(layers "F.Cu" "B.Cu")
		(net "P52V_HSC")
	)
	(via
		(at 29.088588 -10.1092)
		(size 0.508)
		(drill 0.254)
		(layers "F.Cu" "B.Cu")
		(net "P52V_HSC")
	)
	(via
		(at 8.095234 -59.713622)
		(size 0.508)
		(drill 0.254)
		(layers "F.Cu" "B.Cu")
		(net "P52V_HSC")
	)
	(via
		(at 5.38099 -79.305912)
		(size 0.508)
		(drill 0.254)
		(layers "F.Cu" "B.Cu")
		(net "P52V_HSC")
	)
	(via
		(at 46.395132 -61.856112)
		(size 0.508)
		(drill 0.254)
		(layers "F.Cu" "B.Cu")
		(net "P52V_HSC")
	)
	(via
		(at 10.710418 -243.4336)
		(size 0.508)
		(drill 0.254)
		(layers "F.Cu" "B.Cu")
		(net "P52V_HSC")
	)
	(via
		(at 33.904428 -80.067912)
		(size 0.508)
		(drill 0.254)
		(layers "F.Cu" "B.Cu")
		(net "P52V_HSC")
	)
	(via
		(at 29.088588 -13.2842)
		(size 0.508)
		(drill 0.254)
		(layers "F.Cu" "B.Cu")
		(net "P52V_HSC")
	)
	(via
		(at 12.187174 -263.68629)
		(size 0.508)
		(drill 0.254)
		(layers "F.Cu" "B.Cu")
		(net "P52V_HSC")
	)
	(via
		(at 39.009828 -245.113556)
		(size 0.508)
		(drill 0.254)
		(layers "F.Cu" "B.Cu")
		(net "P52V_HSC")
	)
	(via
		(at 28.326588 -11.3792)
		(size 0.508)
		(drill 0.254)
		(layers "F.Cu" "B.Cu")
		(net "P52V_HSC")
	)
	(via
		(at 37.968428 -80.321912)
		(size 0.508)
		(drill 0.254)
		(layers "F.Cu" "B.Cu")
		(net "P52V_HSC")
	)
	(via
		(at 4.61899 -79.305912)
		(size 0.762)
		(drill 0.254)
		(layers "F.Cu" "B.Cu")
		(net "P52V_HSC")
	)
	(via
		(at 33.879028 -263.906)
		(size 0.508)
		(drill 0.254)
		(layers "F.Cu" "B.Cu")
		(net "P52V_HSC")
	)
	(via
		(at 32.304228 -264.668)
		(size 0.508)
		(drill 0.254)
		(layers "F.Cu" "B.Cu")
		(net "P52V_HSC")
	)
	(via
		(at 5.38099 -80.067912)
		(size 0.508)
		(drill 0.254)
		(layers "F.Cu" "B.Cu")
		(net "P52V_HSC")
	)
	(via
		(at 12.842494 -263.68629)
		(size 0.508)
		(drill 0.254)
		(layers "F.Cu" "B.Cu")
		(net "P52V_HSC")
	)
	(via
		(at 6.26999 -263.8552)
		(size 0.508)
		(drill 0.254)
		(layers "F.Cu" "B.Cu")
		(net "P52V_HSC")
	)
	(via
		(at 13.477494 -264.32129)
		(size 0.508)
		(drill 0.254)
		(layers "F.Cu" "B.Cu")
		(net "P52V_HSC")
	)
	(via
		(at 3.426968 -266.511024)
		(size 0.508)
		(drill 0.254)
		(layers "F.Cu" "B.Cu")
		(net "P52V_HSC")
	)
	(via
		(at 13.350494 -79.086202)
		(size 0.508)
		(drill 0.254)
		(layers "F.Cu" "B.Cu")
		(net "P52V_HSC")
	)
	(via
		(at 38.374828 -244.478556)
		(size 0.508)
		(drill 0.254)
		(layers "F.Cu" "B.Cu")
		(net "P52V_HSC")
	)
	(via
		(at 10.20699 -80.321912)
		(size 0.508)
		(drill 0.254)
		(layers "F.Cu" "B.Cu")
		(net "P52V_HSC")
	)
	(via
		(at 6.804914 -244.31371)
		(size 0.508)
		(drill 0.254)
		(layers "F.Cu" "B.Cu")
		(net "P52V_HSC")
	)
	(via
		(at 38.374828 -245.113556)
		(size 0.508)
		(drill 0.254)
		(layers "F.Cu" "B.Cu")
		(net "P52V_HSC")
	)
	(via
		(at 10.710418 -58.477912)
		(size 0.508)
		(drill 0.254)
		(layers "F.Cu" "B.Cu")
		(net "P52V_HSC")
	)
	(via
		(at 28.326588 -13.2842)
		(size 0.508)
		(drill 0.254)
		(layers "F.Cu" "B.Cu")
		(net "P52V_HSC")
	)
	(via
		(at 46.318932 -58.503312)
		(size 0.508)
		(drill 0.254)
		(layers "F.Cu" "B.Cu")
		(net "P52V_HSC")
	)
	(via
		(at 12.352274 -245.670578)
		(size 0.508)
		(drill 0.254)
		(layers "F.Cu" "B.Cu")
		(net "P52V_HSC")
	)
	(via
		(at 12.060174 -79.086202)
		(size 0.508)
		(drill 0.254)
		(layers "F.Cu" "B.Cu")
		(net "P52V_HSC")
	)
	(via
		(at 47.157132 -61.856112)
		(size 0.508)
		(drill 0.254)
		(layers "F.Cu" "B.Cu")
		(net "P52V_HSC")
	)
	(via
		(at 14.469618 -62.541912)
		(size 0.508)
		(drill 0.254)
		(layers "F.Cu" "B.Cu")
		(net "P52V_HSC")
	)
	(via
		(at 39.821612 -79.086202)
		(size 0.508)
		(drill 0.254)
		(layers "F.Cu" "B.Cu")
		(net "P52V_HSC")
	)
	(via
		(at 7.439914 -244.31371)
		(size 0.508)
		(drill 0.254)
		(layers "F.Cu" "B.Cu")
		(net "P52V_HSC")
	)
	(via
		(at 47.411132 -242.0366)
		(size 0.508)
		(drill 0.254)
		(layers "F.Cu" "B.Cu")
		(net "P52V_HSC")
	)
	(via
		(at 45.887132 -246.126)
		(size 0.508)
		(drill 0.254)
		(layers "F.Cu" "B.Cu")
		(net "P52V_HSC")
	)
	(via
		(at 12.352274 -244.375178)
		(size 0.508)
		(drill 0.254)
		(layers "F.Cu" "B.Cu")
		(net "P52V_HSC")
	)
	(via
		(at 6.14299 -79.305912)
		(size 0.508)
		(drill 0.254)
		(layers "F.Cu" "B.Cu")
		(net "P52V_HSC")
	)
	(via
		(at 46.674532 -246.1514)
		(size 0.508)
		(drill 0.254)
		(layers "F.Cu" "B.Cu")
		(net "P52V_HSC")
	)
	(via
		(at 39.019988 -244.478556)
		(size 0.508)
		(drill 0.254)
		(layers "F.Cu" "B.Cu")
		(net "P52V_HSC")
	)
	(via
		(at 39.665148 -245.113556)
		(size 0.508)
		(drill 0.254)
		(layers "F.Cu" "B.Cu")
		(net "P52V_HSC")
	)
	(via
		(at 7.450074 -243.67871)
		(size 0.508)
		(drill 0.254)
		(layers "F.Cu" "B.Cu")
		(net "P52V_HSC")
	)
	(via
		(at 13.707618 -62.541912)
		(size 0.508)
		(drill 0.254)
		(layers "F.Cu" "B.Cu")
		(net "P52V_HSC")
	)
	(via
		(at 38.222428 -59.713622)
		(size 0.508)
		(drill 0.254)
		(layers "F.Cu" "B.Cu")
		(net "P52V_HSC")
	)
	(via
		(at 29.088588 -12.6492)
		(size 0.508)
		(drill 0.254)
		(layers "F.Cu" "B.Cu")
		(net "P52V_HSC")
	)
	(via
		(at 12.945618 -62.541912)
		(size 0.508)
		(drill 0.254)
		(layers "F.Cu" "B.Cu")
		(net "P52V_HSC")
	)
	(via
		(at 13.069824 -58.474356)
		(size 0.508)
		(drill 0.254)
		(layers "F.Cu" "B.Cu")
		(net "P52V_HSC")
	)
	(via
		(at 39.512748 -59.713622)
		(size 0.508)
		(drill 0.254)
		(layers "F.Cu" "B.Cu")
		(net "P52V_HSC")
	)
	(via
		(at 33.117028 -263.906)
		(size 0.508)
		(drill 0.254)
		(layers "F.Cu" "B.Cu")
		(net "P52V_HSC")
	)
	(via
		(at 42.052748 -58.570622)
		(size 0.508)
		(drill 0.254)
		(layers "F.Cu" "B.Cu")
		(net "P52V_HSC")
	)
	(via
		(at 39.665148 -244.478556)
		(size 0.508)
		(drill 0.254)
		(layers "F.Cu" "B.Cu")
		(net "P52V_HSC")
	)
	(via
		(at 33.879028 -264.668)
		(size 0.508)
		(drill 0.254)
		(layers "F.Cu" "B.Cu")
		(net "P52V_HSC")
	)
	(via
		(at 3.426968 -265.855704)
		(size 0.508)
		(drill 0.254)
		(layers "F.Cu" "B.Cu")
		(net "P52V_HSC")
	)
	(via
		(at 13.075158 -59.298078)
		(size 0.508)
		(drill 0.254)
		(layers "F.Cu" "B.Cu")
		(net "P52V_HSC")
	)
	(via
		(at 4.61899 -264.6426)
		(size 0.508)
		(drill 0.254)
		(layers "F.Cu" "B.Cu")
		(net "P52V_HSC")
	)
	(via
		(at 12.313158 -59.298078)
		(size 0.508)
		(drill 0.254)
		(layers "F.Cu" "B.Cu")
		(net "P52V_HSC")
	)
	(via
		(at 45.633132 -61.856112)
		(size 0.508)
		(drill 0.254)
		(layers "F.Cu" "B.Cu")
		(net "P52V_HSC")
	)
	(via
		(at 5.43179 -264.6426)
		(size 0.508)
		(drill 0.254)
		(layers "F.Cu" "B.Cu")
		(net "P52V_HSC")
	)
	(via
		(at 32.304228 -263.906)
		(size 0.762)
		(drill 0.254)
		(layers "F.Cu" "B.Cu")
		(net "P52V_HSC")
	)
	(via
		(at 33.117028 -267.97)
		(size 0.508)
		(drill 0.254)
		(layers "F.Cu" "B.Cu")
		(net "P52V_HSC")
	)
	(via
		(at 45.887132 -242.8494)
		(size 0.508)
		(drill 0.254)
		(layers "F.Cu" "B.Cu")
		(net "P52V_HSC")
	)
	(via
		(at 46.674532 -242.8748)
		(size 0.508)
		(drill 0.254)
		(layers "F.Cu" "B.Cu")
		(net "P52V_HSC")
	)
	(via
		(at 47.411132 -246.126)
		(size 0.508)
		(drill 0.254)
		(layers "F.Cu" "B.Cu")
		(net "P52V_HSC")
	)
	(via
		(at 40.466772 -79.721202)
		(size 0.508)
		(drill 0.254)
		(layers "F.Cu" "B.Cu")
		(net "P52V_HSC")
	)
	(via
		(at 29.088588 -11.3792)
		(size 0.508)
		(drill 0.254)
		(layers "F.Cu" "B.Cu")
		(net "P52V_HSC")
	)
	(via
		(at 38.222428 -59.078622)
		(size 0.508)
		(drill 0.254)
		(layers "F.Cu" "B.Cu")
		(net "P52V_HSC")
	)
	(via
		(at 12.832334 -264.32129)
		(size 0.508)
		(drill 0.254)
		(layers "F.Cu" "B.Cu")
		(net "P52V_HSC")
	)
	(via
		(at 9.948418 -243.4336)
		(size 0.508)
		(drill 0.254)
		(layers "F.Cu" "B.Cu")
		(net "P52V_HSC")
	)
	(via
		(at 9.54659 -264.4902)
		(size 0.508)
		(drill 0.254)
		(layers "F.Cu" "B.Cu")
		(net "P52V_HSC")
	)
	(via
		(at 5.43179 -263.8806)
		(size 0.508)
		(drill 0.254)
		(layers "F.Cu" "B.Cu")
		(net "P52V_HSC")
	)
	(via
		(at 39.512748 -59.078622)
		(size 0.508)
		(drill 0.254)
		(layers "F.Cu" "B.Cu")
		(net "P52V_HSC")
	)
	(via
		(at 12.187174 -264.32129)
		(size 0.508)
		(drill 0.254)
		(layers "F.Cu" "B.Cu")
		(net "P52V_HSC")
	)
	(via
		(at 12.377674 -246.965978)
		(size 0.508)
		(drill 0.254)
		(layers "F.Cu" "B.Cu")
		(net "P52V_HSC")
	)
	(via
		(at 39.821612 -264.32129)
		(size 0.508)
		(drill 0.254)
		(layers "F.Cu" "B.Cu")
		(net "P52V_HSC")
	)
	(via
		(at 39.821612 -79.721202)
		(size 0.508)
		(drill 0.254)
		(layers "F.Cu" "B.Cu")
		(net "P52V_HSC")
	)
	(via
		(at 40.466772 -264.32129)
		(size 0.508)
		(drill 0.254)
		(layers "F.Cu" "B.Cu")
		(net "P52V_HSC")
	)
	(via
		(at 46.674532 -242.062)
		(size 0.508)
		(drill 0.254)
		(layers "F.Cu" "B.Cu")
		(net "P52V_HSC")
	)
	(via
		(at 47.080932 -57.741312)
		(size 0.508)
		(drill 0.254)
		(layers "F.Cu" "B.Cu")
		(net "P52V_HSC")
	)
	(via
		(at 7.450074 -59.078622)
		(size 0.508)
		(drill 0.254)
		(layers "F.Cu" "B.Cu")
		(net "P52V_HSC")
	)
	(via
		(at 12.352274 -246.305578)
		(size 0.508)
		(drill 0.254)
		(layers "F.Cu" "B.Cu")
		(net "P52V_HSC")
	)
	(via
		(at 33.142428 -79.305912)
		(size 0.508)
		(drill 0.254)
		(layers "F.Cu" "B.Cu")
		(net "P52V_HSC")
	)
	(via
		(at 28.326588 -12.6492)
		(size 0.508)
		(drill 0.254)
		(layers "F.Cu" "B.Cu")
		(net "P52V_HSC")
	)
	(via
		(at 32.380428 -79.305912)
		(size 0.762)
		(drill 0.254)
		(layers "F.Cu" "B.Cu")
		(net "P52V_HSC")
	)
	(via
		(at 33.117028 -264.668)
		(size 0.508)
		(drill 0.254)
		(layers "F.Cu" "B.Cu")
		(net "P52V_HSC")
	)
	(via
		(at 28.326588 -10.1092)
		(size 0.508)
		(drill 0.254)
		(layers "F.Cu" "B.Cu")
		(net "P52V_HSC")
	)
	(via
		(at 33.904428 -79.305912)
		(size 0.508)
		(drill 0.254)
		(layers "F.Cu" "B.Cu")
		(net "P52V_HSC")
	)
	(via
		(at 6.90499 -80.067912)
		(size 0.508)
		(drill 0.254)
		(layers "F.Cu" "B.Cu")
		(net "P52V_HSC")
	)
	(via
		(at 37.206428 -264.922)
		(size 0.508)
		(drill 0.254)
		(layers "F.Cu" "B.Cu")
		(net "P52V_HSC")
	)
	(via
		(at 45.556932 -58.503312)
		(size 0.508)
		(drill 0.254)
		(layers "F.Cu" "B.Cu")
		(net "P52V_HSC")
	)
	(via
		(at 32.304228 -267.97)
		(size 0.508)
		(drill 0.254)
		(layers "F.Cu" "B.Cu")
		(net "P52V_HSC")
	)
	(via
		(at 12.307824 -58.474356)
		(size 0.762)
		(drill 0.254)
		(layers "F.Cu" "B.Cu")
		(net "P52V_HSC")
	)
	(via
		(at 45.887132 -242.0366)
		(size 0.508)
		(drill 0.254)
		(layers "F.Cu" "B.Cu")
		(net "P52V_HSC")
	)
	(via
		(at 13.837158 -59.298078)
		(size 0.508)
		(drill 0.254)
		(layers "F.Cu" "B.Cu")
		(net "P52V_HSC")
	)
	(via
		(at 33.879028 -267.97)
		(size 0.508)
		(drill 0.254)
		(layers "F.Cu" "B.Cu")
		(net "P52V_HSC")
	)
	(via
		(at 9.948418 -58.477912)
		(size 0.508)
		(drill 0.254)
		(layers "F.Cu" "B.Cu")
		(net "P52V_HSC")
	)
	(via
		(at 42.635932 -244.2972)
		(size 0.508)
		(drill 0.254)
		(layers "F.Cu" "B.Cu")
		(net "P52V_HSC")
	)
	(via
		(at 8.095234 -59.078622)
		(size 0.508)
		(drill 0.254)
		(layers "F.Cu" "B.Cu")
		(net "P52V_HSC")
	)
	(via
		(at 12.715494 -79.086202)
		(size 0.508)
		(drill 0.254)
		(layers "F.Cu" "B.Cu")
		(net "P52V_HSC")
	)
	(via
		(at 8.095234 -244.31371)
		(size 0.508)
		(drill 0.254)
		(layers "F.Cu" "B.Cu")
		(net "P52V_HSC")
	)
	(via
		(at 40.476932 -79.086202)
		(size 0.508)
		(drill 0.254)
		(layers "F.Cu" "B.Cu")
		(net "P52V_HSC")
	)
	(via
		(at 12.377674 -243.714778)
		(size 0.508)
		(drill 0.254)
		(layers "F.Cu" "B.Cu")
		(net "P52V_HSC")
	)
	(via
		(at 41.111932 -263.68629)
		(size 0.508)
		(drill 0.254)
		(layers "F.Cu" "B.Cu")
		(net "P52V_HSC")
	)
	(via
		(at 7.439914 -59.713622)
		(size 0.508)
		(drill 0.254)
		(layers "F.Cu" "B.Cu")
		(net "P52V_HSC")
	)
	(via
		(at 29.088588 -10.7442)
		(size 0.508)
		(drill 0.254)
		(layers "F.Cu" "B.Cu")
		(net "P52V_HSC")
	)
	(via
		(at 13.831824 -58.474356)
		(size 0.508)
		(drill 0.254)
		(layers "F.Cu" "B.Cu")
		(net "P52V_HSC")
	)
	(via
		(at 29.088588 -12.0142)
		(size 0.508)
		(drill 0.254)
		(layers "F.Cu" "B.Cu")
		(net "P52V_HSC")
	)
	(via
		(at 4.61899 -263.8806)
		(size 0.762)
		(drill 0.254)
		(layers "F.Cu" "B.Cu")
		(net "P52V_HSC")
	)
	(via
		(at 41.111932 -79.721202)
		(size 0.508)
		(drill 0.254)
		(layers "F.Cu" "B.Cu")
		(net "P52V_HSC")
	)
	(via
		(at 41.407588 -58.570622)
		(size 0.508)
		(drill 0.254)
		(layers "F.Cu" "B.Cu")
		(net "P52V_HSC")
	)
	(via
		(at 38.857428 -59.713622)
		(size 0.508)
		(drill 0.254)
		(layers "F.Cu" "B.Cu")
		(net "P52V_HSC")
	)
	(via
		(at 10.30859 -264.4902)
		(size 0.508)
		(drill 0.254)
		(layers "F.Cu" "B.Cu")
		(net "P52V_HSC")
	)
	(via
		(at 4.61899 -80.067912)
		(size 0.508)
		(drill 0.254)
		(layers "F.Cu" "B.Cu")
		(net "P52V_HSC")
	)
	(via
		(at 13.477494 -263.68629)
		(size 0.508)
		(drill 0.254)
		(layers "F.Cu" "B.Cu")
		(net "P52V_HSC")
	)
	(via
		(at 3.426968 -267.146024)
		(size 0.508)
		(drill 0.254)
		(layers "F.Cu" "B.Cu")
		(net "P52V_HSC")
	)
	(via
		(at 41.111932 -264.32129)
		(size 0.508)
		(drill 0.254)
		(layers "F.Cu" "B.Cu")
		(net "P52V_HSC")
	)
	(via
		(at 40.476932 -263.68629)
		(size 0.508)
		(drill 0.254)
		(layers "F.Cu" "B.Cu")
		(net "P52V_HSC")
	)
	(via
		(at 44.159932 -260.477)
		(size 0.762)
		(drill 0.254)
		(layers "F.Cu" "B.Cu")
		(net "FAN_0_SS")
	)
	(segment
		(start 43.416728 -261.347204)
		(end 44.159932 -260.604)
		(width 0.1016)
		(layer "B.Cu")
		(net "FAN_0_SS")
	)
	(segment
		(start 44.159932 -260.477)
		(end 44.159932 -259.897118)
		(width 0.2794)
		(layer "B.Cu")
		(net "FAN_0_SS")
	)
	(segment
		(start 44.159932 -259.897118)
		(end 45.085 -258.97205)
		(width 0.2794)
		(layer "B.Cu")
		(net "FAN_0_SS")
	)
	(segment
		(start 44.159932 -260.604)
		(end 44.159932 -260.477)
		(width 0.1016)
		(layer "B.Cu")
		(net "FAN_0_SS")
	)
	(segment
		(start 43.416728 -262.054848)
		(end 43.416728 -261.347204)
		(width 0.1016)
		(layer "B.Cu")
		(net "FAN_0_SS")
	)
	(via
		(at 46.242732 -259.719826)
		(size 0.762)
		(drill 0.254)
		(layers "F.Cu" "B.Cu")
		(net "FAN_0_CS")
	)
	(segment
		(start 46.990508 -258.97205)
		(end 46.242732 -259.719826)
		(width 0.2794)
		(layer "B.Cu")
		(net "FAN_0_CS")
	)
	(segment
		(start 45.248068 -261.203186)
		(end 45.897038 -260.554216)
		(width 0.2794)
		(layer "B.Cu")
		(net "FAN_0_CS")
	)
	(segment
		(start 44.216574 -262.054848)
		(end 44.216574 -261.944358)
		(width 0.1016)
		(layer "B.Cu")
		(net "FAN_0_CS")
	)
	(segment
		(start 47.117 -258.97205)
		(end 46.990508 -258.97205)
		(width 0.2794)
		(layer "B.Cu")
		(net "FAN_0_CS")
	)
	(segment
		(start 44.373546 -261.787386)
		(end 45.248068 -261.203186)
		(width 0.1016)
		(layer "B.Cu")
		(net "FAN_0_CS")
	)
	(segment
		(start 45.897038 -260.554216)
		(end 46.242732 -259.719826)
		(width 0.2794)
		(layer "B.Cu")
		(net "FAN_0_CS")
	)
	(segment
		(start 44.216574 -261.944358)
		(end 44.373546 -261.787386)
		(width 0.1016)
		(layer "B.Cu")
		(net "FAN_0_CS")
	)
	(segment
		(start 41.12895 -181.61)
		(end 39.116 -181.61)
		(width 0.2794)
		(layer "F.Cu")
		(net "PD_FAN_BUFF_INPUT_U336E")
	)
	(segment
		(start 41.63695 -181.102)
		(end 41.12895 -181.61)
		(width 0.2794)
		(layer "F.Cu")
		(net "PD_FAN_BUFF_INPUT_U336E")
	)
	(segment
		(start 43.58132 -181.991)
		(end 42.46626 -181.991)
		(width 0.2794)
		(layer "F.Cu")
		(net "PD_FAN_BUFF_INPUT_U336E")
	)
	(segment
		(start 42.46626 -181.991)
		(end 41.63695 -181.16169)
		(width 0.2794)
		(layer "F.Cu")
		(net "PD_FAN_BUFF_INPUT_U336E")
	)
	(segment
		(start 44.68495 -181.102)
		(end 43.79595 -181.991)
		(width 0.2794)
		(layer "F.Cu")
		(net "PD_FAN_BUFF_INPUT_U336E")
	)
	(segment
		(start 41.63695 -181.16169)
		(end 41.63695 -181.102)
		(width 0.2794)
		(layer "F.Cu")
		(net "PD_FAN_BUFF_INPUT_U336E")
	)
	(segment
		(start 43.79595 -181.991)
		(end 43.58132 -181.991)
		(width 0.2794)
		(layer "F.Cu")
		(net "PD_FAN_BUFF_INPUT_U336E")
	)
	(via
		(at 43.58132 -181.991)
		(size 0.508)
		(drill 0.254)
		(layers "F.Cu" "B.Cu")
		(net "PD_FAN_BUFF_INPUT_U336E")
	)
	(segment
		(start 41.741598 -254.62865)
		(end 40.50665 -254.62865)
		(width 0.2794)
		(layer "F.Cu")
		(net "FAN_1_ON")
	)
	(segment
		(start 39.727378 -253.849378)
		(end 39.727378 -253.656846)
		(width 0.2794)
		(layer "F.Cu")
		(net "FAN_1_ON")
	)
	(segment
		(start 40.50665 -254.62865)
		(end 39.727378 -253.849378)
		(width 0.2794)
		(layer "F.Cu")
		(net "FAN_1_ON")
	)
	(via
		(at 41.741598 -254.62865)
		(size 0.762)
		(drill 0.254)
		(layers "F.Cu" "B.Cu")
		(net "FAN_1_ON")
	)
	(via
		(at 38.013132 -247.641872)
		(size 0.508)
		(drill 0.254)
		(layers "F.Cu" "B.Cu")
		(net "FAN_1_ON")
	)
	(segment
		(start 38.013132 -247.641872)
		(end 37.988748 -247.631712)
		(width 0.1016)
		(layer "B.Cu")
		(net "FAN_1_ON")
	)
	(segment
		(start 37.917628 -247.4595)
		(end 37.917628 -246.744998)
		(width 0.1016)
		(layer "B.Cu")
		(net "FAN_1_ON")
	)
	(segment
		(start 37.988748 -247.631712)
		(end 37.917628 -247.4595)
		(width 0.1016)
		(layer "B.Cu")
		(net "FAN_1_ON")
	)
	(segment
		(start 39.580566 -248.368312)
		(end 39.580566 -251.28601)
		(width 0.2286)
		(layer "In2.Cu")
		(net "FAN_1_ON")
	)
	(segment
		(start 40.259 -253.146052)
		(end 41.741598 -254.62865)
		(width 0.2286)
		(layer "In2.Cu")
		(net "FAN_1_ON")
	)
	(segment
		(start 39.580566 -251.28601)
		(end 40.259 -251.964444)
		(width 0.2286)
		(layer "In2.Cu")
		(net "FAN_1_ON")
	)
	(segment
		(start 38.013132 -247.641872)
		(end 38.854126 -247.641872)
		(width 0.2286)
		(layer "In2.Cu")
		(net "FAN_1_ON")
	)
	(segment
		(start 40.259 -251.964444)
		(end 40.259 -253.146052)
		(width 0.2286)
		(layer "In2.Cu")
		(net "FAN_1_ON")
	)
	(segment
		(start 38.854126 -247.641872)
		(end 39.580566 -248.368312)
		(width 0.2286)
		(layer "In2.Cu")
		(net "FAN_1_ON")
	)
	(segment
		(start 37.098478 -252.367796)
		(end 36.698428 -252.767846)
		(width 0.2794)
		(layer "F.Cu")
		(net "FAN_1_PRESENT_R")
	)
	(segment
		(start 36.698428 -252.767846)
		(end 36.698428 -252.894846)
		(width 0.2794)
		(layer "F.Cu")
		(net "FAN_1_PRESENT_R")
	)
	(segment
		(start 37.098478 -252.132846)
		(end 37.098478 -252.367796)
		(width 0.2794)
		(layer "F.Cu")
		(net "FAN_1_PRESENT_R")
	)
	(via
		(at 36.698428 -252.894846)
		(size 0.508)
		(drill 0.254)
		(layers "F.Cu" "B.Cu")
		(net "FAN_1_PRESENT_R")
	)
	(segment
		(start 36.698428 -252.767846)
		(end 37.221414 -252.24486)
		(width 0.2794)
		(layer "B.Cu")
		(net "FAN_1_PRESENT_R")
	)
	(segment
		(start 36.698428 -252.894846)
		(end 36.698428 -252.767846)
		(width 0.2794)
		(layer "B.Cu")
		(net "FAN_1_PRESENT_R")
	)
	(segment
		(start 37.221414 -252.24486)
		(end 38.403022 -252.24486)
		(width 0.2794)
		(layer "B.Cu")
		(net "FAN_1_PRESENT_R")
	)
	(via
		(at 45.302932 -260.111748)
		(size 0.6604)
		(drill 0.3302)
		(layers "F.Cu" "B.Cu")
		(net "FAN_0_IMON")
	)
	(segment
		(start 44.323 -261.239)
		(end 45.302932 -260.259068)
		(width 0.2794)
		(layer "B.Cu")
		(net "FAN_0_IMON")
	)
	(segment
		(start 43.816778 -261.597902)
		(end 44.17568 -261.239)
		(width 0.1016)
		(layer "B.Cu")
		(net "FAN_0_IMON")
	)
	(segment
		(start 44.17568 -261.239)
		(end 44.323 -261.239)
		(width 0.2794)
		(layer "B.Cu")
		(net "FAN_0_IMON")
	)
	(segment
		(start 43.816778 -262.054848)
		(end 43.816778 -261.597902)
		(width 0.1016)
		(layer "B.Cu")
		(net "FAN_0_IMON")
	)
	(segment
		(start 46.101 -258.97205)
		(end 45.302932 -259.770118)
		(width 0.2794)
		(layer "B.Cu")
		(net "FAN_0_IMON")
	)
	(segment
		(start 45.302932 -260.259068)
		(end 45.302932 -260.111748)
		(width 0.2794)
		(layer "B.Cu")
		(net "FAN_0_IMON")
	)
	(segment
		(start 45.302932 -259.770118)
		(end 45.302932 -260.111748)
		(width 0.2794)
		(layer "B.Cu")
		(net "FAN_0_IMON")
	)
	(segment
		(start 35.41649 -251.57049)
		(end 35.41649 -251.333)
		(width 0.2794)
		(layer "F.Cu")
		(net "FAN_1_PRESENT")
	)
	(segment
		(start 42.3799 -218.073986)
		(end 42.129964 -217.82405)
		(width 0.2794)
		(layer "F.Cu")
		(net "FAN_1_PRESENT")
	)
	(segment
		(start 42.129964 -217.82405)
		(end 40.894 -217.82405)
		(width 0.2794)
		(layer "F.Cu")
		(net "FAN_1_PRESENT")
	)
	(segment
		(start 36.298378 -252.132846)
		(end 35.978846 -252.132846)
		(width 0.2794)
		(layer "F.Cu")
		(net "FAN_1_PRESENT")
	)
	(segment
		(start 35.978846 -252.132846)
		(end 35.41649 -251.57049)
		(width 0.2794)
		(layer "F.Cu")
		(net "FAN_1_PRESENT")
	)
	(segment
		(start 40.894 -217.82405)
		(end 29.845 -217.82405)
		(width 0.2794)
		(layer "F.Cu")
		(net "FAN_1_PRESENT")
	)
	(via
		(at 35.41649 -251.333)
		(size 0.508)
		(drill 0.254)
		(layers "F.Cu" "B.Cu")
		(net "FAN_1_PRESENT")
	)
	(via
		(at 29.845 -217.82405)
		(size 0.508)
		(drill 0.254)
		(layers "F.Cu" "B.Cu")
		(net "FAN_1_PRESENT")
	)
	(segment
		(start 29.845 -217.82405)
		(end 31.115 -219.09405)
		(width 0.2794)
		(layer "B.Cu")
		(net "FAN_1_PRESENT")
	)
	(segment
		(start 31.115 -219.09405)
		(end 31.115 -250.573032)
		(width 0.2794)
		(layer "B.Cu")
		(net "FAN_1_PRESENT")
	)
	(segment
		(start 35.41649 -251.333)
		(end 35.41649 -252.121924)
		(width 0.2794)
		(layer "B.Cu")
		(net "FAN_1_PRESENT")
	)
	(segment
		(start 31.874968 -251.333)
		(end 35.41649 -251.333)
		(width 0.2794)
		(layer "B.Cu")
		(net "FAN_1_PRESENT")
	)
	(segment
		(start 31.115 -250.573032)
		(end 31.874968 -251.333)
		(width 0.2794)
		(layer "B.Cu")
		(net "FAN_1_PRESENT")
	)
	(via
		(at 42.216578 -260.369558)
		(size 0.6604)
		(drill 0.3302)
		(layers "F.Cu" "B.Cu")
		(net "FAN_0_CLREF")
	)
	(segment
		(start 42.037 -258.97205)
		(end 43.053 -258.97205)
		(width 0.2794)
		(layer "B.Cu")
		(net "FAN_0_CLREF")
	)
	(segment
		(start 42.216578 -260.111494)
		(end 42.216578 -260.369558)
		(width 0.1016)
		(layer "B.Cu")
		(net "FAN_0_CLREF")
	)
	(segment
		(start 42.216578 -260.369558)
		(end 42.216578 -262.054848)
		(width 0.1016)
		(layer "B.Cu")
		(net "FAN_0_CLREF")
	)
	(segment
		(start 42.037 -258.97205)
		(end 42.037 -259.492242)
		(width 0.2794)
		(layer "B.Cu")
		(net "FAN_0_CLREF")
	)
	(segment
		(start 42.037 -259.492242)
		(end 42.216578 -260.111494)
		(width 0.1016)
		(layer "B.Cu")
		(net "FAN_0_CLREF")
	)
	(segment
		(start 13.926058 -298.069)
		(end 13.037058 -298.069)
		(width 0.2794)
		(layer "F.Cu")
		(net "FAN_7_FAIL_R_LED_N")
	)
	(segment
		(start 11.796014 -299.310044)
		(end 8.700008 -299.310044)
		(width 0.2794)
		(layer "F.Cu")
		(net "FAN_7_FAIL_R_LED_N")
	)
	(segment
		(start 13.037058 -298.069)
		(end 12.640056 -298.466002)
		(width 0.2794)
		(layer "F.Cu")
		(net "FAN_7_FAIL_R_LED_N")
	)
	(segment
		(start 13.95095 -296.799)
		(end 13.95095 -297.472608)
		(width 0.2794)
		(layer "F.Cu")
		(net "FAN_7_FAIL_R_LED_N")
	)
	(segment
		(start 13.95095 -297.472608)
		(end 13.926058 -297.4975)
		(width 0.2794)
		(layer "F.Cu")
		(net "FAN_7_FAIL_R_LED_N")
	)
	(segment
		(start 13.926058 -297.4975)
		(end 13.926058 -298.069)
		(width 0.2794)
		(layer "F.Cu")
		(net "FAN_7_FAIL_R_LED_N")
	)
	(segment
		(start 12.640056 -298.466002)
		(end 11.796014 -299.310044)
		(width 0.2794)
		(layer "F.Cu")
		(net "FAN_7_FAIL_R_LED_N")
	)
	(via
		(at 12.640056 -298.466002)
		(size 0.762)
		(drill 0.381)
		(layers "F.Cu" "B.Cu")
		(net "FAN_7_FAIL_R_LED_N")
	)
	(via
		(at 37.973 -259.842)
		(size 0.762)
		(drill 0.254)
		(layers "F.Cu" "B.Cu")
		(net "FAN_0_TEMP")
	)
	(segment
		(start 39.388542 -260.65861)
		(end 39.587932 -260.858)
		(width 0.2794)
		(layer "B.Cu")
		(net "FAN_0_TEMP")
	)
	(segment
		(start 38.46068 -258.962906)
		(end 37.474144 -258.962906)
		(width 0.2794)
		(layer "B.Cu")
		(net "FAN_0_TEMP")
	)
	(segment
		(start 39.106094 -260.601968)
		(end 39.388542 -260.65861)
		(width 0.2794)
		(layer "B.Cu")
		(net "FAN_0_TEMP")
	)
	(segment
		(start 37.465 -259.334)
		(end 37.465 -258.97205)
		(width 0.2794)
		(layer "B.Cu")
		(net "FAN_0_TEMP")
	)
	(segment
		(start 39.587932 -260.858)
		(end 40.216582 -261.48665)
		(width 0.1016)
		(layer "B.Cu")
		(net "FAN_0_TEMP")
	)
	(segment
		(start 37.973 -259.842)
		(end 37.465 -259.334)
		(width 0.2794)
		(layer "B.Cu")
		(net "FAN_0_TEMP")
	)
	(segment
		(start 40.216582 -261.48665)
		(end 40.216582 -262.054848)
		(width 0.1016)
		(layer "B.Cu")
		(net "FAN_0_TEMP")
	)
	(segment
		(start 37.474144 -258.962906)
		(end 37.465 -258.97205)
		(width 0.2794)
		(layer "B.Cu")
		(net "FAN_0_TEMP")
	)
	(segment
		(start 37.973 -259.842)
		(end 39.106094 -260.601968)
		(width 0.2794)
		(layer "B.Cu")
		(net "FAN_0_TEMP")
	)
	(segment
		(start 41.63695 -189.79769)
		(end 41.63695 -189.738)
		(width 0.2794)
		(layer "F.Cu")
		(net "PD_FAN_BUFF_INPUT_U337F")
	)
	(segment
		(start 40.590978 -190.783972)
		(end 39.243 -190.783972)
		(width 0.2794)
		(layer "F.Cu")
		(net "PD_FAN_BUFF_INPUT_U337F")
	)
	(segment
		(start 42.72026 -190.881)
		(end 41.63695 -189.79769)
		(width 0.2794)
		(layer "F.Cu")
		(net "PD_FAN_BUFF_INPUT_U337F")
	)
	(segment
		(start 41.63695 -189.738)
		(end 40.590978 -190.783972)
		(width 0.2794)
		(layer "F.Cu")
		(net "PD_FAN_BUFF_INPUT_U337F")
	)
	(segment
		(start 44.68495 -189.738)
		(end 44.68495 -189.88405)
		(width 0.2794)
		(layer "F.Cu")
		(net "PD_FAN_BUFF_INPUT_U337F")
	)
	(segment
		(start 43.688 -190.881)
		(end 42.72026 -190.881)
		(width 0.2794)
		(layer "F.Cu")
		(net "PD_FAN_BUFF_INPUT_U337F")
	)
	(segment
		(start 44.68495 -189.88405)
		(end 43.688 -190.881)
		(width 0.2794)
		(layer "F.Cu")
		(net "PD_FAN_BUFF_INPUT_U337F")
	)
	(via
		(at 43.688 -190.881)
		(size 0.762)
		(drill 0.254)
		(layers "F.Cu" "B.Cu")
		(net "PD_FAN_BUFF_INPUT_U337F")
	)
	(segment
		(start 11.811 -300.736)
		(end 10.414 -300.736)
		(width 0.2794)
		(layer "F.Cu")
		(net "FAN_7_OK_R_LED_N")
	)
	(segment
		(start 9.83996 -301.31004)
		(end 8.700008 -301.31004)
		(width 0.2794)
		(layer "F.Cu")
		(net "FAN_7_OK_R_LED_N")
	)
	(segment
		(start 13.95095 -300.711108)
		(end 13.926058 -300.736)
		(width 0.2794)
		(layer "F.Cu")
		(net "FAN_7_OK_R_LED_N")
	)
	(segment
		(start 13.95095 -299.339)
		(end 13.95095 -300.711108)
		(width 0.2794)
		(layer "F.Cu")
		(net "FAN_7_OK_R_LED_N")
	)
	(segment
		(start 10.414 -300.736)
		(end 9.83996 -301.31004)
		(width 0.2794)
		(layer "F.Cu")
		(net "FAN_7_OK_R_LED_N")
	)
	(segment
		(start 13.926058 -300.736)
		(end 11.811 -300.736)
		(width 0.2794)
		(layer "F.Cu")
		(net "FAN_7_OK_R_LED_N")
	)
	(via
		(at 11.811 -300.736)
		(size 0.762)
		(drill 0.381)
		(layers "F.Cu" "B.Cu")
		(net "FAN_7_OK_R_LED_N")
	)
	(segment
		(start 42.69105 -259.461)
		(end 42.69105 -260.477)
		(width 0.2794)
		(layer "F.Cu")
		(net "FAN_0_MODE")
	)
	(segment
		(start 42.41165 -261.22122)
		(end 42.69105 -260.94182)
		(width 0.2794)
		(layer "F.Cu")
		(net "FAN_0_MODE")
	)
	(segment
		(start 38.9001 -261.22122)
		(end 42.41165 -261.22122)
		(width 0.2794)
		(layer "F.Cu")
		(net "FAN_0_MODE")
	)
	(segment
		(start 42.69105 -260.94182)
		(end 42.69105 -260.477)
		(width 0.2794)
		(layer "F.Cu")
		(net "FAN_0_MODE")
	)
	(via
		(at 38.9001 -261.22122)
		(size 0.762)
		(drill 0.254)
		(layers "F.Cu" "B.Cu")
		(net "FAN_0_MODE")
	)
	(segment
		(start 38.9001 -261.22122)
		(end 38.9001 -261.3406)
		(width 0.2794)
		(layer "B.Cu")
		(net "FAN_0_MODE")
	)
	(segment
		(start 39.816786 -261.975854)
		(end 39.816786 -262.054848)
		(width 0.1016)
		(layer "B.Cu")
		(net "FAN_0_MODE")
	)
	(segment
		(start 39.639748 -261.798816)
		(end 39.816786 -261.975854)
		(width 0.1016)
		(layer "B.Cu")
		(net "FAN_0_MODE")
	)
	(segment
		(start 38.9001 -261.3406)
		(end 39.358316 -261.798816)
		(width 0.2794)
		(layer "B.Cu")
		(net "FAN_0_MODE")
	)
	(segment
		(start 39.358316 -261.798816)
		(end 39.639748 -261.798816)
		(width 0.2794)
		(layer "B.Cu")
		(net "FAN_0_MODE")
	)
	(segment
		(start 40.513 -258.953)
		(end 41.021 -258.445)
		(width 0.2794)
		(layer "F.Cu")
		(net "FAN_0_P3V_R")
	)
	(segment
		(start 41.021 -258.445)
		(end 41.89095 -258.445)
		(width 0.2794)
		(layer "F.Cu")
		(net "FAN_0_P3V_R")
	)
	(segment
		(start 41.89095 -258.445)
		(end 41.89095 -259.461)
		(width 0.2794)
		(layer "F.Cu")
		(net "FAN_0_P3V_R")
	)
	(segment
		(start 40.513 -259.842)
		(end 40.513 -258.953)
		(width 0.2794)
		(layer "F.Cu")
		(net "FAN_0_P3V_R")
	)
	(via
		(at 40.513 -259.842)
		(size 0.762)
		(drill 0.254)
		(layers "F.Cu" "B.Cu")
		(net "FAN_0_P3V_R")
	)
	(segment
		(start 40.513254 -260.448552)
		(end 41.016682 -261.66318)
		(width 0.1016)
		(layer "B.Cu")
		(net "FAN_0_P3V_R")
	)
	(segment
		(start 41.016682 -261.66318)
		(end 41.016682 -262.054848)
		(width 0.1016)
		(layer "B.Cu")
		(net "FAN_0_P3V_R")
	)
	(segment
		(start 40.513 -259.842)
		(end 40.513254 -260.448552)
		(width 0.1016)
		(layer "B.Cu")
		(net "FAN_0_P3V_R")
	)
	(segment
		(start 40.513 -258.97205)
		(end 40.513 -259.842)
		(width 0.2794)
		(layer "B.Cu")
		(net "FAN_0_P3V_R")
	)
	(via
		(at 39.841932 -260.223)
		(size 0.6604)
		(drill 0.3302)
		(layers "F.Cu" "B.Cu")
		(net "FAN_0_P5V")
	)
	(segment
		(start 39.841932 -260.223)
		(end 39.931594 -260.250178)
		(width 0.1016)
		(layer "B.Cu")
		(net "FAN_0_P5V")
	)
	(segment
		(start 39.47668 -258.962906)
		(end 39.47668 -259.857748)
		(width 0.2794)
		(layer "B.Cu")
		(net "FAN_0_P5V")
	)
	(segment
		(start 40.616632 -261.531608)
		(end 40.616632 -262.054848)
		(width 0.1016)
		(layer "B.Cu")
		(net "FAN_0_P5V")
	)
	(segment
		(start 39.47668 -259.857748)
		(end 39.841932 -260.223)
		(width 0.2794)
		(layer "B.Cu")
		(net "FAN_0_P5V")
	)
	(segment
		(start 39.931594 -260.250178)
		(end 40.616632 -261.531608)
		(width 0.1016)
		(layer "B.Cu")
		(net "FAN_0_P5V")
	)
	(segment
		(start 5.588 -182.372)
		(end 5.725922 -182.234078)
		(width 0.2794)
		(layer "F.Cu")
		(net "PCA9555_MB0_A2")
	)
	(segment
		(start 5.334 -182.626)
		(end 5.588 -182.372)
		(width 0.2794)
		(layer "F.Cu")
		(net "PCA9555_MB0_A2")
	)
	(segment
		(start 5.725922 -182.234078)
		(end 7.366 -182.234078)
		(width 0.2794)
		(layer "F.Cu")
		(net "PCA9555_MB0_A2")
	)
	(segment
		(start 4.21005 -182.626)
		(end 5.334 -182.626)
		(width 0.2794)
		(layer "F.Cu")
		(net "PCA9555_MB0_A2")
	)
	(segment
		(start 4.21005 -181.61)
		(end 4.21005 -182.626)
		(width 0.2794)
		(layer "F.Cu")
		(net "PCA9555_MB0_A2")
	)
	(via
		(at 5.588 -182.372)
		(size 0.762)
		(drill 0.381)
		(layers "F.Cu" "B.Cu")
		(net "PCA9555_MB0_A2")
	)
	(segment
		(start 43.814746 -261.608824)
		(end 43.415966 -261.210044)
		(width 0.2794)
		(layer "F.Cu")
		(net "FAN_0_FAULT")
	)
	(segment
		(start 45.2374 -261.608824)
		(end 43.814746 -261.608824)
		(width 0.2794)
		(layer "F.Cu")
		(net "FAN_0_FAULT")
	)
	(segment
		(start 44.963334 -258.145788)
		(end 45.237146 -258.145788)
		(width 0.2794)
		(layer "F.Cu")
		(net "FAN_0_FAULT")
	)
	(segment
		(start 45.5168 -258.425442)
		(end 45.5168 -261.329424)
		(width 0.2794)
		(layer "F.Cu")
		(net "FAN_0_FAULT")
	)
	(segment
		(start 43.415966 -261.210044)
		(end 43.415966 -260.204966)
		(width 0.2794)
		(layer "F.Cu")
		(net "FAN_0_FAULT")
	)
	(segment
		(start 45.5168 -261.329424)
		(end 45.2374 -261.608824)
		(width 0.2794)
		(layer "F.Cu")
		(net "FAN_0_FAULT")
	)
	(segment
		(start 45.237146 -258.145788)
		(end 45.5168 -258.425442)
		(width 0.2794)
		(layer "F.Cu")
		(net "FAN_0_FAULT")
	)
	(segment
		(start 43.883072 -259.22605)
		(end 44.963334 -258.145788)
		(width 0.2794)
		(layer "F.Cu")
		(net "FAN_0_FAULT")
	)
	(segment
		(start 43.688 -259.22605)
		(end 43.883072 -259.22605)
		(width 0.2794)
		(layer "F.Cu")
		(net "FAN_0_FAULT")
	)
	(via
		(at 44.963334 -258.145788)
		(size 0.762)
		(drill 0.381)
		(layers "F.Cu" "B.Cu")
		(net "FAN_0_FAULT")
	)
	(via
		(at 43.415966 -260.204966)
		(size 0.508)
		(drill 0.254)
		(layers "F.Cu" "B.Cu")
		(net "FAN_0_FAULT")
	)
	(segment
		(start 43.415966 -260.204966)
		(end 43.307 -260.313932)
		(width 0.2794)
		(layer "B.Cu")
		(net "FAN_0_FAULT")
	)
	(segment
		(start 43.307 -260.313932)
		(end 43.307 -260.77037)
		(width 0.2794)
		(layer "B.Cu")
		(net "FAN_0_FAULT")
	)
	(segment
		(start 43.016678 -261.471664)
		(end 43.016678 -262.054848)
		(width 0.1016)
		(layer "B.Cu")
		(net "FAN_0_FAULT")
	)
	(segment
		(start 43.307 -260.77037)
		(end 43.016678 -261.471664)
		(width 0.1016)
		(layer "B.Cu")
		(net "FAN_0_FAULT")
	)
	(segment
		(start 43.456098 -184.108852)
		(end 43.447462 -184.117488)
		(width 0.2794)
		(layer "F.Cu")
		(net "PD_FAN_BUFF_INPUT_U336F")
	)
	(segment
		(start 41.63695 -182.88)
		(end 41.606978 -182.909972)
		(width 0.2794)
		(layer "F.Cu")
		(net "PD_FAN_BUFF_INPUT_U336F")
	)
	(segment
		(start 43.456098 -184.108852)
		(end 44.68495 -182.88)
		(width 0.2794)
		(layer "F.Cu")
		(net "PD_FAN_BUFF_INPUT_U336F")
	)
	(segment
		(start 41.63695 -182.93969)
		(end 41.63695 -182.88)
		(width 0.2794)
		(layer "F.Cu")
		(net "PD_FAN_BUFF_INPUT_U336F")
	)
	(segment
		(start 41.606978 -182.909972)
		(end 39.116 -182.909972)
		(width 0.2794)
		(layer "F.Cu")
		(net "PD_FAN_BUFF_INPUT_U336F")
	)
	(segment
		(start 43.447462 -184.117488)
		(end 42.814748 -184.117488)
		(width 0.2794)
		(layer "F.Cu")
		(net "PD_FAN_BUFF_INPUT_U336F")
	)
	(segment
		(start 42.814748 -184.117488)
		(end 41.63695 -182.93969)
		(width 0.2794)
		(layer "F.Cu")
		(net "PD_FAN_BUFF_INPUT_U336F")
	)
	(via
		(at 43.456098 -184.108852)
		(size 0.762)
		(drill 0.381)
		(layers "F.Cu" "B.Cu")
		(net "PD_FAN_BUFF_INPUT_U336F")
	)
	(segment
		(start 37.762942 -107.067604)
		(end 37.369496 -107.46105)
		(width 0.2794)
		(layer "F.Cu")
		(net "FAN_2_OK_R_LED_N")
	)
	(segment
		(start 37.369496 -107.46105)
		(end 36.703 -107.46105)
		(width 0.2794)
		(layer "F.Cu")
		(net "FAN_2_OK_R_LED_N")
	)
	(segment
		(start 38.273736 -105.086912)
		(end 39.544244 -106.35742)
		(width 0.2794)
		(layer "F.Cu")
		(net "FAN_2_OK_R_LED_N")
	)
	(segment
		(start 37.762942 -105.086912)
		(end 37.762942 -107.067604)
		(width 0.2794)
		(layer "F.Cu")
		(net "FAN_2_OK_R_LED_N")
	)
	(segment
		(start 39.544244 -106.35742)
		(end 39.896796 -106.709972)
		(width 0.2794)
		(layer "F.Cu")
		(net "FAN_2_OK_R_LED_N")
	)
	(segment
		(start 37.762942 -105.086912)
		(end 38.273736 -105.086912)
		(width 0.2794)
		(layer "F.Cu")
		(net "FAN_2_OK_R_LED_N")
	)
	(segment
		(start 39.896796 -106.709972)
		(end 42.999914 -106.709972)
		(width 0.2794)
		(layer "F.Cu")
		(net "FAN_2_OK_R_LED_N")
	)
	(via
		(at 39.544244 -106.35742)
		(size 0.762)
		(drill 0.381)
		(layers "F.Cu" "B.Cu")
		(net "FAN_2_OK_R_LED_N")
	)
	(segment
		(start 14.7193 -141.986)
		(end 11.346434 -140.589)
		(width 0.2794)
		(layer "F.Cu")
		(net "RST_SMB_PDB_N")
	)
	(segment
		(start 8.2042 -140.589)
		(end 7.3406 -141.4526)
		(width 0.2794)
		(layer "F.Cu")
		(net "RST_SMB_PDB_N")
	)
	(segment
		(start 20.30095 -141.986)
		(end 15.67434 -141.986)
		(width 0.2794)
		(layer "F.Cu")
		(net "RST_SMB_PDB_N")
	)
	(segment
		(start 20.32 -142.00505)
		(end 20.30095 -141.986)
		(width 0.2794)
		(layer "F.Cu")
		(net "RST_SMB_PDB_N")
	)
	(segment
		(start 20.32 -142.00505)
		(end 20.32 -143.49095)
		(width 0.2794)
		(layer "F.Cu")
		(net "RST_SMB_PDB_N")
	)
	(segment
		(start 11.346434 -140.589)
		(end 8.2042 -140.589)
		(width 0.2794)
		(layer "F.Cu")
		(net "RST_SMB_PDB_N")
	)
	(segment
		(start 15.67434 -141.986)
		(end 14.7193 -141.986)
		(width 0.2794)
		(layer "F.Cu")
		(net "RST_SMB_PDB_N")
	)
	(via
		(at 15.67434 -141.986)
		(size 0.762)
		(drill 0.381)
		(layers "F.Cu" "B.Cu")
		(net "RST_SMB_PDB_N")
	)
	(via
		(at 7.3406 -141.4526)
		(size 0.508)
		(drill 0.254)
		(layers "F.Cu" "B.Cu")
		(net "RST_SMB_PDB_N")
	)
	(via
		(at 21.4376 -16.3068)
		(size 0.508)
		(drill 0.254)
		(layers "F.Cu" "B.Cu")
		(net "RST_SMB_PDB_N")
	)
	(segment
		(start 24.889968 -4.350004)
		(end 24.889968 -13.464286)
		(width 0.2794)
		(layer "B.Cu")
		(net "RST_SMB_PDB_N")
	)
	(segment
		(start 22.047454 -16.3068)
		(end 21.4376 -16.3068)
		(width 0.2794)
		(layer "B.Cu")
		(net "RST_SMB_PDB_N")
	)
	(segment
		(start 24.889968 -13.464286)
		(end 22.047454 -16.3068)
		(width 0.2794)
		(layer "B.Cu")
		(net "RST_SMB_PDB_N")
	)
	(segment
		(start 13.3858 -28.61818)
		(end 15.38097 -30.61335)
		(width 0.2286)
		(layer "In2.Cu")
		(net "RST_SMB_PDB_N")
	)
	(segment
		(start 12.0269 -106.10088)
		(end 12.0269 -119.01678)
		(width 0.2286)
		(layer "In2.Cu")
		(net "RST_SMB_PDB_N")
	)
	(segment
		(start 15.38097 -30.61335)
		(end 15.38097 -52.85232)
		(width 0.2286)
		(layer "In2.Cu")
		(net "RST_SMB_PDB_N")
	)
	(segment
		(start 21.4376 -16.3068)
		(end 19.805142 -16.3068)
		(width 0.2286)
		(layer "In2.Cu")
		(net "RST_SMB_PDB_N")
	)
	(segment
		(start 19.805142 -16.3068)
		(end 18.966942 -17.145)
		(width 0.2286)
		(layer "In2.Cu")
		(net "RST_SMB_PDB_N")
	)
	(segment
		(start 15.38097 -52.85232)
		(end 19.568668 -62.957456)
		(width 0.2286)
		(layer "In2.Cu")
		(net "RST_SMB_PDB_N")
	)
	(segment
		(start 16.684498 -17.145)
		(end 13.3858 -20.443698)
		(width 0.2286)
		(layer "In2.Cu")
		(net "RST_SMB_PDB_N")
	)
	(segment
		(start 11.3538 -137.4394)
		(end 7.3406 -141.4526)
		(width 0.2286)
		(layer "In2.Cu")
		(net "RST_SMB_PDB_N")
	)
	(segment
		(start 12.0269 -119.01678)
		(end 11.14806 -119.89562)
		(width 0.2286)
		(layer "In2.Cu")
		(net "RST_SMB_PDB_N")
	)
	(segment
		(start 11.3538 -129.15646)
		(end 11.3538 -137.4394)
		(width 0.2286)
		(layer "In2.Cu")
		(net "RST_SMB_PDB_N")
	)
	(segment
		(start 13.3858 -20.443698)
		(end 13.3858 -28.61818)
		(width 0.2286)
		(layer "In2.Cu")
		(net "RST_SMB_PDB_N")
	)
	(segment
		(start 11.14806 -119.89562)
		(end 11.14806 -128.95072)
		(width 0.2286)
		(layer "In2.Cu")
		(net "RST_SMB_PDB_N")
	)
	(segment
		(start 18.966942 -17.145)
		(end 16.684498 -17.145)
		(width 0.2286)
		(layer "In2.Cu")
		(net "RST_SMB_PDB_N")
	)
	(segment
		(start 11.14806 -128.95072)
		(end 11.3538 -129.15646)
		(width 0.2286)
		(layer "In2.Cu")
		(net "RST_SMB_PDB_N")
	)
	(segment
		(start 20.371816 -97.755964)
		(end 12.0269 -106.10088)
		(width 0.2286)
		(layer "In2.Cu")
		(net "RST_SMB_PDB_N")
	)
	(segment
		(start 20.371816 -85.809836)
		(end 20.371816 -97.755964)
		(width 0.2286)
		(layer "In2.Cu")
		(net "RST_SMB_PDB_N")
	)
	(segment
		(start 19.568668 -62.957456)
		(end 19.568668 -85.006688)
		(width 0.2286)
		(layer "In2.Cu")
		(net "RST_SMB_PDB_N")
	)
	(segment
		(start 19.568668 -85.006688)
		(end 20.371816 -85.809836)
		(width 0.2286)
		(layer "In2.Cu")
		(net "RST_SMB_PDB_N")
	)
	(segment
		(start 43.688 -258.42595)
		(end 42.7101 -258.42595)
		(width 0.2794)
		(layer "F.Cu")
		(net "FAN_0_FAULT_R")
	)
	(segment
		(start 42.7101 -258.42595)
		(end 42.69105 -258.445)
		(width 0.2794)
		(layer "F.Cu")
		(net "FAN_0_FAULT_R")
	)
	(segment
		(start 39.071296 -111.465614)
		(end 39.448486 -111.088424)
		(width 0.2794)
		(layer "F.Cu")
		(net "FAN_2_FAIL_R_LED_N")
	)
	(segment
		(start 41.414446 -108.441236)
		(end 39.521892 -108.441236)
		(width 0.2794)
		(layer "F.Cu")
		(net "FAN_2_FAIL_R_LED_N")
	)
	(segment
		(start 38.033706 -108.441236)
		(end 37.762942 -108.712)
		(width 0.2794)
		(layer "F.Cu")
		(net "FAN_2_FAIL_R_LED_N")
	)
	(segment
		(start 39.521892 -108.441236)
		(end 38.033706 -108.441236)
		(width 0.2794)
		(layer "F.Cu")
		(net "FAN_2_FAIL_R_LED_N")
	)
	(segment
		(start 37.973 -109.96295)
		(end 38.518592 -110.508542)
		(width 0.2794)
		(layer "F.Cu")
		(net "FAN_2_FAIL_R_LED_N")
	)
	(segment
		(start 39.448486 -111.088424)
		(end 39.448486 -110.508542)
		(width 0.2794)
		(layer "F.Cu")
		(net "FAN_2_FAIL_R_LED_N")
	)
	(segment
		(start 37.532564 -111.465614)
		(end 39.071296 -111.465614)
		(width 0.2794)
		(layer "F.Cu")
		(net "FAN_2_FAIL_R_LED_N")
	)
	(segment
		(start 37.973 -108.922058)
		(end 37.973 -109.96295)
		(width 0.2794)
		(layer "F.Cu")
		(net "FAN_2_FAIL_R_LED_N")
	)
	(segment
		(start 37.762942 -108.712)
		(end 37.973 -108.922058)
		(width 0.2794)
		(layer "F.Cu")
		(net "FAN_2_FAIL_R_LED_N")
	)
	(segment
		(start 36.83 -110.76305)
		(end 37.532564 -111.465614)
		(width 0.2794)
		(layer "F.Cu")
		(net "FAN_2_FAIL_R_LED_N")
	)
	(segment
		(start 38.518592 -110.508542)
		(end 39.448486 -110.508542)
		(width 0.2794)
		(layer "F.Cu")
		(net "FAN_2_FAIL_R_LED_N")
	)
	(segment
		(start 41.683178 -108.709968)
		(end 41.414446 -108.441236)
		(width 0.2794)
		(layer "F.Cu")
		(net "FAN_2_FAIL_R_LED_N")
	)
	(segment
		(start 42.999914 -108.709968)
		(end 41.683178 -108.709968)
		(width 0.2794)
		(layer "F.Cu")
		(net "FAN_2_FAIL_R_LED_N")
	)
	(via
		(at 39.521892 -108.441236)
		(size 0.762)
		(drill 0.381)
		(layers "F.Cu" "B.Cu")
		(net "FAN_2_FAIL_R_LED_N")
	)
	(via
		(at 39.448486 -110.508542)
		(size 0.762)
		(drill 0.381)
		(layers "F.Cu" "B.Cu")
		(net "FAN_2_FAIL_R_LED_N")
	)
	(segment
		(start 6.472936 -182.884064)
		(end 7.366 -182.884064)
		(width 0.2794)
		(layer "F.Cu")
		(net "PCA9555_MB0_A1")
	)
	(segment
		(start 5.461 -183.896)
		(end 6.472936 -182.884064)
		(width 0.2794)
		(layer "F.Cu")
		(net "PCA9555_MB0_A1")
	)
	(segment
		(start 4.21005 -184.658)
		(end 5.461 -184.658)
		(width 0.2794)
		(layer "F.Cu")
		(net "PCA9555_MB0_A1")
	)
	(segment
		(start 4.21005 -183.642)
		(end 4.21005 -184.658)
		(width 0.2794)
		(layer "F.Cu")
		(net "PCA9555_MB0_A1")
	)
	(segment
		(start 5.461 -184.658)
		(end 5.461 -183.896)
		(width 0.2794)
		(layer "F.Cu")
		(net "PCA9555_MB0_A1")
	)
	(via
		(at 5.461 -184.658)
		(size 0.762)
		(drill 0.381)
		(layers "F.Cu" "B.Cu")
		(net "PCA9555_MB0_A1")
	)
	(segment
		(start 39.14013 -254.609092)
		(end 39.606982 -255.075944)
		(width 0.2794)
		(layer "F.Cu")
		(net "FAN_0_ON")
	)
	(segment
		(start 37.87902 -254.609092)
		(end 39.14013 -254.609092)
		(width 0.2794)
		(layer "F.Cu")
		(net "FAN_0_ON")
	)
	(segment
		(start 39.606982 -255.075944)
		(end 39.606982 -255.143)
		(width 0.2794)
		(layer "F.Cu")
		(net "FAN_0_ON")
	)
	(segment
		(start 37.396166 -255.091946)
		(end 37.87902 -254.609092)
		(width 0.2794)
		(layer "F.Cu")
		(net "FAN_0_ON")
	)
	(via
		(at 41.118536 -260.616192)
		(size 0.508)
		(drill 0.254)
		(layers "F.Cu" "B.Cu")
		(net "FAN_0_ON")
	)
	(via
		(at 37.396166 -255.091946)
		(size 0.508)
		(drill 0.254)
		(layers "F.Cu" "B.Cu")
		(net "FAN_0_ON")
	)
	(segment
		(start 41.416732 -261.340346)
		(end 41.416732 -262.054848)
		(width 0.1016)
		(layer "B.Cu")
		(net "FAN_0_ON")
	)
	(segment
		(start 41.118536 -260.616192)
		(end 41.416732 -261.340346)
		(width 0.1016)
		(layer "B.Cu")
		(net "FAN_0_ON")
	)
	(segment
		(start 41.118536 -260.616192)
		(end 39.654988 -260.616192)
		(width 0.2286)
		(layer "In2.Cu")
		(net "FAN_0_ON")
	)
	(segment
		(start 39.654988 -260.616192)
		(end 39.243 -260.204204)
		(width 0.2286)
		(layer "In2.Cu")
		(net "FAN_0_ON")
	)
	(segment
		(start 38.768782 -256.75463)
		(end 38.768782 -256.464562)
		(width 0.2286)
		(layer "In2.Cu")
		(net "FAN_0_ON")
	)
	(segment
		(start 38.768782 -256.464562)
		(end 37.396166 -255.091946)
		(width 0.2286)
		(layer "In2.Cu")
		(net "FAN_0_ON")
	)
	(segment
		(start 39.243 -257.228848)
		(end 38.768782 -256.75463)
		(width 0.2286)
		(layer "In2.Cu")
		(net "FAN_0_ON")
	)
	(segment
		(start 39.243 -260.204204)
		(end 39.243 -257.228848)
		(width 0.2286)
		(layer "In2.Cu")
		(net "FAN_0_ON")
	)
	(segment
		(start 44.68495 -187.96)
		(end 43.79595 -188.849)
		(width 0.2794)
		(layer "F.Cu")
		(net "PD_FAN_BUFF_INPUT_U337E")
	)
	(segment
		(start 40.11295 -189.484)
		(end 39.243 -189.484)
		(width 0.2794)
		(layer "F.Cu")
		(net "PD_FAN_BUFF_INPUT_U337E")
	)
	(segment
		(start 41.63695 -187.96)
		(end 40.11295 -189.484)
		(width 0.2794)
		(layer "F.Cu")
		(net "PD_FAN_BUFF_INPUT_U337E")
	)
	(segment
		(start 42.46626 -188.849)
		(end 41.63695 -188.01969)
		(width 0.2794)
		(layer "F.Cu")
		(net "PD_FAN_BUFF_INPUT_U337E")
	)
	(segment
		(start 43.561 -188.849)
		(end 42.46626 -188.849)
		(width 0.2794)
		(layer "F.Cu")
		(net "PD_FAN_BUFF_INPUT_U337E")
	)
	(segment
		(start 41.63695 -188.01969)
		(end 41.63695 -187.96)
		(width 0.2794)
		(layer "F.Cu")
		(net "PD_FAN_BUFF_INPUT_U337E")
	)
	(segment
		(start 43.79595 -188.849)
		(end 43.561 -188.849)
		(width 0.2794)
		(layer "F.Cu")
		(net "PD_FAN_BUFF_INPUT_U337E")
	)
	(via
		(at 43.561 -188.849)
		(size 0.508)
		(drill 0.254)
		(layers "F.Cu" "B.Cu")
		(net "PD_FAN_BUFF_INPUT_U337E")
	)
	(segment
		(start 13.208 -181.584092)
		(end 16.705072 -181.584092)
		(width 0.2794)
		(layer "F.Cu")
		(net "PCA9555_MB0_A0")
	)
	(segment
		(start 20.42795 -181.61)
		(end 20.42795 -181.588664)
		(width 0.2794)
		(layer "F.Cu")
		(net "PCA9555_MB0_A0")
	)
	(segment
		(start 18.01495 -181.61)
		(end 16.73098 -181.61)
		(width 0.2794)
		(layer "F.Cu")
		(net "PCA9555_MB0_A0")
	)
	(segment
		(start 19.776186 -180.9369)
		(end 18.536158 -180.9369)
		(width 0.2794)
		(layer "F.Cu")
		(net "PCA9555_MB0_A0")
	)
	(segment
		(start 20.42795 -181.588664)
		(end 19.776186 -180.9369)
		(width 0.2794)
		(layer "F.Cu")
		(net "PCA9555_MB0_A0")
	)
	(segment
		(start 16.705072 -181.584092)
		(end 16.73098 -181.61)
		(width 0.2794)
		(layer "F.Cu")
		(net "PCA9555_MB0_A0")
	)
	(segment
		(start 18.536158 -180.9369)
		(end 18.01495 -181.458108)
		(width 0.2794)
		(layer "F.Cu")
		(net "PCA9555_MB0_A0")
	)
	(segment
		(start 18.01495 -181.458108)
		(end 18.01495 -181.61)
		(width 0.2794)
		(layer "F.Cu")
		(net "PCA9555_MB0_A0")
	)
	(via
		(at 16.73098 -181.61)
		(size 0.762)
		(drill 0.381)
		(layers "F.Cu" "B.Cu")
		(net "PCA9555_MB0_A0")
	)
	(segment
		(start 13.926058 -205.7146)
		(end 13.926058 -205.74)
		(width 0.2794)
		(layer "F.Cu")
		(net "FAN_6_FAIL_R_LED_N")
	)
	(segment
		(start 11.9126 -204.851)
		(end 12.4968 -204.851)
		(width 0.2794)
		(layer "F.Cu")
		(net "FAN_6_FAIL_R_LED_N")
	)
	(segment
		(start 13.3604 -205.7146)
		(end 13.926058 -205.7146)
		(width 0.2794)
		(layer "F.Cu")
		(net "FAN_6_FAIL_R_LED_N")
	)
	(segment
		(start 13.926058 -205.7146)
		(end 13.95095 -205.689708)
		(width 0.2794)
		(layer "F.Cu")
		(net "FAN_6_FAIL_R_LED_N")
	)
	(segment
		(start 9.7536 -207.01)
		(end 11.9126 -204.851)
		(width 0.2794)
		(layer "F.Cu")
		(net "FAN_6_FAIL_R_LED_N")
	)
	(segment
		(start 12.4968 -204.851)
		(end 13.3604 -205.7146)
		(width 0.2794)
		(layer "F.Cu")
		(net "FAN_6_FAIL_R_LED_N")
	)
	(segment
		(start 13.95095 -205.689708)
		(end 13.95095 -204.47)
		(width 0.2794)
		(layer "F.Cu")
		(net "FAN_6_FAIL_R_LED_N")
	)
	(segment
		(start 8.700008 -207.01)
		(end 9.7536 -207.01)
		(width 0.2794)
		(layer "F.Cu")
		(net "FAN_6_FAIL_R_LED_N")
	)
	(via
		(at 11.9126 -204.851)
		(size 0.762)
		(drill 0.381)
		(layers "F.Cu" "B.Cu")
		(net "FAN_6_FAIL_R_LED_N")
	)
	(segment
		(start 11.811 -208.435956)
		(end 10.004044 -208.435956)
		(width 0.2794)
		(layer "F.Cu")
		(net "FAN_6_OK_R_LED_N")
	)
	(segment
		(start 9.430004 -209.009996)
		(end 8.700008 -209.009996)
		(width 0.2794)
		(layer "F.Cu")
		(net "FAN_6_OK_R_LED_N")
	)
	(segment
		(start 13.926058 -208.435956)
		(end 11.811 -208.435956)
		(width 0.2794)
		(layer "F.Cu")
		(net "FAN_6_OK_R_LED_N")
	)
	(segment
		(start 13.926058 -208.435956)
		(end 13.95095 -208.411064)
		(width 0.2794)
		(layer "F.Cu")
		(net "FAN_6_OK_R_LED_N")
	)
	(segment
		(start 13.95095 -208.411064)
		(end 13.95095 -207.264)
		(width 0.2794)
		(layer "F.Cu")
		(net "FAN_6_OK_R_LED_N")
	)
	(segment
		(start 10.004044 -208.435956)
		(end 9.430004 -209.009996)
		(width 0.2794)
		(layer "F.Cu")
		(net "FAN_6_OK_R_LED_N")
	)
	(via
		(at 11.811 -208.435956)
		(size 0.762)
		(drill 0.381)
		(layers "F.Cu" "B.Cu")
		(net "FAN_6_OK_R_LED_N")
	)
	(segment
		(start 13.35405 -73.172828)
		(end 13.067284 -72.886062)
		(width 0.2794)
		(layer "F.Cu")
		(net "FAN_5_FAULT_R")
	)
	(segment
		(start 14.351 -73.51395)
		(end 14.351 -72.86879)
		(width 0.2794)
		(layer "F.Cu")
		(net "FAN_5_FAULT_R")
	)
	(segment
		(start 13.35405 -73.406)
		(end 13.35405 -73.172828)
		(width 0.2794)
		(layer "F.Cu")
		(net "FAN_5_FAULT_R")
	)
	(segment
		(start 13.067284 -72.886062)
		(end 13.067284 -72.221344)
		(width 0.2794)
		(layer "F.Cu")
		(net "FAN_5_FAULT_R")
	)
	(segment
		(start 13.574014 -72.091804)
		(end 13.196824 -72.091804)
		(width 0.2794)
		(layer "F.Cu")
		(net "FAN_5_FAULT_R")
	)
	(segment
		(start 13.067284 -72.221344)
		(end 13.196824 -72.091804)
		(width 0.2794)
		(layer "F.Cu")
		(net "FAN_5_FAULT_R")
	)
	(segment
		(start 14.351 -72.86879)
		(end 13.574014 -72.091804)
		(width 0.2794)
		(layer "F.Cu")
		(net "FAN_5_FAULT_R")
	)
	(via
		(at 13.196824 -72.091804)
		(size 0.762)
		(drill 0.381)
		(layers "F.Cu" "B.Cu")
		(net "FAN_5_FAULT_R")
	)
	(segment
		(start 15.60068 -76.02474)
		(end 15.60068 -75.56373)
		(width 0.2794)
		(layer "F.Cu")
		(net "FAN_5_FAULT")
	)
	(segment
		(start 15.60068 -75.56373)
		(end 14.351 -74.31405)
		(width 0.2794)
		(layer "F.Cu")
		(net "FAN_5_FAULT")
	)
	(via
		(at 15.60068 -76.02474)
		(size 0.508)
		(drill 0.254)
		(layers "F.Cu" "B.Cu")
		(net "FAN_5_FAULT")
	)
	(segment
		(start 15.60068 -76.02474)
		(end 15.25524 -76.858876)
		(width 0.1016)
		(layer "B.Cu")
		(net "FAN_5_FAULT")
	)
	(segment
		(start 15.25524 -76.858876)
		(end 15.25524 -77.45476)
		(width 0.1016)
		(layer "B.Cu")
		(net "FAN_5_FAULT")
	)
	(via
		(at 10.287 -75.057)
		(size 0.762)
		(drill 0.254)
		(layers "F.Cu" "B.Cu")
		(net "FAN_5_TEMP")
	)
	(segment
		(start 10.445242 -74.898758)
		(end 10.287 -75.057)
		(width 0.2794)
		(layer "B.Cu")
		(net "FAN_5_TEMP")
	)
	(segment
		(start 12.455144 -76.886562)
		(end 12.455144 -77.45476)
		(width 0.1016)
		(layer "B.Cu")
		(net "FAN_5_TEMP")
	)
	(segment
		(start 10.438638 -75.283822)
		(end 11.687048 -76.118466)
		(width 0.2794)
		(layer "B.Cu")
		(net "FAN_5_TEMP")
	)
	(segment
		(start 11.687048 -76.118466)
		(end 12.455144 -76.886562)
		(width 0.1016)
		(layer "B.Cu")
		(net "FAN_5_TEMP")
	)
	(segment
		(start 10.445242 -74.362818)
		(end 9.413494 -74.362818)
		(width 0.2794)
		(layer "B.Cu")
		(net "FAN_5_TEMP")
	)
	(segment
		(start 10.445242 -74.362818)
		(end 10.445242 -74.898758)
		(width 0.2794)
		(layer "B.Cu")
		(net "FAN_5_TEMP")
	)
	(segment
		(start 10.287 -75.057)
		(end 10.438638 -75.283822)
		(width 0.2794)
		(layer "B.Cu")
		(net "FAN_5_TEMP")
	)
	(via
		(at 16.398494 -75.805284)
		(size 0.762)
		(drill 0.254)
		(layers "F.Cu" "B.Cu")
		(net "FAN_5_SS")
	)
	(segment
		(start 15.65529 -76.969112)
		(end 15.65529 -77.45476)
		(width 0.1016)
		(layer "B.Cu")
		(net "FAN_5_SS")
	)
	(segment
		(start 17.287494 -74.916284)
		(end 16.398494 -75.805284)
		(width 0.2794)
		(layer "B.Cu")
		(net "FAN_5_SS")
	)
	(segment
		(start 16.398494 -75.805284)
		(end 16.398494 -76.018644)
		(width 0.1016)
		(layer "B.Cu")
		(net "FAN_5_SS")
	)
	(segment
		(start 15.801848 -76.61529)
		(end 15.65529 -76.969112)
		(width 0.1016)
		(layer "B.Cu")
		(net "FAN_5_SS")
	)
	(segment
		(start 16.398494 -76.018644)
		(end 15.801848 -76.61529)
		(width 0.1016)
		(layer "B.Cu")
		(net "FAN_5_SS")
	)
	(segment
		(start 17.287494 -74.371962)
		(end 17.287494 -74.916284)
		(width 0.2794)
		(layer "B.Cu")
		(net "FAN_5_SS")
	)
	(via
		(at 14.58722 -75.82408)
		(size 0.762)
		(drill 0.254)
		(layers "F.Cu" "B.Cu")
		(net "FAN_5_CLREF")
	)
	(segment
		(start 15.113 -74.371962)
		(end 15.113 -74.802746)
		(width 0.2794)
		(layer "B.Cu")
		(net "FAN_5_CLREF")
	)
	(segment
		(start 14.45514 -75.95616)
		(end 14.45514 -77.45476)
		(width 0.1016)
		(layer "B.Cu")
		(net "FAN_5_CLREF")
	)
	(segment
		(start 14.097 -74.371962)
		(end 15.113 -74.371962)
		(width 0.2794)
		(layer "B.Cu")
		(net "FAN_5_CLREF")
	)
	(segment
		(start 14.93774 -74.978006)
		(end 14.58722 -75.82408)
		(width 0.1016)
		(layer "B.Cu")
		(net "FAN_5_CLREF")
	)
	(segment
		(start 14.58722 -75.82408)
		(end 14.45514 -75.95616)
		(width 0.1016)
		(layer "B.Cu")
		(net "FAN_5_CLREF")
	)
	(segment
		(start 15.113 -74.802746)
		(end 14.93774 -74.978006)
		(width 0.2794)
		(layer "B.Cu")
		(net "FAN_5_CLREF")
	)
	(segment
		(start 11.076686 -77.1271)
		(end 10.7569 -76.807314)
		(width 0.2794)
		(layer "F.Cu")
		(net "FAN_5_P3V_R")
	)
	(segment
		(start 13.208 -75.826112)
		(end 11.907012 -77.1271)
		(width 0.2794)
		(layer "F.Cu")
		(net "FAN_5_P3V_R")
	)
	(segment
		(start 12.446 -73.51395)
		(end 12.55395 -73.406)
		(width 0.2794)
		(layer "F.Cu")
		(net "FAN_5_P3V_R")
	)
	(segment
		(start 11.454638 -73.51395)
		(end 11.557 -73.51395)
		(width 0.2794)
		(layer "F.Cu")
		(net "FAN_5_P3V_R")
	)
	(segment
		(start 11.907012 -77.1271)
		(end 11.076686 -77.1271)
		(width 0.2794)
		(layer "F.Cu")
		(net "FAN_5_P3V_R")
	)
	(segment
		(start 11.557 -73.51395)
		(end 12.446 -73.51395)
		(width 0.2794)
		(layer "F.Cu")
		(net "FAN_5_P3V_R")
	)
	(segment
		(start 10.9728 -75.369674)
		(end 10.9728 -73.995788)
		(width 0.2794)
		(layer "F.Cu")
		(net "FAN_5_P3V_R")
	)
	(segment
		(start 10.7569 -75.585574)
		(end 10.9728 -75.369674)
		(width 0.2794)
		(layer "F.Cu")
		(net "FAN_5_P3V_R")
	)
	(segment
		(start 10.7569 -76.807314)
		(end 10.7569 -75.585574)
		(width 0.2794)
		(layer "F.Cu")
		(net "FAN_5_P3V_R")
	)
	(segment
		(start 10.9728 -73.995788)
		(end 11.454638 -73.51395)
		(width 0.2794)
		(layer "F.Cu")
		(net "FAN_5_P3V_R")
	)
	(via
		(at 13.208 -75.826112)
		(size 0.762)
		(drill 0.254)
		(layers "F.Cu" "B.Cu")
		(net "FAN_5_P3V_R")
	)
	(segment
		(start 13.208 -75.826112)
		(end 13.04671 -75.987402)
		(width 0.1016)
		(layer "B.Cu")
		(net "FAN_5_P3V_R")
	)
	(segment
		(start 13.04671 -76.559664)
		(end 13.255244 -77.063092)
		(width 0.1016)
		(layer "B.Cu")
		(net "FAN_5_P3V_R")
	)
	(segment
		(start 13.208 -75.69835)
		(end 12.446 -74.93635)
		(width 0.2794)
		(layer "B.Cu")
		(net "FAN_5_P3V_R")
	)
	(segment
		(start 13.04671 -75.987402)
		(end 13.04671 -76.559664)
		(width 0.1016)
		(layer "B.Cu")
		(net "FAN_5_P3V_R")
	)
	(segment
		(start 12.446 -74.93635)
		(end 12.446 -74.36485)
		(width 0.2794)
		(layer "B.Cu")
		(net "FAN_5_P3V_R")
	)
	(segment
		(start 13.208 -75.826112)
		(end 13.208 -75.69835)
		(width 0.2794)
		(layer "B.Cu")
		(net "FAN_5_P3V_R")
	)
	(segment
		(start 13.255244 -77.063092)
		(end 13.255244 -77.45476)
		(width 0.1016)
		(layer "B.Cu")
		(net "FAN_5_P3V_R")
	)
	(via
		(at 12.080494 -75.622912)
		(size 0.6604)
		(drill 0.3302)
		(layers "F.Cu" "B.Cu")
		(net "FAN_5_P5V")
	)
	(segment
		(start 12.855194 -76.93152)
		(end 12.855194 -77.45476)
		(width 0.1016)
		(layer "B.Cu")
		(net "FAN_5_P5V")
	)
	(segment
		(start 12.170156 -75.65009)
		(end 12.855194 -76.93152)
		(width 0.1016)
		(layer "B.Cu")
		(net "FAN_5_P5V")
	)
	(segment
		(start 11.461242 -74.362818)
		(end 11.461242 -75.00366)
		(width 0.2794)
		(layer "B.Cu")
		(net "FAN_5_P5V")
	)
	(segment
		(start 12.080494 -75.622912)
		(end 12.170156 -75.65009)
		(width 0.1016)
		(layer "B.Cu")
		(net "FAN_5_P5V")
	)
	(segment
		(start 11.461242 -75.00366)
		(end 12.080494 -75.622912)
		(width 0.2794)
		(layer "B.Cu")
		(net "FAN_5_P5V")
	)
	(segment
		(start 13.843 -110.80115)
		(end 14.1732 -110.47095)
		(width 0.2794)
		(layer "F.Cu")
		(net "FAN_5_FAIL_R_LED_N")
	)
	(segment
		(start 14.1732 -110.47095)
		(end 15.113 -110.47095)
		(width 0.2794)
		(layer "F.Cu")
		(net "FAN_5_FAIL_R_LED_N")
	)
	(segment
		(start 13.814044 -112.706912)
		(end 11.811 -114.709956)
		(width 0.2794)
		(layer "F.Cu")
		(net "FAN_5_FAIL_R_LED_N")
	)
	(segment
		(start 11.811 -114.709956)
		(end 8.700008 -114.709956)
		(width 0.2794)
		(layer "F.Cu")
		(net "FAN_5_FAIL_R_LED_N")
	)
	(segment
		(start 13.926058 -112.706912)
		(end 13.843 -112.623854)
		(width 0.2794)
		(layer "F.Cu")
		(net "FAN_5_FAIL_R_LED_N")
	)
	(segment
		(start 13.926058 -112.706912)
		(end 13.814044 -112.706912)
		(width 0.2794)
		(layer "F.Cu")
		(net "FAN_5_FAIL_R_LED_N")
	)
	(segment
		(start 13.843 -112.623854)
		(end 13.843 -110.80115)
		(width 0.2794)
		(layer "F.Cu")
		(net "FAN_5_FAIL_R_LED_N")
	)
	(via
		(at 11.811 -114.709956)
		(size 0.762)
		(drill 0.381)
		(layers "F.Cu" "B.Cu")
		(net "FAN_5_FAIL_R_LED_N")
	)
	(segment
		(start 13.843 -114.35715)
		(end 14.1732 -114.02695)
		(width 0.2794)
		(layer "F.Cu")
		(net "FAN_5_OK_R_LED_N")
	)
	(segment
		(start 9.274048 -116.135912)
		(end 12.4968 -116.135912)
		(width 0.2794)
		(layer "F.Cu")
		(net "FAN_5_OK_R_LED_N")
	)
	(segment
		(start 14.1732 -114.02695)
		(end 15.113 -114.02695)
		(width 0.2794)
		(layer "F.Cu")
		(net "FAN_5_OK_R_LED_N")
	)
	(segment
		(start 13.843 -116.052854)
		(end 13.843 -114.35715)
		(width 0.2794)
		(layer "F.Cu")
		(net "FAN_5_OK_R_LED_N")
	)
	(segment
		(start 8.700008 -116.709952)
		(end 9.274048 -116.135912)
		(width 0.2794)
		(layer "F.Cu")
		(net "FAN_5_OK_R_LED_N")
	)
	(segment
		(start 13.926058 -116.135912)
		(end 13.843 -116.052854)
		(width 0.2794)
		(layer "F.Cu")
		(net "FAN_5_OK_R_LED_N")
	)
	(segment
		(start 12.4968 -116.135912)
		(end 13.926058 -116.135912)
		(width 0.2794)
		(layer "F.Cu")
		(net "FAN_5_OK_R_LED_N")
	)
	(via
		(at 12.4968 -116.135912)
		(size 0.762)
		(drill 0.381)
		(layers "F.Cu" "B.Cu")
		(net "FAN_5_OK_R_LED_N")
	)
	(via
		(at 18.209006 -76.708)
		(size 0.762)
		(drill 0.254)
		(layers "F.Cu" "B.Cu")
		(net "FAN_5_CS")
	)
	(segment
		(start 16.455136 -77.34427)
		(end 16.455136 -77.45476)
		(width 0.1016)
		(layer "B.Cu")
		(net "FAN_5_CS")
	)
	(segment
		(start 19.573494 -74.371962)
		(end 19.573494 -75.343512)
		(width 0.2794)
		(layer "B.Cu")
		(net "FAN_5_CS")
	)
	(segment
		(start 17.28724 -76.708)
		(end 17.201896 -76.793344)
		(width 0.2794)
		(layer "B.Cu")
		(net "FAN_5_CS")
	)
	(segment
		(start 17.201896 -76.793344)
		(end 16.612108 -77.187298)
		(width 0.1016)
		(layer "B.Cu")
		(net "FAN_5_CS")
	)
	(segment
		(start 18.209006 -76.708)
		(end 17.28724 -76.708)
		(width 0.2794)
		(layer "B.Cu")
		(net "FAN_5_CS")
	)
	(segment
		(start 19.573494 -75.343512)
		(end 18.209006 -76.708)
		(width 0.2794)
		(layer "B.Cu")
		(net "FAN_5_CS")
	)
	(segment
		(start 16.612108 -77.187298)
		(end 16.455136 -77.34427)
		(width 0.1016)
		(layer "B.Cu")
		(net "FAN_5_CS")
	)
	(segment
		(start 15.21079 -75.517502)
		(end 15.72641 -75.173332)
		(width 0.1016)
		(layer "B.Cu")
		(net "FAN_5_TIMER")
	)
	(segment
		(start 15.72641 -75.173332)
		(end 16.016478 -74.979784)
		(width 0.1016)
		(layer "B.Cu")
		(net "FAN_5_TIMER")
	)
	(segment
		(start 14.85519 -77.45476)
		(end 14.85519 -76.378816)
		(width 0.1016)
		(layer "B.Cu")
		(net "FAN_5_TIMER")
	)
	(segment
		(start 16.129 -74.867262)
		(end 16.129 -74.371962)
		(width 0.2794)
		(layer "B.Cu")
		(net "FAN_5_TIMER")
	)
	(segment
		(start 14.85519 -76.378816)
		(end 15.21079 -75.517502)
		(width 0.1016)
		(layer "B.Cu")
		(net "FAN_5_TIMER")
	)
	(segment
		(start 16.016478 -74.979784)
		(end 16.129 -74.867262)
		(width 0.2794)
		(layer "B.Cu")
		(net "FAN_5_TIMER")
	)
	(via
		(at 17.78 -75.819)
		(size 0.6604)
		(drill 0.3302)
		(layers "F.Cu" "B.Cu")
		(net "FAN_5_IMON")
	)
	(segment
		(start 17.038828 -76.126086)
		(end 17.78 -75.819)
		(width 0.2794)
		(layer "B.Cu")
		(net "FAN_5_IMON")
	)
	(segment
		(start 18.430494 -75.168506)
		(end 17.78 -75.819)
		(width 0.2794)
		(layer "B.Cu")
		(net "FAN_5_IMON")
	)
	(segment
		(start 16.05534 -77.45476)
		(end 16.05534 -76.997814)
		(width 0.1016)
		(layer "B.Cu")
		(net "FAN_5_IMON")
	)
	(segment
		(start 16.05534 -76.997814)
		(end 16.51 -76.543154)
		(width 0.1016)
		(layer "B.Cu")
		(net "FAN_5_IMON")
	)
	(segment
		(start 18.430494 -74.371962)
		(end 18.430494 -75.168506)
		(width 0.2794)
		(layer "B.Cu")
		(net "FAN_5_IMON")
	)
	(segment
		(start 16.51 -76.543154)
		(end 16.62176 -76.543154)
		(width 0.2794)
		(layer "B.Cu")
		(net "FAN_5_IMON")
	)
	(segment
		(start 16.62176 -76.543154)
		(end 17.038828 -76.126086)
		(width 0.2794)
		(layer "B.Cu")
		(net "FAN_5_IMON")
	)
	(segment
		(start 11.557 -74.31405)
		(end 12.446 -74.31405)
		(width 0.2794)
		(layer "F.Cu")
		(net "FAN_5_MODE")
	)
	(segment
		(start 11.303 -76.581)
		(end 11.557 -76.327)
		(width 0.2794)
		(layer "F.Cu")
		(net "FAN_5_MODE")
	)
	(segment
		(start 11.557 -75.7809)
		(end 11.557 -74.31405)
		(width 0.2794)
		(layer "F.Cu")
		(net "FAN_5_MODE")
	)
	(segment
		(start 12.446 -74.31405)
		(end 12.55395 -74.422)
		(width 0.2794)
		(layer "F.Cu")
		(net "FAN_5_MODE")
	)
	(segment
		(start 11.557 -76.327)
		(end 11.557 -75.7809)
		(width 0.2794)
		(layer "F.Cu")
		(net "FAN_5_MODE")
	)
	(via
		(at 11.557 -75.7809)
		(size 0.762)
		(drill 0.381)
		(layers "F.Cu" "B.Cu")
		(net "FAN_5_MODE")
	)
	(via
		(at 11.303 -76.581)
		(size 0.508)
		(drill 0.254)
		(layers "F.Cu" "B.Cu")
		(net "FAN_5_MODE")
	)
	(segment
		(start 11.303 -76.702412)
		(end 11.952478 -77.35189)
		(width 0.2794)
		(layer "B.Cu")
		(net "FAN_5_MODE")
	)
	(segment
		(start 11.303 -76.581)
		(end 11.303 -76.702412)
		(width 0.2794)
		(layer "B.Cu")
		(net "FAN_5_MODE")
	)
	(segment
		(start 11.952478 -77.35189)
		(end 12.055348 -77.45476)
		(width 0.1016)
		(layer "B.Cu")
		(net "FAN_5_MODE")
	)
	(segment
		(start 12.9286 -302.2981)
		(end 7.688072 -302.2981)
		(width 0.2794)
		(layer "F.Cu")
		(net "FAN_7_TACH_OL_D")
	)
	(segment
		(start 14.285722 -303.513236)
		(end 14.285722 -302.4251)
		(width 0.2794)
		(layer "F.Cu")
		(net "FAN_7_TACH_OL_D")
	)
	(segment
		(start 14.158722 -302.2981)
		(end 12.9286 -302.2981)
		(width 0.2794)
		(layer "F.Cu")
		(net "FAN_7_TACH_OL_D")
	)
	(segment
		(start 7.688072 -302.2981)
		(end 6.700012 -301.31004)
		(width 0.2794)
		(layer "F.Cu")
		(net "FAN_7_TACH_OL_D")
	)
	(segment
		(start 14.224 -304.121058)
		(end 14.224 -303.574958)
		(width 0.2794)
		(layer "F.Cu")
		(net "FAN_7_TACH_OL_D")
	)
	(segment
		(start 14.285722 -302.4251)
		(end 14.158722 -302.2981)
		(width 0.2794)
		(layer "F.Cu")
		(net "FAN_7_TACH_OL_D")
	)
	(segment
		(start 14.224 -303.574958)
		(end 14.285722 -303.513236)
		(width 0.2794)
		(layer "F.Cu")
		(net "FAN_7_TACH_OL_D")
	)
	(via
		(at 12.9286 -302.2981)
		(size 0.762)
		(drill 0.381)
		(layers "F.Cu" "B.Cu")
		(net "FAN_7_TACH_OL_D")
	)
	(segment
		(start 37.73805 -293.624)
		(end 38.9763 -293.624)
		(width 0.2794)
		(layer "F.Cu")
		(net "FAN_0_FAIL_R_LED_N")
	)
	(segment
		(start 38.9763 -293.624)
		(end 39.2303 -293.37)
		(width 0.2794)
		(layer "F.Cu")
		(net "FAN_0_FAIL_R_LED_N")
	)
	(segment
		(start 37.73805 -292.950392)
		(end 37.73805 -293.624)
		(width 0.2794)
		(layer "F.Cu")
		(net "FAN_0_FAIL_R_LED_N")
	)
	(segment
		(start 42.93997 -293.37)
		(end 42.999914 -293.310056)
		(width 0.2794)
		(layer "F.Cu")
		(net "FAN_0_FAIL_R_LED_N")
	)
	(segment
		(start 37.762942 -292.354)
		(end 37.762942 -292.9255)
		(width 0.2794)
		(layer "F.Cu")
		(net "FAN_0_FAIL_R_LED_N")
	)
	(segment
		(start 39.878 -293.37)
		(end 42.93997 -293.37)
		(width 0.2794)
		(layer "F.Cu")
		(net "FAN_0_FAIL_R_LED_N")
	)
	(segment
		(start 37.762942 -292.9255)
		(end 37.73805 -292.950392)
		(width 0.2794)
		(layer "F.Cu")
		(net "FAN_0_FAIL_R_LED_N")
	)
	(segment
		(start 39.2303 -293.37)
		(end 39.878 -293.37)
		(width 0.2794)
		(layer "F.Cu")
		(net "FAN_0_FAIL_R_LED_N")
	)
	(via
		(at 39.878 -293.37)
		(size 0.762)
		(drill 0.381)
		(layers "F.Cu" "B.Cu")
		(net "FAN_0_FAIL_R_LED_N")
	)
	(segment
		(start 13.834872 -286.73679)
		(end 13.834872 -286.6771)
		(width 0.2794)
		(layer "F.Cu")
		(net "FAN_7_PWM_OL_R")
	)
	(segment
		(start 17.58188 -286.004)
		(end 16.51508 -286.004)
		(width 0.2794)
		(layer "F.Cu")
		(net "FAN_7_PWM_OL_R")
	)
	(segment
		(start 14.295882 -287.1978)
		(end 13.834872 -286.73679)
		(width 0.2794)
		(layer "F.Cu")
		(net "FAN_7_PWM_OL_R")
	)
	(segment
		(start 16.51508 -286.004)
		(end 15.993872 -286.525208)
		(width 0.2794)
		(layer "F.Cu")
		(net "FAN_7_PWM_OL_R")
	)
	(segment
		(start 11.201908 -289.310064)
		(end 8.700008 -289.310064)
		(width 0.2794)
		(layer "F.Cu")
		(net "FAN_7_PWM_OL_R")
	)
	(segment
		(start 11.787886 -288.724086)
		(end 11.201908 -289.310064)
		(width 0.2794)
		(layer "F.Cu")
		(net "FAN_7_PWM_OL_R")
	)
	(segment
		(start 13.834872 -286.6771)
		(end 11.787886 -288.724086)
		(width 0.2794)
		(layer "F.Cu")
		(net "FAN_7_PWM_OL_R")
	)
	(segment
		(start 15.473172 -287.1978)
		(end 14.295882 -287.1978)
		(width 0.2794)
		(layer "F.Cu")
		(net "FAN_7_PWM_OL_R")
	)
	(segment
		(start 15.993872 -286.6771)
		(end 15.473172 -287.1978)
		(width 0.2794)
		(layer "F.Cu")
		(net "FAN_7_PWM_OL_R")
	)
	(segment
		(start 15.993872 -286.525208)
		(end 15.993872 -286.6771)
		(width 0.2794)
		(layer "F.Cu")
		(net "FAN_7_PWM_OL_R")
	)
	(segment
		(start 18.25498 -286.6771)
		(end 17.58188 -286.004)
		(width 0.2794)
		(layer "F.Cu")
		(net "FAN_7_PWM_OL_R")
	)
	(via
		(at 11.787886 -288.724086)
		(size 0.762)
		(drill 0.381)
		(layers "F.Cu" "B.Cu")
		(net "FAN_7_PWM_OL_R")
	)
	(segment
		(start 13.6906 -290.262564)
		(end 7.652512 -290.262564)
		(width 0.2794)
		(layer "F.Cu")
		(net "FAN_7_TACH_IL_D")
	)
	(segment
		(start 7.652512 -290.262564)
		(end 6.700012 -289.310064)
		(width 0.2794)
		(layer "F.Cu")
		(net "FAN_7_TACH_IL_D")
	)
	(segment
		(start 14.95298 -290.2331)
		(end 14.923516 -290.262564)
		(width 0.2794)
		(layer "F.Cu")
		(net "FAN_7_TACH_IL_D")
	)
	(segment
		(start 14.923516 -290.262564)
		(end 13.6906 -290.262564)
		(width 0.2794)
		(layer "F.Cu")
		(net "FAN_7_TACH_IL_D")
	)
	(segment
		(start 14.95298 -290.2331)
		(end 14.95298 -289.249358)
		(width 0.2794)
		(layer "F.Cu")
		(net "FAN_7_TACH_IL_D")
	)
	(segment
		(start 14.95298 -289.249358)
		(end 14.285722 -288.5821)
		(width 0.2794)
		(layer "F.Cu")
		(net "FAN_7_TACH_IL_D")
	)
	(via
		(at 13.6906 -290.262564)
		(size 0.762)
		(drill 0.381)
		(layers "F.Cu" "B.Cu")
		(net "FAN_7_TACH_IL_D")
	)
	(segment
		(start 6.700012 -291.31006)
		(end 7.655052 -292.2651)
		(width 0.2794)
		(layer "F.Cu")
		(net "FAN_7_PWM_IL_R")
	)
	(segment
		(start 16.120872 -291.229796)
		(end 16.120872 -291.351208)
		(width 0.2794)
		(layer "F.Cu")
		(net "FAN_7_PWM_IL_R")
	)
	(segment
		(start 18.244058 -291.264594)
		(end 17.809464 -290.83)
		(width 0.2794)
		(layer "F.Cu")
		(net "FAN_7_PWM_IL_R")
	)
	(segment
		(start 7.655052 -292.2651)
		(end 11.049 -292.2651)
		(width 0.2794)
		(layer "F.Cu")
		(net "FAN_7_PWM_IL_R")
	)
	(segment
		(start 17.809464 -290.83)
		(end 16.64208 -290.83)
		(width 0.2794)
		(layer "F.Cu")
		(net "FAN_7_PWM_IL_R")
	)
	(segment
		(start 16.120872 -291.5031)
		(end 16.120872 -291.351208)
		(width 0.2794)
		(layer "F.Cu")
		(net "FAN_7_PWM_IL_R")
	)
	(segment
		(start 11.049 -292.2651)
		(end 11.811 -291.5031)
		(width 0.2794)
		(layer "F.Cu")
		(net "FAN_7_PWM_IL_R")
	)
	(segment
		(start 14.51991 -290.9189)
		(end 15.809976 -290.9189)
		(width 0.2794)
		(layer "F.Cu")
		(net "FAN_7_PWM_IL_R")
	)
	(segment
		(start 16.64208 -290.83)
		(end 16.120872 -291.351208)
		(width 0.2794)
		(layer "F.Cu")
		(net "FAN_7_PWM_IL_R")
	)
	(segment
		(start 18.244058 -291.465)
		(end 18.244058 -291.264594)
		(width 0.2794)
		(layer "F.Cu")
		(net "FAN_7_PWM_IL_R")
	)
	(segment
		(start 13.961872 -291.44341)
		(end 14.422882 -290.9824)
		(width 0.2794)
		(layer "F.Cu")
		(net "FAN_7_PWM_IL_R")
	)
	(segment
		(start 15.809976 -290.9189)
		(end 16.120872 -291.229796)
		(width 0.2794)
		(layer "F.Cu")
		(net "FAN_7_PWM_IL_R")
	)
	(segment
		(start 13.961872 -291.5031)
		(end 13.961872 -291.44341)
		(width 0.2794)
		(layer "F.Cu")
		(net "FAN_7_PWM_IL_R")
	)
	(segment
		(start 14.422882 -290.9824)
		(end 14.45641 -290.9824)
		(width 0.2794)
		(layer "F.Cu")
		(net "FAN_7_PWM_IL_R")
	)
	(segment
		(start 11.811 -291.5031)
		(end 13.961872 -291.5031)
		(width 0.2794)
		(layer "F.Cu")
		(net "FAN_7_PWM_IL_R")
	)
	(segment
		(start 14.45641 -290.9824)
		(end 14.51991 -290.9189)
		(width 0.2794)
		(layer "F.Cu")
		(net "FAN_7_PWM_IL_R")
	)
	(via
		(at 11.811 -291.5031)
		(size 0.762)
		(drill 0.381)
		(layers "F.Cu" "B.Cu")
		(net "FAN_7_PWM_IL_R")
	)
	(segment
		(start 33.401 -169.951908)
		(end 31.343854 -169.951908)
		(width 0.2794)
		(layer "F.Cu")
		(net "PU_U8_PIN2")
	)
	(segment
		(start 30.936946 -169.545)
		(end 29.35605 -169.545)
		(width 0.2794)
		(layer "F.Cu")
		(net "PU_U8_PIN2")
	)
	(segment
		(start 31.343854 -169.951908)
		(end 30.936946 -169.545)
		(width 0.2794)
		(layer "F.Cu")
		(net "PU_U8_PIN2")
	)
	(via
		(at 31.343854 -169.951908)
		(size 0.508)
		(drill 0.254)
		(layers "F.Cu" "B.Cu")
		(net "PU_U8_PIN2")
	)
	(segment
		(start 30.136846 -16.2179)
		(end 29.398722 -16.956024)
		(width 0.2794)
		(layer "F.Cu")
		(net "FAN_3_TACH_OL")
	)
	(segment
		(start 29.398722 -19.17065)
		(end 29.443172 -19.2151)
		(width 0.2794)
		(layer "F.Cu")
		(net "FAN_3_TACH_OL")
	)
	(segment
		(start 32.70885 -16.2179)
		(end 30.136846 -16.2179)
		(width 0.2794)
		(layer "F.Cu")
		(net "FAN_3_TACH_OL")
	)
	(segment
		(start 33.00095 -16.51)
		(end 32.70885 -16.2179)
		(width 0.2794)
		(layer "F.Cu")
		(net "FAN_3_TACH_OL")
	)
	(segment
		(start 38.227 -123.698)
		(end 38.227 -124.333)
		(width 0.2794)
		(layer "F.Cu")
		(net "FAN_3_TACH_OL")
	)
	(segment
		(start 29.398722 -16.956024)
		(end 29.398722 -19.17065)
		(width 0.2794)
		(layer "F.Cu")
		(net "FAN_3_TACH_OL")
	)
	(via
		(at 38.227 -124.333)
		(size 0.508)
		(drill 0.254)
		(layers "F.Cu" "B.Cu")
		(net "FAN_3_TACH_OL")
	)
	(via
		(at 29.443172 -19.2151)
		(size 0.508)
		(drill 0.254)
		(layers "F.Cu" "B.Cu")
		(net "FAN_3_TACH_OL")
	)
	(segment
		(start 38.227 -124.35205)
		(end 38.227 -124.333)
		(width 0.2794)
		(layer "B.Cu")
		(net "FAN_3_TACH_OL")
	)
	(segment
		(start 40.49395 -126.619)
		(end 38.227 -124.35205)
		(width 0.2794)
		(layer "B.Cu")
		(net "FAN_3_TACH_OL")
	)
	(segment
		(start 26.264616 -83.511136)
		(end 25.72258 -82.9691)
		(width 0.2286)
		(layer "In2.Cu")
		(net "FAN_3_TACH_OL")
	)
	(segment
		(start 29.135832 -101.99116)
		(end 26.264616 -99.119944)
		(width 0.2286)
		(layer "In2.Cu")
		(net "FAN_3_TACH_OL")
	)
	(segment
		(start 28.512008 -111.265208)
		(end 27.974798 -110.727998)
		(width 0.2286)
		(layer "In2.Cu")
		(net "FAN_3_TACH_OL")
	)
	(segment
		(start 30.867096 -21.214842)
		(end 29.443172 -19.790918)
		(width 0.2286)
		(layer "In2.Cu")
		(net "FAN_3_TACH_OL")
	)
	(segment
		(start 38.227 -122.555)
		(end 35.5092 -119.8372)
		(width 0.2286)
		(layer "In2.Cu")
		(net "FAN_3_TACH_OL")
	)
	(segment
		(start 31.0642 -51.480974)
		(end 31.0642 -32.041592)
		(width 0.2286)
		(layer "In2.Cu")
		(net "FAN_3_TACH_OL")
	)
	(segment
		(start 25.72258 -64.381126)
		(end 31.0642 -51.480974)
		(width 0.2286)
		(layer "In2.Cu")
		(net "FAN_3_TACH_OL")
	)
	(segment
		(start 27.974798 -110.727998)
		(end 27.974798 -105.201974)
		(width 0.2286)
		(layer "In2.Cu")
		(net "FAN_3_TACH_OL")
	)
	(segment
		(start 29.135832 -104.04094)
		(end 29.135832 -101.99116)
		(width 0.2286)
		(layer "In2.Cu")
		(net "FAN_3_TACH_OL")
	)
	(segment
		(start 30.867096 -21.762974)
		(end 30.867096 -21.214842)
		(width 0.2286)
		(layer "In2.Cu")
		(net "FAN_3_TACH_OL")
	)
	(segment
		(start 25.72258 -82.9691)
		(end 25.72258 -64.381126)
		(width 0.2286)
		(layer "In2.Cu")
		(net "FAN_3_TACH_OL")
	)
	(segment
		(start 29.443172 -19.790918)
		(end 29.443172 -19.2151)
		(width 0.2286)
		(layer "In2.Cu")
		(net "FAN_3_TACH_OL")
	)
	(segment
		(start 33.290764 -114.579654)
		(end 31.293054 -114.579654)
		(width 0.2286)
		(layer "In2.Cu")
		(net "FAN_3_TACH_OL")
	)
	(segment
		(start 27.974798 -105.201974)
		(end 29.135832 -104.04094)
		(width 0.2286)
		(layer "In2.Cu")
		(net "FAN_3_TACH_OL")
	)
	(segment
		(start 26.264616 -99.119944)
		(end 26.264616 -83.511136)
		(width 0.2286)
		(layer "In2.Cu")
		(net "FAN_3_TACH_OL")
	)
	(segment
		(start 28.512008 -111.798608)
		(end 28.512008 -111.265208)
		(width 0.2286)
		(layer "In2.Cu")
		(net "FAN_3_TACH_OL")
	)
	(segment
		(start 38.227 -124.333)
		(end 38.227 -122.555)
		(width 0.2286)
		(layer "In2.Cu")
		(net "FAN_3_TACH_OL")
	)
	(segment
		(start 28.5496 -24.08047)
		(end 30.867096 -21.762974)
		(width 0.2286)
		(layer "In2.Cu")
		(net "FAN_3_TACH_OL")
	)
	(segment
		(start 35.5092 -116.79809)
		(end 33.290764 -114.579654)
		(width 0.2286)
		(layer "In2.Cu")
		(net "FAN_3_TACH_OL")
	)
	(segment
		(start 31.0642 -32.041592)
		(end 28.5496 -29.526992)
		(width 0.2286)
		(layer "In2.Cu")
		(net "FAN_3_TACH_OL")
	)
	(segment
		(start 31.293054 -114.579654)
		(end 28.512008 -111.798608)
		(width 0.2286)
		(layer "In2.Cu")
		(net "FAN_3_TACH_OL")
	)
	(segment
		(start 35.5092 -119.8372)
		(end 35.5092 -116.79809)
		(width 0.2286)
		(layer "In2.Cu")
		(net "FAN_3_TACH_OL")
	)
	(segment
		(start 28.5496 -29.526992)
		(end 28.5496 -24.08047)
		(width 0.2286)
		(layer "In2.Cu")
		(net "FAN_3_TACH_OL")
	)
	(segment
		(start 9.144 -200.025)
		(end 10.092944 -199.076056)
		(width 0.2794)
		(layer "F.Cu")
		(net "FAN_6_PWM_IL_R")
	)
	(segment
		(start 7.714996 -200.025)
		(end 9.144 -200.025)
		(width 0.2794)
		(layer "F.Cu")
		(net "FAN_6_PWM_IL_R")
	)
	(segment
		(start 16.64208 -198.402956)
		(end 17.809464 -198.402956)
		(width 0.2794)
		(layer "F.Cu")
		(net "FAN_6_PWM_IL_R")
	)
	(segment
		(start 13.961872 -199.076056)
		(end 13.961872 -199.016366)
		(width 0.2794)
		(layer "F.Cu")
		(net "FAN_6_PWM_IL_R")
	)
	(segment
		(start 14.51991 -198.491856)
		(end 15.809976 -198.491856)
		(width 0.2794)
		(layer "F.Cu")
		(net "FAN_6_PWM_IL_R")
	)
	(segment
		(start 13.961872 -199.016366)
		(end 14.422882 -198.555356)
		(width 0.2794)
		(layer "F.Cu")
		(net "FAN_6_PWM_IL_R")
	)
	(segment
		(start 16.120872 -199.076056)
		(end 16.120872 -198.924164)
		(width 0.2794)
		(layer "F.Cu")
		(net "FAN_6_PWM_IL_R")
	)
	(segment
		(start 15.809976 -198.491856)
		(end 16.120872 -198.802752)
		(width 0.2794)
		(layer "F.Cu")
		(net "FAN_6_PWM_IL_R")
	)
	(segment
		(start 16.120872 -198.802752)
		(end 16.120872 -198.924164)
		(width 0.2794)
		(layer "F.Cu")
		(net "FAN_6_PWM_IL_R")
	)
	(segment
		(start 16.120872 -198.924164)
		(end 16.64208 -198.402956)
		(width 0.2794)
		(layer "F.Cu")
		(net "FAN_6_PWM_IL_R")
	)
	(segment
		(start 18.244058 -198.83755)
		(end 18.244058 -199.037956)
		(width 0.2794)
		(layer "F.Cu")
		(net "FAN_6_PWM_IL_R")
	)
	(segment
		(start 14.422882 -198.555356)
		(end 14.45641 -198.555356)
		(width 0.2794)
		(layer "F.Cu")
		(net "FAN_6_PWM_IL_R")
	)
	(segment
		(start 10.092944 -199.076056)
		(end 11.811 -199.076056)
		(width 0.2794)
		(layer "F.Cu")
		(net "FAN_6_PWM_IL_R")
	)
	(segment
		(start 14.45641 -198.555356)
		(end 14.51991 -198.491856)
		(width 0.2794)
		(layer "F.Cu")
		(net "FAN_6_PWM_IL_R")
	)
	(segment
		(start 17.809464 -198.402956)
		(end 18.244058 -198.83755)
		(width 0.2794)
		(layer "F.Cu")
		(net "FAN_6_PWM_IL_R")
	)
	(segment
		(start 6.700012 -199.010016)
		(end 7.714996 -200.025)
		(width 0.2794)
		(layer "F.Cu")
		(net "FAN_6_PWM_IL_R")
	)
	(segment
		(start 11.811 -199.076056)
		(end 13.961872 -199.076056)
		(width 0.2794)
		(layer "F.Cu")
		(net "FAN_6_PWM_IL_R")
	)
	(via
		(at 11.811 -199.076056)
		(size 0.762)
		(drill 0.381)
		(layers "F.Cu" "B.Cu")
		(net "FAN_6_PWM_IL_R")
	)
	(segment
		(start 30.099 -102.489)
		(end 32.816038 -102.489)
		(width 0.2794)
		(layer "F.Cu")
		(net "FAN_2_TACH_OL")
	)
	(segment
		(start 32.816038 -102.489)
		(end 32.87395 -102.546912)
		(width 0.2794)
		(layer "F.Cu")
		(net "FAN_2_TACH_OL")
	)
	(segment
		(start 38.24605 -126.238)
		(end 38.24605 -126.873)
		(width 0.2794)
		(layer "F.Cu")
		(net "FAN_2_TACH_OL")
	)
	(via
		(at 30.099 -102.489)
		(size 0.762)
		(drill 0.254)
		(layers "F.Cu" "B.Cu")
		(net "FAN_2_TACH_OL")
	)
	(via
		(at 38.24605 -126.873)
		(size 0.508)
		(drill 0.254)
		(layers "F.Cu" "B.Cu")
		(net "FAN_2_TACH_OL")
	)
	(segment
		(start 39.60495 -126.873)
		(end 38.24605 -126.873)
		(width 0.2794)
		(layer "B.Cu")
		(net "FAN_2_TACH_OL")
	)
	(segment
		(start 40.49395 -127.762)
		(end 39.60495 -126.873)
		(width 0.2794)
		(layer "B.Cu")
		(net "FAN_2_TACH_OL")
	)
	(segment
		(start 36.1442 -119.5832)
		(end 36.1442 -116.67871)
		(width 0.2286)
		(layer "In2.Cu")
		(net "FAN_2_TACH_OL")
	)
	(segment
		(start 31.7373 -114.046254)
		(end 29.1846 -111.493554)
		(width 0.2286)
		(layer "In2.Cu")
		(net "FAN_2_TACH_OL")
	)
	(segment
		(start 36.1442 -116.67871)
		(end 33.511744 -114.046254)
		(width 0.2286)
		(layer "In2.Cu")
		(net "FAN_2_TACH_OL")
	)
	(segment
		(start 29.1846 -104.8004)
		(end 29.718 -104.267)
		(width 0.2286)
		(layer "In2.Cu")
		(net "FAN_2_TACH_OL")
	)
	(segment
		(start 29.1846 -111.493554)
		(end 29.1846 -104.8004)
		(width 0.2286)
		(layer "In2.Cu")
		(net "FAN_2_TACH_OL")
	)
	(segment
		(start 29.718 -102.87)
		(end 30.099 -102.489)
		(width 0.2286)
		(layer "In2.Cu")
		(net "FAN_2_TACH_OL")
	)
	(segment
		(start 33.511744 -114.046254)
		(end 31.7373 -114.046254)
		(width 0.2286)
		(layer "In2.Cu")
		(net "FAN_2_TACH_OL")
	)
	(segment
		(start 29.718 -104.267)
		(end 29.718 -102.87)
		(width 0.2286)
		(layer "In2.Cu")
		(net "FAN_2_TACH_OL")
	)
	(segment
		(start 38.862 -122.301)
		(end 36.1442 -119.5832)
		(width 0.2286)
		(layer "In2.Cu")
		(net "FAN_2_TACH_OL")
	)
	(segment
		(start 38.862 -126.25705)
		(end 38.862 -122.301)
		(width 0.2286)
		(layer "In2.Cu")
		(net "FAN_2_TACH_OL")
	)
	(segment
		(start 38.24605 -126.873)
		(end 38.862 -126.25705)
		(width 0.2286)
		(layer "In2.Cu")
		(net "FAN_2_TACH_OL")
	)
	(segment
		(start 11.972544 -255.397)
		(end 12.316968 -255.741424)
		(width 0.2794)
		(layer "F.Cu")
		(net "FAN_7_ON")
	)
	(segment
		(start 11.972544 -255.143)
		(end 11.972544 -255.397)
		(width 0.2794)
		(layer "F.Cu")
		(net "FAN_7_ON")
	)
	(via
		(at 12.316968 -255.741424)
		(size 0.508)
		(drill 0.254)
		(layers "F.Cu" "B.Cu")
		(net "FAN_7_ON")
	)
	(via
		(at 13.462 -260.604)
		(size 0.508)
		(drill 0.254)
		(layers "F.Cu" "B.Cu")
		(net "FAN_7_ON")
	)
	(via
		(at 13.170408 -257.111246)
		(size 0.762)
		(drill 0.254)
		(layers "F.Cu" "B.Cu")
		(net "FAN_7_ON")
	)
	(segment
		(start 13.782294 -260.924294)
		(end 13.782294 -262.054848)
		(width 0.1016)
		(layer "B.Cu")
		(net "FAN_7_ON")
	)
	(segment
		(start 13.462 -260.604)
		(end 13.782294 -260.924294)
		(width 0.1016)
		(layer "B.Cu")
		(net "FAN_7_ON")
	)
	(segment
		(start 14.097 -258.037838)
		(end 13.170408 -257.111246)
		(width 0.2286)
		(layer "In2.Cu")
		(net "FAN_7_ON")
	)
	(segment
		(start 14.097 -259.969)
		(end 14.097 -258.037838)
		(width 0.2286)
		(layer "In2.Cu")
		(net "FAN_7_ON")
	)
	(segment
		(start 13.170408 -257.111246)
		(end 13.170408 -256.594864)
		(width 0.2286)
		(layer "In2.Cu")
		(net "FAN_7_ON")
	)
	(segment
		(start 13.170408 -256.594864)
		(end 12.316968 -255.741424)
		(width 0.2286)
		(layer "In2.Cu")
		(net "FAN_7_ON")
	)
	(segment
		(start 13.462 -260.604)
		(end 14.097 -259.969)
		(width 0.2286)
		(layer "In2.Cu")
		(net "FAN_7_ON")
	)
	(segment
		(start 14.359382 -194.834256)
		(end 13.834872 -194.309746)
		(width 0.2794)
		(layer "F.Cu")
		(net "FAN_6_PWM_OL_R")
	)
	(segment
		(start 15.993872 -194.250056)
		(end 15.409672 -194.834256)
		(width 0.2794)
		(layer "F.Cu")
		(net "FAN_6_PWM_OL_R")
	)
	(segment
		(start 16.51508 -194.923156)
		(end 16.120872 -194.528948)
		(width 0.2794)
		(layer "F.Cu")
		(net "FAN_6_PWM_OL_R")
	)
	(segment
		(start 9.889236 -197.01002)
		(end 8.700008 -197.01002)
		(width 0.2794)
		(layer "F.Cu")
		(net "FAN_6_PWM_OL_R")
	)
	(segment
		(start 12.6492 -194.250056)
		(end 9.889236 -197.01002)
		(width 0.2794)
		(layer "F.Cu")
		(net "FAN_6_PWM_OL_R")
	)
	(segment
		(start 15.409672 -194.834256)
		(end 14.359382 -194.834256)
		(width 0.2794)
		(layer "F.Cu")
		(net "FAN_6_PWM_OL_R")
	)
	(segment
		(start 17.97558 -194.923156)
		(end 16.51508 -194.923156)
		(width 0.2794)
		(layer "F.Cu")
		(net "FAN_6_PWM_OL_R")
	)
	(segment
		(start 18.25498 -194.643756)
		(end 17.97558 -194.923156)
		(width 0.2794)
		(layer "F.Cu")
		(net "FAN_6_PWM_OL_R")
	)
	(segment
		(start 13.834872 -194.309746)
		(end 13.834872 -194.250056)
		(width 0.2794)
		(layer "F.Cu")
		(net "FAN_6_PWM_OL_R")
	)
	(segment
		(start 13.834872 -194.250056)
		(end 12.6492 -194.250056)
		(width 0.2794)
		(layer "F.Cu")
		(net "FAN_6_PWM_OL_R")
	)
	(segment
		(start 16.120872 -194.528948)
		(end 16.120872 -194.377056)
		(width 0.2794)
		(layer "F.Cu")
		(net "FAN_6_PWM_OL_R")
	)
	(segment
		(start 16.120872 -194.377056)
		(end 15.993872 -194.250056)
		(width 0.2794)
		(layer "F.Cu")
		(net "FAN_6_PWM_OL_R")
	)
	(segment
		(start 18.25498 -194.250056)
		(end 18.25498 -194.643756)
		(width 0.2794)
		(layer "F.Cu")
		(net "FAN_6_PWM_OL_R")
	)
	(via
		(at 12.6492 -194.250056)
		(size 0.762)
		(drill 0.381)
		(layers "F.Cu" "B.Cu")
		(net "FAN_6_PWM_OL_R")
	)
	(segment
		(start 10.344912 -22.409912)
		(end 8.700008 -22.409912)
		(width 0.2794)
		(layer "F.Cu")
		(net "FAN_4_FAIL_R_LED_N")
	)
	(segment
		(start 14.053058 -24.765)
		(end 14.053058 -22.96795)
		(width 0.2794)
		(layer "F.Cu")
		(net "FAN_4_FAIL_R_LED_N")
	)
	(segment
		(start 14.053058 -22.96795)
		(end 14.307058 -22.71395)
		(width 0.2794)
		(layer "F.Cu")
		(net "FAN_4_FAIL_R_LED_N")
	)
	(segment
		(start 14.307058 -22.71395)
		(end 15.113 -22.71395)
		(width 0.2794)
		(layer "F.Cu")
		(net "FAN_4_FAIL_R_LED_N")
	)
	(segment
		(start 12.7 -24.765)
		(end 10.344912 -22.409912)
		(width 0.2794)
		(layer "F.Cu")
		(net "FAN_4_FAIL_R_LED_N")
	)
	(segment
		(start 14.053058 -24.765)
		(end 12.7 -24.765)
		(width 0.2794)
		(layer "F.Cu")
		(net "FAN_4_FAIL_R_LED_N")
	)
	(via
		(at 12.7 -24.765)
		(size 0.762)
		(drill 0.381)
		(layers "F.Cu" "B.Cu")
		(net "FAN_4_FAIL_R_LED_N")
	)
	(segment
		(start 12.9286 -210.057492)
		(end 14.218158 -210.057492)
		(width 0.2794)
		(layer "F.Cu")
		(net "FAN_6_TACH_OL_D")
	)
	(segment
		(start 14.95298 -210.792314)
		(end 14.285722 -210.125056)
		(width 0.2794)
		(layer "F.Cu")
		(net "FAN_6_TACH_OL_D")
	)
	(segment
		(start 14.95298 -211.776056)
		(end 14.95298 -210.792314)
		(width 0.2794)
		(layer "F.Cu")
		(net "FAN_6_TACH_OL_D")
	)
	(segment
		(start 14.218158 -210.057492)
		(end 14.285722 -210.125056)
		(width 0.2794)
		(layer "F.Cu")
		(net "FAN_6_TACH_OL_D")
	)
	(segment
		(start 6.700012 -209.009996)
		(end 7.699756 -210.00974)
		(width 0.2794)
		(layer "F.Cu")
		(net "FAN_6_TACH_OL_D")
	)
	(segment
		(start 12.880848 -210.00974)
		(end 12.9286 -210.057492)
		(width 0.2794)
		(layer "F.Cu")
		(net "FAN_6_TACH_OL_D")
	)
	(segment
		(start 7.699756 -210.00974)
		(end 12.880848 -210.00974)
		(width 0.2794)
		(layer "F.Cu")
		(net "FAN_6_TACH_OL_D")
	)
	(via
		(at 12.9286 -210.057492)
		(size 0.762)
		(drill 0.381)
		(layers "F.Cu" "B.Cu")
		(net "FAN_6_TACH_OL_D")
	)
	(segment
		(start 10.820908 -24.409908)
		(end 12.573 -26.162)
		(width 0.2794)
		(layer "F.Cu")
		(net "FAN_4_OK_R_LED_N")
	)
	(segment
		(start 14.053058 -26.803604)
		(end 14.332712 -26.52395)
		(width 0.2794)
		(layer "F.Cu")
		(net "FAN_4_OK_R_LED_N")
	)
	(segment
		(start 14.332712 -26.52395)
		(end 15.113 -26.52395)
		(width 0.2794)
		(layer "F.Cu")
		(net "FAN_4_OK_R_LED_N")
	)
	(segment
		(start 8.700008 -24.409908)
		(end 10.820908 -24.409908)
		(width 0.2794)
		(layer "F.Cu")
		(net "FAN_4_OK_R_LED_N")
	)
	(segment
		(start 14.053058 -28.877768)
		(end 14.053058 -26.803604)
		(width 0.2794)
		(layer "F.Cu")
		(net "FAN_4_OK_R_LED_N")
	)
	(segment
		(start 14.00429 -28.829)
		(end 14.053058 -28.877768)
		(width 0.2794)
		(layer "F.Cu")
		(net "FAN_4_OK_R_LED_N")
	)
	(segment
		(start 13.5636 -28.829)
		(end 14.00429 -28.829)
		(width 0.2794)
		(layer "F.Cu")
		(net "FAN_4_OK_R_LED_N")
	)
	(segment
		(start 12.573 -26.162)
		(end 12.573 -27.8384)
		(width 0.2794)
		(layer "F.Cu")
		(net "FAN_4_OK_R_LED_N")
	)
	(segment
		(start 12.573 -27.8384)
		(end 13.5636 -28.829)
		(width 0.2794)
		(layer "F.Cu")
		(net "FAN_4_OK_R_LED_N")
	)
	(via
		(at 12.573 -27.8384)
		(size 0.762)
		(drill 0.381)
		(layers "F.Cu" "B.Cu")
		(net "FAN_4_OK_R_LED_N")
	)
	(segment
		(start 14.601444 -256.667)
		(end 14.601444 -256.43205)
		(width 0.2794)
		(layer "F.Cu")
		(net "FAN_7_PRESENT_R")
	)
	(segment
		(start 14.601444 -256.43205)
		(end 15.054072 -255.979422)
		(width 0.2794)
		(layer "F.Cu")
		(net "FAN_7_PRESENT_R")
	)
	(via
		(at 15.054072 -255.979422)
		(size 0.508)
		(drill 0.254)
		(layers "F.Cu" "B.Cu")
		(net "FAN_7_PRESENT_R")
	)
	(segment
		(start 15.054072 -255.979422)
		(end 14.478508 -256.554986)
		(width 0.2794)
		(layer "B.Cu")
		(net "FAN_7_PRESENT_R")
	)
	(segment
		(start 14.478508 -256.554986)
		(end 13.2969 -256.554986)
		(width 0.2794)
		(layer "B.Cu")
		(net "FAN_7_PRESENT_R")
	)
	(segment
		(start 7.652512 -197.96252)
		(end 6.700012 -197.01002)
		(width 0.2794)
		(layer "F.Cu")
		(net "FAN_6_TACH_IL_D")
	)
	(segment
		(start 14.053058 -196.894196)
		(end 14.285722 -196.661532)
		(width 0.2794)
		(layer "F.Cu")
		(net "FAN_6_TACH_IL_D")
	)
	(segment
		(start 9.885426 -197.96252)
		(end 7.652512 -197.96252)
		(width 0.2794)
		(layer "F.Cu")
		(net "FAN_6_TACH_IL_D")
	)
	(segment
		(start 12.5476 -196.155056)
		(end 11.69289 -196.155056)
		(width 0.2794)
		(layer "F.Cu")
		(net "FAN_6_TACH_IL_D")
	)
	(segment
		(start 14.053058 -197.739)
		(end 14.053058 -196.894196)
		(width 0.2794)
		(layer "F.Cu")
		(net "FAN_6_TACH_IL_D")
	)
	(segment
		(start 14.285722 -196.661532)
		(end 14.285722 -196.155056)
		(width 0.2794)
		(layer "F.Cu")
		(net "FAN_6_TACH_IL_D")
	)
	(segment
		(start 11.69289 -196.155056)
		(end 9.885426 -197.96252)
		(width 0.2794)
		(layer "F.Cu")
		(net "FAN_6_TACH_IL_D")
	)
	(segment
		(start 14.285722 -196.155056)
		(end 12.5476 -196.155056)
		(width 0.2794)
		(layer "F.Cu")
		(net "FAN_6_TACH_IL_D")
	)
	(via
		(at 12.5476 -196.155056)
		(size 0.762)
		(drill 0.381)
		(layers "F.Cu" "B.Cu")
		(net "FAN_6_TACH_IL_D")
	)
	(segment
		(start 4.33705 -314.178696)
		(end 4.33705 -314.833)
		(width 0.2794)
		(layer "F.Cu")
		(net "FAN_7_PRESENT")
	)
	(segment
		(start 16.163544 -257.429)
		(end 15.401544 -256.667)
		(width 0.2794)
		(layer "F.Cu")
		(net "FAN_7_PRESENT")
	)
	(segment
		(start 4.586986 -313.4741)
		(end 4.586986 -313.92876)
		(width 0.2794)
		(layer "F.Cu")
		(net "FAN_7_PRESENT")
	)
	(segment
		(start 4.586986 -313.92876)
		(end 4.33705 -314.178696)
		(width 0.2794)
		(layer "F.Cu")
		(net "FAN_7_PRESENT")
	)
	(segment
		(start 4.953 -314.833)
		(end 4.33705 -314.833)
		(width 0.2794)
		(layer "F.Cu")
		(net "FAN_7_PRESENT")
	)
	(segment
		(start 18.288 -257.429)
		(end 16.163544 -257.429)
		(width 0.2794)
		(layer "F.Cu")
		(net "FAN_7_PRESENT")
	)
	(via
		(at 18.288 -257.429)
		(size 0.762)
		(drill 0.254)
		(layers "F.Cu" "B.Cu")
		(net "FAN_7_PRESENT")
	)
	(via
		(at 4.953 -314.833)
		(size 0.508)
		(drill 0.254)
		(layers "F.Cu" "B.Cu")
		(net "FAN_7_PRESENT")
	)
	(segment
		(start 24.892 -279.4)
		(end 24.892 -258.445)
		(width 0.2794)
		(layer "B.Cu")
		(net "FAN_7_PRESENT")
	)
	(segment
		(start 18.288 -257.429)
		(end 17.320768 -257.429)
		(width 0.2794)
		(layer "B.Cu")
		(net "FAN_7_PRESENT")
	)
	(segment
		(start 23.494746 -291.338254)
		(end 23.494746 -280.797254)
		(width 0.2794)
		(layer "B.Cu")
		(net "FAN_7_PRESENT")
	)
	(segment
		(start 21.209 -301.371)
		(end 21.209 -293.624)
		(width 0.2794)
		(layer "B.Cu")
		(net "FAN_7_PRESENT")
	)
	(segment
		(start 17.320768 -257.429)
		(end 16.56969 -256.677922)
		(width 0.2794)
		(layer "B.Cu")
		(net "FAN_7_PRESENT")
	)
	(segment
		(start 23.876 -257.429)
		(end 18.288 -257.429)
		(width 0.2794)
		(layer "B.Cu")
		(net "FAN_7_PRESENT")
	)
	(segment
		(start 23.494746 -280.797254)
		(end 24.892 -279.4)
		(width 0.2794)
		(layer "B.Cu")
		(net "FAN_7_PRESENT")
	)
	(segment
		(start 21.209 -293.624)
		(end 23.494746 -291.338254)
		(width 0.2794)
		(layer "B.Cu")
		(net "FAN_7_PRESENT")
	)
	(segment
		(start 24.892 -258.445)
		(end 23.876 -257.429)
		(width 0.2794)
		(layer "B.Cu")
		(net "FAN_7_PRESENT")
	)
	(segment
		(start 4.953 -314.833)
		(end 7.112 -314.833)
		(width 0.2794)
		(layer "B.Cu")
		(net "FAN_7_PRESENT")
	)
	(segment
		(start 19.3675 -303.2125)
		(end 21.209 -301.371)
		(width 0.2794)
		(layer "B.Cu")
		(net "FAN_7_PRESENT")
	)
	(segment
		(start 7.112 -314.833)
		(end 18.7325 -303.2125)
		(width 0.2794)
		(layer "B.Cu")
		(net "FAN_7_PRESENT")
	)
	(segment
		(start 16.56969 -256.677922)
		(end 16.283432 -256.677922)
		(width 0.2794)
		(layer "B.Cu")
		(net "FAN_7_PRESENT")
	)
	(segment
		(start 18.7325 -303.2125)
		(end 19.3675 -303.2125)
		(width 0.2794)
		(layer "B.Cu")
		(net "FAN_7_PRESENT")
	)
	(segment
		(start 13.834872 -102.100126)
		(end 14.350746 -102.616)
		(width 0.2794)
		(layer "F.Cu")
		(net "FAN_5_PWM_OL_R")
	)
	(segment
		(start 12.6492 -101.950012)
		(end 9.889236 -104.709976)
		(width 0.2794)
		(layer "F.Cu")
		(net "FAN_5_PWM_OL_R")
	)
	(segment
		(start 17.79778 -100.9142)
		(end 18.25498 -101.3714)
		(width 0.2794)
		(layer "F.Cu")
		(net "FAN_5_PWM_OL_R")
	)
	(segment
		(start 16.877792 -100.9142)
		(end 17.79778 -100.9142)
		(width 0.2794)
		(layer "F.Cu")
		(net "FAN_5_PWM_OL_R")
	)
	(segment
		(start 15.993872 -101.950012)
		(end 15.993872 -101.79812)
		(width 0.2794)
		(layer "F.Cu")
		(net "FAN_5_PWM_OL_R")
	)
	(segment
		(start 18.25498 -101.3714)
		(end 18.25498 -101.950012)
		(width 0.2794)
		(layer "F.Cu")
		(net "FAN_5_PWM_OL_R")
	)
	(segment
		(start 9.889236 -104.709976)
		(end 8.700008 -104.709976)
		(width 0.2794)
		(layer "F.Cu")
		(net "FAN_5_PWM_OL_R")
	)
	(segment
		(start 13.834872 -101.950012)
		(end 13.834872 -102.100126)
		(width 0.2794)
		(layer "F.Cu")
		(net "FAN_5_PWM_OL_R")
	)
	(segment
		(start 15.993872 -101.79812)
		(end 16.877792 -100.9142)
		(width 0.2794)
		(layer "F.Cu")
		(net "FAN_5_PWM_OL_R")
	)
	(segment
		(start 14.350746 -102.616)
		(end 15.327884 -102.616)
		(width 0.2794)
		(layer "F.Cu")
		(net "FAN_5_PWM_OL_R")
	)
	(segment
		(start 15.327884 -102.616)
		(end 15.993872 -101.950012)
		(width 0.2794)
		(layer "F.Cu")
		(net "FAN_5_PWM_OL_R")
	)
	(segment
		(start 13.834872 -101.950012)
		(end 12.6492 -101.950012)
		(width 0.2794)
		(layer "F.Cu")
		(net "FAN_5_PWM_OL_R")
	)
	(via
		(at 12.6492 -101.950012)
		(size 0.762)
		(drill 0.381)
		(layers "F.Cu" "B.Cu")
		(net "FAN_5_PWM_OL_R")
	)
	(segment
		(start 33.782 -286.74695)
		(end 33.782 -284.0101)
		(width 0.2794)
		(layer "F.Cu")
		(net "FAN_0_TACH_OL")
	)
	(segment
		(start 33.782 -284.0101)
		(end 33.57245 -283.80055)
		(width 0.2794)
		(layer "F.Cu")
		(net "FAN_0_TACH_OL")
	)
	(segment
		(start 38.24605 -133.858)
		(end 38.24605 -134.493)
		(width 0.2794)
		(layer "F.Cu")
		(net "FAN_0_TACH_OL")
	)
	(via
		(at 33.57245 -283.80055)
		(size 0.508)
		(drill 0.254)
		(layers "F.Cu" "B.Cu")
		(net "FAN_0_TACH_OL")
	)
	(via
		(at 38.24605 -134.493)
		(size 0.508)
		(drill 0.254)
		(layers "F.Cu" "B.Cu")
		(net "FAN_0_TACH_OL")
	)
	(segment
		(start 39.81958 -133.410706)
		(end 39.81958 -133.00837)
		(width 0.2794)
		(layer "B.Cu")
		(net "FAN_0_TACH_OL")
	)
	(segment
		(start 38.737286 -134.493)
		(end 39.81958 -133.410706)
		(width 0.2794)
		(layer "B.Cu")
		(net "FAN_0_TACH_OL")
	)
	(segment
		(start 38.24605 -134.493)
		(end 38.737286 -134.493)
		(width 0.2794)
		(layer "B.Cu")
		(net "FAN_0_TACH_OL")
	)
	(segment
		(start 39.81958 -133.00837)
		(end 40.49395 -132.334)
		(width 0.2794)
		(layer "B.Cu")
		(net "FAN_0_TACH_OL")
	)
	(segment
		(start 45.9232 -144.124426)
		(end 45.9232 -159.382968)
		(width 0.2286)
		(layer "In2.Cu")
		(net "FAN_0_TACH_OL")
	)
	(segment
		(start 29.718 -279.9461)
		(end 33.57245 -283.80055)
		(width 0.2286)
		(layer "In2.Cu")
		(net "FAN_0_TACH_OL")
	)
	(segment
		(start 36.516564 -202.184)
		(end 37.462206 -203.129642)
		(width 0.2286)
		(layer "In2.Cu")
		(net "FAN_0_TACH_OL")
	)
	(segment
		(start 30.447488 -248.459244)
		(end 29.718 -249.188732)
		(width 0.2286)
		(layer "In2.Cu")
		(net "FAN_0_TACH_OL")
	)
	(segment
		(start 38.7096 -187.525914)
		(end 30.372812 -195.862702)
		(width 0.2286)
		(layer "In2.Cu")
		(net "FAN_0_TACH_OL")
	)
	(segment
		(start 33.296098 -213.668356)
		(end 33.296098 -241.581686)
		(width 0.2286)
		(layer "In2.Cu")
		(net "FAN_0_TACH_OL")
	)
	(segment
		(start 32.627062 -202.184)
		(end 36.516564 -202.184)
		(width 0.2286)
		(layer "In2.Cu")
		(net "FAN_0_TACH_OL")
	)
	(segment
		(start 40.049196 -138.250422)
		(end 45.9232 -144.124426)
		(width 0.2286)
		(layer "In2.Cu")
		(net "FAN_0_TACH_OL")
	)
	(segment
		(start 29.718 -249.188732)
		(end 29.718 -279.9461)
		(width 0.2286)
		(layer "In2.Cu")
		(net "FAN_0_TACH_OL")
	)
	(segment
		(start 38.24605 -134.493)
		(end 40.049196 -136.296146)
		(width 0.2286)
		(layer "In2.Cu")
		(net "FAN_0_TACH_OL")
	)
	(segment
		(start 30.372812 -199.92975)
		(end 32.627062 -202.184)
		(width 0.2286)
		(layer "In2.Cu")
		(net "FAN_0_TACH_OL")
	)
	(segment
		(start 37.462206 -209.502248)
		(end 33.296098 -213.668356)
		(width 0.2286)
		(layer "In2.Cu")
		(net "FAN_0_TACH_OL")
	)
	(segment
		(start 45.9232 -159.382968)
		(end 38.7096 -166.596568)
		(width 0.2286)
		(layer "In2.Cu")
		(net "FAN_0_TACH_OL")
	)
	(segment
		(start 33.296098 -241.581686)
		(end 30.447488 -248.459244)
		(width 0.2286)
		(layer "In2.Cu")
		(net "FAN_0_TACH_OL")
	)
	(segment
		(start 30.372812 -195.862702)
		(end 30.372812 -199.92975)
		(width 0.2286)
		(layer "In2.Cu")
		(net "FAN_0_TACH_OL")
	)
	(segment
		(start 38.7096 -166.596568)
		(end 38.7096 -187.525914)
		(width 0.2286)
		(layer "In2.Cu")
		(net "FAN_0_TACH_OL")
	)
	(segment
		(start 37.462206 -203.129642)
		(end 37.462206 -209.502248)
		(width 0.2286)
		(layer "In2.Cu")
		(net "FAN_0_TACH_OL")
	)
	(segment
		(start 40.049196 -136.296146)
		(end 40.049196 -138.250422)
		(width 0.2286)
		(layer "In2.Cu")
		(net "FAN_0_TACH_OL")
	)
	(segment
		(start 7.752588 -254.073152)
		(end 7.752588 -253.414276)
		(width 0.2794)
		(layer "F.Cu")
		(net "FAN_6_ON")
	)
	(segment
		(start 7.752588 -253.414276)
		(end 8.309864 -252.857)
		(width 0.2794)
		(layer "F.Cu")
		(net "FAN_6_ON")
	)
	(via
		(at 7.752588 -254.073152)
		(size 0.762)
		(drill 0.254)
		(layers "F.Cu" "B.Cu")
		(net "FAN_6_ON")
	)
	(via
		(at 6.85546 -247.658636)
		(size 0.508)
		(drill 0.254)
		(layers "F.Cu" "B.Cu")
		(net "FAN_6_ON")
	)
	(segment
		(start 6.85546 -247.658636)
		(end 6.500114 -246.799862)
		(width 0.1016)
		(layer "B.Cu")
		(net "FAN_6_ON")
	)
	(segment
		(start 6.500114 -246.799862)
		(end 6.500114 -245.945152)
		(width 0.1016)
		(layer "B.Cu")
		(net "FAN_6_ON")
	)
	(segment
		(start 8.595614 -248.4501)
		(end 7.739888 -247.594374)
		(width 0.2286)
		(layer "In2.Cu")
		(net "FAN_6_ON")
	)
	(segment
		(start 6.919722 -247.594374)
		(end 6.85546 -247.658636)
		(width 0.2286)
		(layer "In2.Cu")
		(net "FAN_6_ON")
	)
	(segment
		(start 7.739888 -247.594374)
		(end 6.919722 -247.594374)
		(width 0.2286)
		(layer "In2.Cu")
		(net "FAN_6_ON")
	)
	(segment
		(start 7.752588 -254.073152)
		(end 7.752588 -253.280926)
		(width 0.2286)
		(layer "In2.Cu")
		(net "FAN_6_ON")
	)
	(segment
		(start 8.595614 -252.4379)
		(end 8.595614 -248.4501)
		(width 0.2286)
		(layer "In2.Cu")
		(net "FAN_6_ON")
	)
	(segment
		(start 7.752588 -253.280926)
		(end 8.595614 -252.4379)
		(width 0.2286)
		(layer "In2.Cu")
		(net "FAN_6_ON")
	)
	(segment
		(start 14.285722 -117.825012)
		(end 14.95298 -118.49227)
		(width 0.2794)
		(layer "F.Cu")
		(net "FAN_5_TACH_OL_D")
	)
	(segment
		(start 11.811 -117.698012)
		(end 7.688072 -117.698012)
		(width 0.2794)
		(layer "F.Cu")
		(net "FAN_5_TACH_OL_D")
	)
	(segment
		(start 14.95298 -118.49227)
		(end 14.95298 -119.476012)
		(width 0.2794)
		(layer "F.Cu")
		(net "FAN_5_TACH_OL_D")
	)
	(segment
		(start 14.285722 -117.825012)
		(end 14.158722 -117.698012)
		(width 0.2794)
		(layer "F.Cu")
		(net "FAN_5_TACH_OL_D")
	)
	(segment
		(start 14.158722 -117.698012)
		(end 11.811 -117.698012)
		(width 0.2794)
		(layer "F.Cu")
		(net "FAN_5_TACH_OL_D")
	)
	(segment
		(start 7.688072 -117.698012)
		(end 6.700012 -116.709952)
		(width 0.2794)
		(layer "F.Cu")
		(net "FAN_5_TACH_OL_D")
	)
	(via
		(at 11.811 -117.698012)
		(size 0.762)
		(drill 0.381)
		(layers "F.Cu" "B.Cu")
		(net "FAN_5_TACH_OL_D")
	)
	(segment
		(start 16.64208 -106.102912)
		(end 17.809464 -106.102912)
		(width 0.2794)
		(layer "F.Cu")
		(net "FAN_5_PWM_IL_R")
	)
	(segment
		(start 13.961872 -106.716322)
		(end 14.422882 -106.255312)
		(width 0.2794)
		(layer "F.Cu")
		(net "FAN_5_PWM_IL_R")
	)
	(segment
		(start 18.244058 -106.537506)
		(end 18.244058 -106.737912)
		(width 0.2794)
		(layer "F.Cu")
		(net "FAN_5_PWM_IL_R")
	)
	(segment
		(start 14.51991 -106.191812)
		(end 15.809976 -106.191812)
		(width 0.2794)
		(layer "F.Cu")
		(net "FAN_5_PWM_IL_R")
	)
	(segment
		(start 16.120872 -106.62412)
		(end 16.64208 -106.102912)
		(width 0.2794)
		(layer "F.Cu")
		(net "FAN_5_PWM_IL_R")
	)
	(segment
		(start 13.961872 -106.776012)
		(end 13.378688 -106.776012)
		(width 0.2794)
		(layer "F.Cu")
		(net "FAN_5_PWM_IL_R")
	)
	(segment
		(start 17.809464 -106.102912)
		(end 18.244058 -106.537506)
		(width 0.2794)
		(layer "F.Cu")
		(net "FAN_5_PWM_IL_R")
	)
	(segment
		(start 16.120872 -106.502708)
		(end 16.120872 -106.62412)
		(width 0.2794)
		(layer "F.Cu")
		(net "FAN_5_PWM_IL_R")
	)
	(segment
		(start 13.961872 -106.776012)
		(end 13.961872 -106.716322)
		(width 0.2794)
		(layer "F.Cu")
		(net "FAN_5_PWM_IL_R")
	)
	(segment
		(start 14.45641 -106.255312)
		(end 14.51991 -106.191812)
		(width 0.2794)
		(layer "F.Cu")
		(net "FAN_5_PWM_IL_R")
	)
	(segment
		(start 6.994652 -106.709972)
		(end 7.99846 -107.71378)
		(width 0.2794)
		(layer "F.Cu")
		(net "FAN_5_PWM_IL_R")
	)
	(segment
		(start 16.120872 -106.776012)
		(end 16.120872 -106.62412)
		(width 0.2794)
		(layer "F.Cu")
		(net "FAN_5_PWM_IL_R")
	)
	(segment
		(start 11.759692 -107.71378)
		(end 11.811 -107.662472)
		(width 0.2794)
		(layer "F.Cu")
		(net "FAN_5_PWM_IL_R")
	)
	(segment
		(start 15.809976 -106.191812)
		(end 16.120872 -106.502708)
		(width 0.2794)
		(layer "F.Cu")
		(net "FAN_5_PWM_IL_R")
	)
	(segment
		(start 12.492228 -107.662472)
		(end 11.811 -107.662472)
		(width 0.2794)
		(layer "F.Cu")
		(net "FAN_5_PWM_IL_R")
	)
	(segment
		(start 7.99846 -107.71378)
		(end 11.759692 -107.71378)
		(width 0.2794)
		(layer "F.Cu")
		(net "FAN_5_PWM_IL_R")
	)
	(segment
		(start 14.422882 -106.255312)
		(end 14.45641 -106.255312)
		(width 0.2794)
		(layer "F.Cu")
		(net "FAN_5_PWM_IL_R")
	)
	(segment
		(start 6.700012 -106.709972)
		(end 6.994652 -106.709972)
		(width 0.2794)
		(layer "F.Cu")
		(net "FAN_5_PWM_IL_R")
	)
	(segment
		(start 13.378688 -106.776012)
		(end 12.492228 -107.662472)
		(width 0.2794)
		(layer "F.Cu")
		(net "FAN_5_PWM_IL_R")
	)
	(via
		(at 11.811 -107.662472)
		(size 0.762)
		(drill 0.381)
		(layers "F.Cu" "B.Cu")
		(net "FAN_5_PWM_IL_R")
	)
	(segment
		(start 31.576518 -196.943218)
		(end 30.851094 -196.217794)
		(width 0.2794)
		(layer "F.Cu")
		(net "FAN_0_TACH_IL")
	)
	(segment
		(start 30.9118 -202.767184)
		(end 30.9118 -200.671938)
		(width 0.2794)
		(layer "F.Cu")
		(net "FAN_0_TACH_IL")
	)
	(segment
		(start 30.851094 -193.875406)
		(end 30.438344 -193.462656)
		(width 0.2794)
		(layer "F.Cu")
		(net "FAN_0_TACH_IL")
	)
	(segment
		(start 38.24605 -136.398)
		(end 38.24605 -137.033)
		(width 0.2794)
		(layer "F.Cu")
		(net "FAN_0_TACH_IL")
	)
	(segment
		(start 30.851094 -196.217794)
		(end 30.851094 -193.875406)
		(width 0.2794)
		(layer "F.Cu")
		(net "FAN_0_TACH_IL")
	)
	(segment
		(start 32.098488 -301.230538)
		(end 32.61995 -301.752)
		(width 0.2794)
		(layer "F.Cu")
		(net "FAN_0_TACH_IL")
	)
	(segment
		(start 25.781 -207.897984)
		(end 30.9118 -202.767184)
		(width 0.2794)
		(layer "F.Cu")
		(net "FAN_0_TACH_IL")
	)
	(segment
		(start 25.781 -209.364834)
		(end 25.781 -207.897984)
		(width 0.2794)
		(layer "F.Cu")
		(net "FAN_0_TACH_IL")
	)
	(segment
		(start 31.576518 -200.00722)
		(end 31.576518 -196.943218)
		(width 0.2794)
		(layer "F.Cu")
		(net "FAN_0_TACH_IL")
	)
	(segment
		(start 32.09544 -301.230538)
		(end 32.098488 -301.230538)
		(width 0.2794)
		(layer "F.Cu")
		(net "FAN_0_TACH_IL")
	)
	(segment
		(start 30.9118 -200.671938)
		(end 31.576518 -200.00722)
		(width 0.2794)
		(layer "F.Cu")
		(net "FAN_0_TACH_IL")
	)
	(via
		(at 30.438344 -193.462656)
		(size 0.508)
		(drill 0.254)
		(layers "F.Cu" "B.Cu")
		(net "FAN_0_TACH_IL")
	)
	(via
		(at 25.781 -209.364834)
		(size 0.508)
		(drill 0.254)
		(layers "F.Cu" "B.Cu")
		(net "FAN_0_TACH_IL")
	)
	(via
		(at 38.24605 -137.033)
		(size 0.508)
		(drill 0.254)
		(layers "F.Cu" "B.Cu")
		(net "FAN_0_TACH_IL")
	)
	(via
		(at 32.09544 -301.230538)
		(size 0.508)
		(drill 0.254)
		(layers "F.Cu" "B.Cu")
		(net "FAN_0_TACH_IL")
	)
	(segment
		(start 40.49395 -134.62)
		(end 38.24605 -136.8679)
		(width 0.2794)
		(layer "B.Cu")
		(net "FAN_0_TACH_IL")
	)
	(segment
		(start 38.24605 -136.8679)
		(end 38.24605 -137.033)
		(width 0.2794)
		(layer "B.Cu")
		(net "FAN_0_TACH_IL")
	)
	(segment
		(start 32.63646 -297.431714)
		(end 32.63646 -300.689518)
		(width 0.2286)
		(layer "In2.Cu")
		(net "FAN_0_TACH_IL")
	)
	(segment
		(start 35.369754 -158.051246)
		(end 35.33775 -157.974284)
		(width 0.2286)
		(layer "In2.Cu")
		(net "FAN_0_TACH_IL")
	)
	(segment
		(start 37.1094 -181.636162)
		(end 37.1094 -163.49218)
		(width 0.2286)
		(layer "In2.Cu")
		(net "FAN_0_TACH_IL")
	)
	(segment
		(start 30.546294 -291.444426)
		(end 30.546294 -295.341548)
		(width 0.2286)
		(layer "In2.Cu")
		(net "FAN_0_TACH_IL")
	)
	(segment
		(start 30.438344 -193.462656)
		(end 33.652968 -190.248032)
		(width 0.2286)
		(layer "In2.Cu")
		(net "FAN_0_TACH_IL")
	)
	(segment
		(start 30.546294 -295.341548)
		(end 32.63646 -297.431714)
		(width 0.2286)
		(layer "In2.Cu")
		(net "FAN_0_TACH_IL")
	)
	(segment
		(start 25.781 -209.364834)
		(end 25.781 -219.36837)
		(width 0.2286)
		(layer "In2.Cu")
		(net "FAN_0_TACH_IL")
	)
	(segment
		(start 37.1094 -163.49218)
		(end 36.576 -162.95878)
		(width 0.2286)
		(layer "In2.Cu")
		(net "FAN_0_TACH_IL")
	)
	(segment
		(start 35.33775 -143.689832)
		(end 38.904164 -140.123418)
		(width 0.2286)
		(layer "In2.Cu")
		(net "FAN_0_TACH_IL")
	)
	(segment
		(start 35.33775 -157.974284)
		(end 35.33775 -143.689832)
		(width 0.2286)
		(layer "In2.Cu")
		(net "FAN_0_TACH_IL")
	)
	(segment
		(start 38.904164 -137.691114)
		(end 38.24605 -137.033)
		(width 0.2286)
		(layer "In2.Cu")
		(net "FAN_0_TACH_IL")
	)
	(segment
		(start 32.63646 -300.689518)
		(end 32.09544 -301.230538)
		(width 0.2286)
		(layer "In2.Cu")
		(net "FAN_0_TACH_IL")
	)
	(segment
		(start 33.652968 -185.092594)
		(end 37.1094 -181.636162)
		(width 0.2286)
		(layer "In2.Cu")
		(net "FAN_0_TACH_IL")
	)
	(segment
		(start 28.6385 -289.536632)
		(end 30.546294 -291.444426)
		(width 0.2286)
		(layer "In2.Cu")
		(net "FAN_0_TACH_IL")
	)
	(segment
		(start 33.652968 -190.248032)
		(end 33.652968 -185.092594)
		(width 0.2286)
		(layer "In2.Cu")
		(net "FAN_0_TACH_IL")
	)
	(segment
		(start 36.576 -162.95878)
		(end 36.576 -160.960816)
		(width 0.2286)
		(layer "In2.Cu")
		(net "FAN_0_TACH_IL")
	)
	(segment
		(start 28.6385 -284.622748)
		(end 28.6385 -289.536632)
		(width 0.2286)
		(layer "In2.Cu")
		(net "FAN_0_TACH_IL")
	)
	(segment
		(start 36.576 -160.960816)
		(end 35.369754 -158.051246)
		(width 0.2286)
		(layer "In2.Cu")
		(net "FAN_0_TACH_IL")
	)
	(segment
		(start 25.781 -219.36837)
		(end 19.657314 -225.492056)
		(width 0.2286)
		(layer "In2.Cu")
		(net "FAN_0_TACH_IL")
	)
	(segment
		(start 26.0604 -282.044648)
		(end 28.6385 -284.622748)
		(width 0.2286)
		(layer "In2.Cu")
		(net "FAN_0_TACH_IL")
	)
	(segment
		(start 19.657314 -245.239794)
		(end 26.0604 -251.64288)
		(width 0.2286)
		(layer "In2.Cu")
		(net "FAN_0_TACH_IL")
	)
	(segment
		(start 38.904164 -140.123418)
		(end 38.904164 -137.691114)
		(width 0.2286)
		(layer "In2.Cu")
		(net "FAN_0_TACH_IL")
	)
	(segment
		(start 19.657314 -225.492056)
		(end 19.657314 -245.239794)
		(width 0.2286)
		(layer "In2.Cu")
		(net "FAN_0_TACH_IL")
	)
	(segment
		(start 26.0604 -251.64288)
		(end 26.0604 -282.044648)
		(width 0.2286)
		(layer "In2.Cu")
		(net "FAN_0_TACH_IL")
	)
	(segment
		(start 11.811 -105.664)
		(end 7.654036 -105.664)
		(width 0.2794)
		(layer "F.Cu")
		(net "FAN_5_TACH_IL_D")
	)
	(segment
		(start 7.654036 -105.664)
		(end 6.700012 -104.709976)
		(width 0.2794)
		(layer "F.Cu")
		(net "FAN_5_TACH_IL_D")
	)
	(segment
		(start 14.379448 -105.506012)
		(end 14.22146 -105.664)
		(width 0.2794)
		(layer "F.Cu")
		(net "FAN_5_TACH_IL_D")
	)
	(segment
		(start 14.285722 -103.855012)
		(end 14.95298 -104.52227)
		(width 0.2794)
		(layer "F.Cu")
		(net "FAN_5_TACH_IL_D")
	)
	(segment
		(start 14.22146 -105.664)
		(end 11.811 -105.664)
		(width 0.2794)
		(layer "F.Cu")
		(net "FAN_5_TACH_IL_D")
	)
	(segment
		(start 14.95298 -104.52227)
		(end 14.95298 -105.506012)
		(width 0.2794)
		(layer "F.Cu")
		(net "FAN_5_TACH_IL_D")
	)
	(segment
		(start 14.95298 -105.506012)
		(end 14.379448 -105.506012)
		(width 0.2794)
		(layer "F.Cu")
		(net "FAN_5_TACH_IL_D")
	)
	(via
		(at 11.811 -105.664)
		(size 0.762)
		(drill 0.381)
		(layers "F.Cu" "B.Cu")
		(net "FAN_5_TACH_IL_D")
	)
	(segment
		(start 11.557 -29.068268)
		(end 13.0556 -30.566868)
		(width 0.2794)
		(layer "F.Cu")
		(net "FAN_4_TACH_OL_D")
	)
	(segment
		(start 13.0556 -30.566868)
		(end 14.412722 -30.566868)
		(width 0.2794)
		(layer "F.Cu")
		(net "FAN_4_TACH_OL_D")
	)
	(segment
		(start 14.412722 -31.55061)
		(end 14.412722 -30.566868)
		(width 0.2794)
		(layer "F.Cu")
		(net "FAN_4_TACH_OL_D")
	)
	(segment
		(start 7.700264 -25.41016)
		(end 10.42416 -25.41016)
		(width 0.2794)
		(layer "F.Cu")
		(net "FAN_4_TACH_OL_D")
	)
	(segment
		(start 11.557 -26.543)
		(end 11.557 -29.068268)
		(width 0.2794)
		(layer "F.Cu")
		(net "FAN_4_TACH_OL_D")
	)
	(segment
		(start 10.42416 -25.41016)
		(end 11.557 -26.543)
		(width 0.2794)
		(layer "F.Cu")
		(net "FAN_4_TACH_OL_D")
	)
	(segment
		(start 6.700012 -24.409908)
		(end 7.700264 -25.41016)
		(width 0.2794)
		(layer "F.Cu")
		(net "FAN_4_TACH_OL_D")
	)
	(segment
		(start 15.07998 -32.217868)
		(end 14.412722 -31.55061)
		(width 0.2794)
		(layer "F.Cu")
		(net "FAN_4_TACH_OL_D")
	)
	(via
		(at 13.0556 -30.566868)
		(size 0.762)
		(drill 0.381)
		(layers "F.Cu" "B.Cu")
		(net "FAN_4_TACH_OL_D")
	)
	(segment
		(start 14.83995 -120.65)
		(end 12.823444 -120.65)
		(width 0.2794)
		(layer "F.Cu")
		(net "FAN_5_TACH_OL")
	)
	(segment
		(start 12.823444 -120.65)
		(end 12.621006 -120.447562)
		(width 0.2794)
		(layer "F.Cu")
		(net "FAN_5_TACH_OL")
	)
	(segment
		(start 14.45895 -128.524)
		(end 14.45895 -129.159)
		(width 0.2794)
		(layer "F.Cu")
		(net "FAN_5_TACH_OL")
	)
	(via
		(at 14.45895 -129.159)
		(size 0.508)
		(drill 0.254)
		(layers "F.Cu" "B.Cu")
		(net "FAN_5_TACH_OL")
	)
	(via
		(at 12.621006 -120.447562)
		(size 0.508)
		(drill 0.254)
		(layers "F.Cu" "B.Cu")
		(net "FAN_5_TACH_OL")
	)
	(segment
		(start 17.25295 -129.667)
		(end 14.96695 -129.667)
		(width 0.2794)
		(layer "B.Cu")
		(net "FAN_5_TACH_OL")
	)
	(segment
		(start 14.96695 -129.667)
		(end 14.45895 -129.159)
		(width 0.2794)
		(layer "B.Cu")
		(net "FAN_5_TACH_OL")
	)
	(segment
		(start 13.703808 -129.159)
		(end 14.45895 -129.159)
		(width 0.2286)
		(layer "In2.Cu")
		(net "FAN_5_TACH_OL")
	)
	(segment
		(start 12.51966 -127.974852)
		(end 13.703808 -129.159)
		(width 0.2286)
		(layer "In2.Cu")
		(net "FAN_5_TACH_OL")
	)
	(segment
		(start 12.51966 -120.548908)
		(end 12.51966 -127.974852)
		(width 0.2286)
		(layer "In2.Cu")
		(net "FAN_5_TACH_OL")
	)
	(segment
		(start 12.621006 -120.447562)
		(end 12.51966 -120.548908)
		(width 0.2286)
		(layer "In2.Cu")
		(net "FAN_5_TACH_OL")
	)
	(segment
		(start 5.844286 -252.854714)
		(end 5.103622 -252.11405)
		(width 0.2794)
		(layer "F.Cu")
		(net "FAN_6_PRESENT_R")
	)
	(segment
		(start 5.103622 -252.11405)
		(end 4.318 -252.11405)
		(width 0.2794)
		(layer "F.Cu")
		(net "FAN_6_PRESENT_R")
	)
	(via
		(at 5.844286 -252.854714)
		(size 0.762)
		(drill 0.254)
		(layers "F.Cu" "B.Cu")
		(net "FAN_6_PRESENT_R")
	)
	(segment
		(start 5.844286 -252.854714)
		(end 5.440172 -252.4506)
		(width 0.2794)
		(layer "B.Cu")
		(net "FAN_6_PRESENT_R")
	)
	(segment
		(start 5.440172 -251.808742)
		(end 5.8039 -251.445014)
		(width 0.2794)
		(layer "B.Cu")
		(net "FAN_6_PRESENT_R")
	)
	(segment
		(start 5.440172 -252.4506)
		(end 5.440172 -251.808742)
		(width 0.2794)
		(layer "B.Cu")
		(net "FAN_6_PRESENT_R")
	)
	(segment
		(start 5.8039 -251.445014)
		(end 6.985508 -251.445014)
		(width 0.2794)
		(layer "B.Cu")
		(net "FAN_6_PRESENT_R")
	)
	(segment
		(start 12.2174 -14.310868)
		(end 13.834872 -14.310868)
		(width 0.2794)
		(layer "F.Cu")
		(net "FAN_4_PWM_OL_R")
	)
	(segment
		(start 16.393922 -14.710918)
		(end 15.94866 -14.710918)
		(width 0.2794)
		(layer "F.Cu")
		(net "FAN_4_PWM_OL_R")
	)
	(segment
		(start 8.700008 -12.409932)
		(end 9.742932 -12.409932)
		(width 0.2794)
		(layer "F.Cu")
		(net "FAN_4_PWM_OL_R")
	)
	(segment
		(start 16.393922 -14.710918)
		(end 17.23009 -14.710918)
		(width 0.2794)
		(layer "F.Cu")
		(net "FAN_4_PWM_OL_R")
	)
	(segment
		(start 14.96441 -13.726668)
		(end 14.359382 -13.726668)
		(width 0.2794)
		(layer "F.Cu")
		(net "FAN_4_PWM_OL_R")
	)
	(segment
		(start 14.359382 -13.726668)
		(end 13.834872 -14.251178)
		(width 0.2794)
		(layer "F.Cu")
		(net "FAN_4_PWM_OL_R")
	)
	(segment
		(start 17.63014 -14.310868)
		(end 18.25498 -14.310868)
		(width 0.2794)
		(layer "F.Cu")
		(net "FAN_4_PWM_OL_R")
	)
	(segment
		(start 11.643868 -14.310868)
		(end 12.2174 -14.310868)
		(width 0.2794)
		(layer "F.Cu")
		(net "FAN_4_PWM_OL_R")
	)
	(segment
		(start 17.23009 -14.710918)
		(end 17.63014 -14.310868)
		(width 0.2794)
		(layer "F.Cu")
		(net "FAN_4_PWM_OL_R")
	)
	(segment
		(start 13.834872 -14.251178)
		(end 13.834872 -14.310868)
		(width 0.2794)
		(layer "F.Cu")
		(net "FAN_4_PWM_OL_R")
	)
	(segment
		(start 15.94866 -14.710918)
		(end 14.96441 -13.726668)
		(width 0.2794)
		(layer "F.Cu")
		(net "FAN_4_PWM_OL_R")
	)
	(segment
		(start 9.742932 -12.409932)
		(end 11.643868 -14.310868)
		(width 0.2794)
		(layer "F.Cu")
		(net "FAN_4_PWM_OL_R")
	)
	(via
		(at 12.2174 -14.310868)
		(size 0.762)
		(drill 0.381)
		(layers "F.Cu" "B.Cu")
		(net "FAN_4_PWM_OL_R")
	)
	(segment
		(start 42.235882 -256.43205)
		(end 42.635932 -256.032)
		(width 0.2794)
		(layer "F.Cu")
		(net "FAN_0_PRESENT_R")
	)
	(segment
		(start 42.235882 -256.667)
		(end 42.235882 -256.43205)
		(width 0.2794)
		(layer "F.Cu")
		(net "FAN_0_PRESENT_R")
	)
	(segment
		(start 42.635932 -256.032)
		(end 42.635932 -255.905)
		(width 0.2794)
		(layer "F.Cu")
		(net "FAN_0_PRESENT_R")
	)
	(via
		(at 42.635932 -255.905)
		(size 0.508)
		(drill 0.254)
		(layers "F.Cu" "B.Cu")
		(net "FAN_0_PRESENT_R")
	)
	(segment
		(start 42.635932 -256.032)
		(end 42.112946 -256.554986)
		(width 0.2794)
		(layer "B.Cu")
		(net "FAN_0_PRESENT_R")
	)
	(segment
		(start 42.635932 -255.905)
		(end 42.635932 -256.032)
		(width 0.2794)
		(layer "B.Cu")
		(net "FAN_0_PRESENT_R")
	)
	(segment
		(start 42.112946 -256.554986)
		(end 40.931338 -256.554986)
		(width 0.2794)
		(layer "B.Cu")
		(net "FAN_0_PRESENT_R")
	)
	(segment
		(start 12.7 -16.215868)
		(end 14.285722 -16.215868)
		(width 0.2794)
		(layer "F.Cu")
		(net "FAN_4_TACH_IL_D")
	)
	(segment
		(start 14.285722 -16.215868)
		(end 14.285722 -17.19961)
		(width 0.2794)
		(layer "F.Cu")
		(net "FAN_4_TACH_IL_D")
	)
	(segment
		(start 14.285722 -17.19961)
		(end 14.95298 -17.866868)
		(width 0.2794)
		(layer "F.Cu")
		(net "FAN_4_TACH_IL_D")
	)
	(segment
		(start 9.425178 -13.362432)
		(end 12.278614 -16.215868)
		(width 0.2794)
		(layer "F.Cu")
		(net "FAN_4_TACH_IL_D")
	)
	(segment
		(start 7.652512 -13.362432)
		(end 9.425178 -13.362432)
		(width 0.2794)
		(layer "F.Cu")
		(net "FAN_4_TACH_IL_D")
	)
	(segment
		(start 12.278614 -16.215868)
		(end 12.7 -16.215868)
		(width 0.2794)
		(layer "F.Cu")
		(net "FAN_4_TACH_IL_D")
	)
	(segment
		(start 6.700012 -12.409932)
		(end 7.652512 -13.362432)
		(width 0.2794)
		(layer "F.Cu")
		(net "FAN_4_TACH_IL_D")
	)
	(via
		(at 12.7 -16.215868)
		(size 0.762)
		(drill 0.381)
		(layers "F.Cu" "B.Cu")
		(net "FAN_4_TACH_IL_D")
	)
	(segment
		(start 16.120872 -18.984976)
		(end 16.120872 -19.136868)
		(width 0.2794)
		(layer "F.Cu")
		(net "FAN_4_PWM_IL_R")
	)
	(segment
		(start 13.961872 -19.136868)
		(end 13.961872 -19.077178)
		(width 0.2794)
		(layer "F.Cu")
		(net "FAN_4_PWM_IL_R")
	)
	(segment
		(start 15.536672 -18.552668)
		(end 16.120872 -19.136868)
		(width 0.2794)
		(layer "F.Cu")
		(net "FAN_4_PWM_IL_R")
	)
	(segment
		(start 12.271502 -17.446498)
		(end 10.192004 -15.367)
		(width 0.2794)
		(layer "F.Cu")
		(net "FAN_4_PWM_IL_R")
	)
	(segment
		(start 14.486382 -18.552668)
		(end 15.536672 -18.552668)
		(width 0.2794)
		(layer "F.Cu")
		(net "FAN_4_PWM_IL_R")
	)
	(segment
		(start 7.657084 -15.367)
		(end 6.700012 -14.409928)
		(width 0.2794)
		(layer "F.Cu")
		(net "FAN_4_PWM_IL_R")
	)
	(segment
		(start 13.961872 -19.136868)
		(end 12.271502 -17.446498)
		(width 0.2794)
		(layer "F.Cu")
		(net "FAN_4_PWM_IL_R")
	)
	(segment
		(start 13.961872 -19.077178)
		(end 14.486382 -18.552668)
		(width 0.2794)
		(layer "F.Cu")
		(net "FAN_4_PWM_IL_R")
	)
	(segment
		(start 16.690848 -18.415)
		(end 16.120872 -18.984976)
		(width 0.2794)
		(layer "F.Cu")
		(net "FAN_4_PWM_IL_R")
	)
	(segment
		(start 10.192004 -15.367)
		(end 7.657084 -15.367)
		(width 0.2794)
		(layer "F.Cu")
		(net "FAN_4_PWM_IL_R")
	)
	(segment
		(start 18.244058 -19.006058)
		(end 17.653 -18.415)
		(width 0.2794)
		(layer "F.Cu")
		(net "FAN_4_PWM_IL_R")
	)
	(segment
		(start 18.244058 -19.098768)
		(end 18.244058 -19.006058)
		(width 0.2794)
		(layer "F.Cu")
		(net "FAN_4_PWM_IL_R")
	)
	(segment
		(start 17.653 -18.415)
		(end 16.690848 -18.415)
		(width 0.2794)
		(layer "F.Cu")
		(net "FAN_4_PWM_IL_R")
	)
	(via
		(at 12.271502 -17.446498)
		(size 0.762)
		(drill 0.381)
		(layers "F.Cu" "B.Cu")
		(net "FAN_4_PWM_IL_R")
	)
	(segment
		(start 49.55921 -130.203956)
		(end 49.55921 -137.130536)
		(width 0.2794)
		(layer "F.Cu")
		(net "P52V_FAN_EN")
	)
	(segment
		(start 32.52851 -184.69356)
		(end 32.87395 -185.039)
		(width 0.2794)
		(layer "F.Cu")
		(net "P52V_FAN_EN")
	)
	(segment
		(start 27.312366 -21.394166)
		(end 25.95245 -21.394166)
		(width 0.2794)
		(layer "F.Cu")
		(net "P52V_FAN_EN")
	)
	(segment
		(start 36.423092 -163.553648)
		(end 36.0426 -163.93414)
		(width 0.2794)
		(layer "F.Cu")
		(net "P52V_FAN_EN")
	)
	(segment
		(start 28.448 -22.5298)
		(end 27.312366 -21.394166)
		(width 0.2794)
		(layer "F.Cu")
		(net "P52V_FAN_EN")
	)
	(segment
		(start 42.037254 -122.682)
		(end 49.55921 -130.203956)
		(width 0.2794)
		(layer "F.Cu")
		(net "P52V_FAN_EN")
	)
	(segment
		(start 29.95295 -190.952628)
		(end 30.595316 -190.310262)
		(width 0.2794)
		(layer "F.Cu")
		(net "P52V_FAN_EN")
	)
	(segment
		(start 32.52851 -184.293764)
		(end 32.52851 -184.69356)
		(width 0.2794)
		(layer "F.Cu")
		(net "P52V_FAN_EN")
	)
	(segment
		(start 43.2308 -162.3822)
		(end 41.797732 -162.3822)
		(width 0.2794)
		(layer "F.Cu")
		(net "P52V_FAN_EN")
	)
	(segment
		(start 40.164004 -163.05784)
		(end 37.620194 -163.05784)
		(width 0.2794)
		(layer "F.Cu")
		(net "P52V_FAN_EN")
	)
	(segment
		(start 46.609 -140.080746)
		(end 46.609 -159.004)
		(width 0.2794)
		(layer "F.Cu")
		(net "P52V_FAN_EN")
	)
	(segment
		(start 49.55921 -137.130536)
		(end 46.609 -140.080746)
		(width 0.2794)
		(layer "F.Cu")
		(net "P52V_FAN_EN")
	)
	(segment
		(start 30.595316 -190.310262)
		(end 30.870144 -190.310262)
		(width 0.2794)
		(layer "F.Cu")
		(net "P52V_FAN_EN")
	)
	(segment
		(start 25.67305 -21.114766)
		(end 25.67305 -20.713954)
		(width 0.2794)
		(layer "F.Cu")
		(net "P52V_FAN_EN")
	)
	(segment
		(start 37.592 -122.682)
		(end 42.037254 -122.682)
		(width 0.2794)
		(layer "F.Cu")
		(net "P52V_FAN_EN")
	)
	(segment
		(start 41.797732 -162.3822)
		(end 40.164004 -163.05784)
		(width 0.2794)
		(layer "F.Cu")
		(net "P52V_FAN_EN")
	)
	(segment
		(start 29.95295 -191.008)
		(end 29.95295 -190.952628)
		(width 0.2794)
		(layer "F.Cu")
		(net "P52V_FAN_EN")
	)
	(segment
		(start 46.609 -159.004)
		(end 43.2308 -162.3822)
		(width 0.2794)
		(layer "F.Cu")
		(net "P52V_FAN_EN")
	)
	(segment
		(start 37.620194 -163.05784)
		(end 36.423092 -163.553648)
		(width 0.2794)
		(layer "F.Cu")
		(net "P52V_FAN_EN")
	)
	(segment
		(start 25.95245 -21.394166)
		(end 25.67305 -21.114766)
		(width 0.2794)
		(layer "F.Cu")
		(net "P52V_FAN_EN")
	)
	(via
		(at 30.870144 -190.310262)
		(size 0.508)
		(drill 0.254)
		(layers "F.Cu" "B.Cu")
		(net "P52V_FAN_EN")
	)
	(via
		(at 37.592 -122.682)
		(size 0.508)
		(drill 0.254)
		(layers "F.Cu" "B.Cu")
		(net "P52V_FAN_EN")
	)
	(via
		(at 32.52851 -184.293764)
		(size 0.508)
		(drill 0.254)
		(layers "F.Cu" "B.Cu")
		(net "P52V_FAN_EN")
	)
	(via
		(at 28.448 -22.5298)
		(size 0.508)
		(drill 0.254)
		(layers "F.Cu" "B.Cu")
		(net "P52V_FAN_EN")
	)
	(via
		(at 36.0426 -163.93414)
		(size 0.508)
		(drill 0.254)
		(layers "F.Cu" "B.Cu")
		(net "P52V_FAN_EN")
	)
	(segment
		(start 31.877 -189.303406)
		(end 31.877 -184.945274)
		(width 0.2286)
		(layer "In2.Cu")
		(net "P52V_FAN_EN")
	)
	(segment
		(start 34.925 -117.19814)
		(end 34.925 -120.015)
		(width 0.2286)
		(layer "In2.Cu")
		(net "P52V_FAN_EN")
	)
	(segment
		(start 20.17903 -38.113716)
		(end 20.17903 -51.830986)
		(width 0.2286)
		(layer "In2.Cu")
		(net "P52V_FAN_EN")
	)
	(segment
		(start 26.087578 -112.158018)
		(end 29.80436 -115.8748)
		(width 0.2286)
		(layer "In2.Cu")
		(net "P52V_FAN_EN")
	)
	(segment
		(start 36.0426 -181.194202)
		(end 32.943038 -184.293764)
		(width 0.2286)
		(layer "In2.Cu")
		(net "P52V_FAN_EN")
	)
	(segment
		(start 27.0256 -23.9522)
		(end 27.0256 -31.267146)
		(width 0.2286)
		(layer "In2.Cu")
		(net "P52V_FAN_EN")
	)
	(segment
		(start 30.870144 -190.310262)
		(end 31.877 -189.303406)
		(width 0.2286)
		(layer "In2.Cu")
		(net "P52V_FAN_EN")
	)
	(segment
		(start 27.0256 -31.267146)
		(end 20.17903 -38.113716)
		(width 0.2286)
		(layer "In2.Cu")
		(net "P52V_FAN_EN")
	)
	(segment
		(start 24.65578 -83.41106)
		(end 25.197816 -83.953096)
		(width 0.2286)
		(layer "In2.Cu")
		(net "P52V_FAN_EN")
	)
	(segment
		(start 33.60166 -115.8748)
		(end 34.925 -117.19814)
		(width 0.2286)
		(layer "In2.Cu")
		(net "P52V_FAN_EN")
	)
	(segment
		(start 36.0426 -163.93414)
		(end 36.0426 -181.194202)
		(width 0.2286)
		(layer "In2.Cu")
		(net "P52V_FAN_EN")
	)
	(segment
		(start 28.448 -22.5298)
		(end 27.0256 -23.9522)
		(width 0.2286)
		(layer "In2.Cu")
		(net "P52V_FAN_EN")
	)
	(segment
		(start 31.877 -184.945274)
		(end 32.52851 -184.293764)
		(width 0.2286)
		(layer "In2.Cu")
		(net "P52V_FAN_EN")
	)
	(segment
		(start 25.197816 -100.098352)
		(end 26.087578 -100.988114)
		(width 0.2286)
		(layer "In2.Cu")
		(net "P52V_FAN_EN")
	)
	(segment
		(start 29.80436 -115.8748)
		(end 33.60166 -115.8748)
		(width 0.2286)
		(layer "In2.Cu")
		(net "P52V_FAN_EN")
	)
	(segment
		(start 25.197816 -83.953096)
		(end 25.197816 -100.098352)
		(width 0.2286)
		(layer "In2.Cu")
		(net "P52V_FAN_EN")
	)
	(segment
		(start 34.925 -120.015)
		(end 37.592 -122.682)
		(width 0.2286)
		(layer "In2.Cu")
		(net "P52V_FAN_EN")
	)
	(segment
		(start 26.087578 -100.988114)
		(end 26.087578 -112.158018)
		(width 0.2286)
		(layer "In2.Cu")
		(net "P52V_FAN_EN")
	)
	(segment
		(start 32.943038 -184.293764)
		(end 32.52851 -184.293764)
		(width 0.2286)
		(layer "In2.Cu")
		(net "P52V_FAN_EN")
	)
	(segment
		(start 20.17903 -51.830986)
		(end 24.65578 -62.655196)
		(width 0.2286)
		(layer "In2.Cu")
		(net "P52V_FAN_EN")
	)
	(segment
		(start 24.65578 -62.655196)
		(end 24.65578 -83.41106)
		(width 0.2286)
		(layer "In2.Cu")
		(net "P52V_FAN_EN")
	)
	(segment
		(start 36.703 -21.69795)
		(end 37.483288 -21.69795)
		(width 0.2794)
		(layer "F.Cu")
		(net "FAN_3_FAIL_R_LED_N")
	)
	(segment
		(start 37.483288 -21.69795)
		(end 37.762942 -21.977604)
		(width 0.2794)
		(layer "F.Cu")
		(net "FAN_3_FAIL_R_LED_N")
	)
	(segment
		(start 41.402 -20.701254)
		(end 39.822628 -22.280626)
		(width 0.2794)
		(layer "F.Cu")
		(net "FAN_3_FAIL_R_LED_N")
	)
	(segment
		(start 39.822628 -22.280626)
		(end 38.227254 -23.876)
		(width 0.2794)
		(layer "F.Cu")
		(net "FAN_3_FAIL_R_LED_N")
	)
	(segment
		(start 37.762942 -21.977604)
		(end 37.762942 -23.876)
		(width 0.2794)
		(layer "F.Cu")
		(net "FAN_3_FAIL_R_LED_N")
	)
	(segment
		(start 42.999914 -16.409924)
		(end 41.402 -18.007838)
		(width 0.2794)
		(layer "F.Cu")
		(net "FAN_3_FAIL_R_LED_N")
	)
	(segment
		(start 41.402 -18.007838)
		(end 41.402 -20.701254)
		(width 0.2794)
		(layer "F.Cu")
		(net "FAN_3_FAIL_R_LED_N")
	)
	(segment
		(start 38.227254 -23.876)
		(end 37.762942 -23.876)
		(width 0.2794)
		(layer "F.Cu")
		(net "FAN_3_FAIL_R_LED_N")
	)
	(via
		(at 39.822628 -22.280626)
		(size 0.762)
		(drill 0.381)
		(layers "F.Cu" "B.Cu")
		(net "FAN_3_FAIL_R_LED_N")
	)
	(segment
		(start 23.495 -214.86495)
		(end 24.61895 -214.86495)
		(width 0.2794)
		(layer "F.Cu")
		(net "FAN_6_PRESENT")
	)
	(segment
		(start 23.490936 -214.869014)
		(end 23.495 -214.86495)
		(width 0.2794)
		(layer "F.Cu")
		(net "FAN_6_PRESENT")
	)
	(segment
		(start 4.97205 -251.31395)
		(end 5.08 -251.206)
		(width 0.2794)
		(layer "F.Cu")
		(net "FAN_6_PRESENT")
	)
	(segment
		(start 4.318 -251.31395)
		(end 4.97205 -251.31395)
		(width 0.2794)
		(layer "F.Cu")
		(net "FAN_6_PRESENT")
	)
	(segment
		(start 24.61895 -214.86495)
		(end 25.146 -215.392)
		(width 0.2794)
		(layer "F.Cu")
		(net "FAN_6_PRESENT")
	)
	(segment
		(start 22.1361 -214.869014)
		(end 23.490936 -214.869014)
		(width 0.2794)
		(layer "F.Cu")
		(net "FAN_6_PRESENT")
	)
	(via
		(at 20.32 -249.084846)
		(size 0.6604)
		(drill 0.3302)
		(layers "F.Cu" "B.Cu")
		(net "FAN_6_PRESENT")
	)
	(via
		(at 25.146 -215.392)
		(size 0.508)
		(drill 0.254)
		(layers "F.Cu" "B.Cu")
		(net "FAN_6_PRESENT")
	)
	(via
		(at 5.08 -251.206)
		(size 0.508)
		(drill 0.254)
		(layers "F.Cu" "B.Cu")
		(net "FAN_6_PRESENT")
	)
	(segment
		(start 4.572 -250.698)
		(end 5.08 -251.206)
		(width 0.2794)
		(layer "B.Cu")
		(net "FAN_6_PRESENT")
	)
	(segment
		(start 2.159 -250.698)
		(end 4.572 -250.698)
		(width 0.2794)
		(layer "B.Cu")
		(net "FAN_6_PRESENT")
	)
	(segment
		(start 8.128 -255.651)
		(end 2.286 -255.651)
		(width 0.2794)
		(layer "B.Cu")
		(net "FAN_6_PRESENT")
	)
	(segment
		(start 20.32 -220.218)
		(end 20.32 -249.084846)
		(width 0.2794)
		(layer "B.Cu")
		(net "FAN_6_PRESENT")
	)
	(segment
		(start 5.08 -251.31014)
		(end 4.560062 -251.830078)
		(width 0.2794)
		(layer "B.Cu")
		(net "FAN_6_PRESENT")
	)
	(segment
		(start 1.651 -255.016)
		(end 1.651 -251.206)
		(width 0.2794)
		(layer "B.Cu")
		(net "FAN_6_PRESENT")
	)
	(segment
		(start 25.146 -215.392)
		(end 20.32 -220.218)
		(width 0.2794)
		(layer "B.Cu")
		(net "FAN_6_PRESENT")
	)
	(segment
		(start 18.845022 -254.204978)
		(end 9.574022 -254.204978)
		(width 0.2794)
		(layer "B.Cu")
		(net "FAN_6_PRESENT")
	)
	(segment
		(start 20.32 -252.73)
		(end 18.845022 -254.204978)
		(width 0.2794)
		(layer "B.Cu")
		(net "FAN_6_PRESENT")
	)
	(segment
		(start 2.286 -255.651)
		(end 1.651 -255.016)
		(width 0.2794)
		(layer "B.Cu")
		(net "FAN_6_PRESENT")
	)
	(segment
		(start 1.651 -251.206)
		(end 2.159 -250.698)
		(width 0.2794)
		(layer "B.Cu")
		(net "FAN_6_PRESENT")
	)
	(segment
		(start 9.574022 -254.204978)
		(end 8.128 -255.651)
		(width 0.2794)
		(layer "B.Cu")
		(net "FAN_6_PRESENT")
	)
	(segment
		(start 20.32 -249.084846)
		(end 20.32 -252.73)
		(width 0.2794)
		(layer "B.Cu")
		(net "FAN_6_PRESENT")
	)
	(segment
		(start 5.08 -251.206)
		(end 5.08 -251.31014)
		(width 0.2794)
		(layer "B.Cu")
		(net "FAN_6_PRESENT")
	)
	(segment
		(start 14.45895 -133.604)
		(end 14.45895 -134.239)
		(width 0.2794)
		(layer "F.Cu")
		(net "FAN_6_TACH_OL")
	)
	(segment
		(start 16.99895 -211.836)
		(end 16.36395 -212.471)
		(width 0.2794)
		(layer "F.Cu")
		(net "FAN_6_TACH_OL")
	)
	(segment
		(start 16.36395 -212.471)
		(end 13.0302 -212.471)
		(width 0.2794)
		(layer "F.Cu")
		(net "FAN_6_TACH_OL")
	)
	(segment
		(start 13.0302 -212.471)
		(end 12.144502 -211.585302)
		(width 0.2794)
		(layer "F.Cu")
		(net "FAN_6_TACH_OL")
	)
	(via
		(at 14.45895 -134.239)
		(size 0.508)
		(drill 0.254)
		(layers "F.Cu" "B.Cu")
		(net "FAN_6_TACH_OL")
	)
	(via
		(at 12.144502 -211.585302)
		(size 0.508)
		(drill 0.254)
		(layers "F.Cu" "B.Cu")
		(net "FAN_6_TACH_OL")
	)
	(segment
		(start 16.578326 -133.096)
		(end 15.435326 -134.239)
		(width 0.2794)
		(layer "B.Cu")
		(net "FAN_6_TACH_OL")
	)
	(segment
		(start 15.435326 -134.239)
		(end 14.45895 -134.239)
		(width 0.2794)
		(layer "B.Cu")
		(net "FAN_6_TACH_OL")
	)
	(segment
		(start 17.25295 -133.096)
		(end 16.578326 -133.096)
		(width 0.2794)
		(layer "B.Cu")
		(net "FAN_6_TACH_OL")
	)
	(segment
		(start 19.1516 -172.72)
		(end 19.1516 -167.239696)
		(width 0.2286)
		(layer "In2.Cu")
		(net "FAN_6_TACH_OL")
	)
	(segment
		(start 15.00886 -134.78891)
		(end 14.45895 -134.239)
		(width 0.2286)
		(layer "In2.Cu")
		(net "FAN_6_TACH_OL")
	)
	(segment
		(start 19.1516 -167.239696)
		(end 16.11122 -164.199316)
		(width 0.2286)
		(layer "In2.Cu")
		(net "FAN_6_TACH_OL")
	)
	(segment
		(start 18.3896 -177.671984)
		(end 18.3896 -173.482)
		(width 0.2286)
		(layer "In2.Cu")
		(net "FAN_6_TACH_OL")
	)
	(segment
		(start 18.3896 -173.482)
		(end 19.1516 -172.72)
		(width 0.2286)
		(layer "In2.Cu")
		(net "FAN_6_TACH_OL")
	)
	(segment
		(start 16.11122 -164.199316)
		(end 16.11122 -143.00327)
		(width 0.2286)
		(layer "In2.Cu")
		(net "FAN_6_TACH_OL")
	)
	(segment
		(start 15.00886 -136.4742)
		(end 15.00886 -134.78891)
		(width 0.2286)
		(layer "In2.Cu")
		(net "FAN_6_TACH_OL")
	)
	(segment
		(start 15.19682 -136.66216)
		(end 15.00886 -136.4742)
		(width 0.2286)
		(layer "In2.Cu")
		(net "FAN_6_TACH_OL")
	)
	(segment
		(start 12.144502 -183.917082)
		(end 18.3896 -177.671984)
		(width 0.2286)
		(layer "In2.Cu")
		(net "FAN_6_TACH_OL")
	)
	(segment
		(start 16.11122 -143.00327)
		(end 15.19682 -140.795756)
		(width 0.2286)
		(layer "In2.Cu")
		(net "FAN_6_TACH_OL")
	)
	(segment
		(start 12.144502 -211.585302)
		(end 12.144502 -183.917082)
		(width 0.2286)
		(layer "In2.Cu")
		(net "FAN_6_TACH_OL")
	)
	(segment
		(start 15.19682 -140.795756)
		(end 15.19682 -136.66216)
		(width 0.2286)
		(layer "In2.Cu")
		(net "FAN_6_TACH_OL")
	)
	(segment
		(start 42.999914 -14.409928)
		(end 40.386 -17.023842)
		(width 0.2794)
		(layer "F.Cu")
		(net "FAN_3_OK_R_LED_N")
	)
	(segment
		(start 40.386 -18.796)
		(end 39.8653 -19.3167)
		(width 0.2794)
		(layer "F.Cu")
		(net "FAN_3_OK_R_LED_N")
	)
	(segment
		(start 39.8653 -19.3167)
		(end 38.902132 -20.279868)
		(width 0.2794)
		(layer "F.Cu")
		(net "FAN_3_OK_R_LED_N")
	)
	(segment
		(start 37.483542 -18.14195)
		(end 37.762942 -18.42135)
		(width 0.2794)
		(layer "F.Cu")
		(net "FAN_3_OK_R_LED_N")
	)
	(segment
		(start 37.762942 -18.42135)
		(end 37.762942 -20.279868)
		(width 0.2794)
		(layer "F.Cu")
		(net "FAN_3_OK_R_LED_N")
	)
	(segment
		(start 40.386 -17.023842)
		(end 40.386 -18.796)
		(width 0.2794)
		(layer "F.Cu")
		(net "FAN_3_OK_R_LED_N")
	)
	(segment
		(start 38.902132 -20.279868)
		(end 37.762942 -20.279868)
		(width 0.2794)
		(layer "F.Cu")
		(net "FAN_3_OK_R_LED_N")
	)
	(segment
		(start 36.703 -18.14195)
		(end 37.483542 -18.14195)
		(width 0.2794)
		(layer "F.Cu")
		(net "FAN_3_OK_R_LED_N")
	)
	(via
		(at 39.8653 -19.3167)
		(size 0.762)
		(drill 0.381)
		(layers "F.Cu" "B.Cu")
		(net "FAN_3_OK_R_LED_N")
	)
	(segment
		(start 11.845544 -70.392544)
		(end 11.845544 -70.542912)
		(width 0.2794)
		(layer "F.Cu")
		(net "FAN_5_ON")
	)
	(segment
		(start 11.303 -69.282818)
		(end 11.303 -69.85)
		(width 0.2794)
		(layer "F.Cu")
		(net "FAN_5_ON")
	)
	(segment
		(start 11.303 -69.85)
		(end 11.845544 -70.392544)
		(width 0.2794)
		(layer "F.Cu")
		(net "FAN_5_ON")
	)
	(via
		(at 13.549122 -76.538836)
		(size 0.508)
		(drill 0.254)
		(layers "F.Cu" "B.Cu")
		(net "FAN_5_ON")
	)
	(via
		(at 11.303 -69.282818)
		(size 0.762)
		(drill 0.254)
		(layers "F.Cu" "B.Cu")
		(net "FAN_5_ON")
	)
	(segment
		(start 13.549122 -76.538836)
		(end 13.576554 -76.550266)
		(width 0.1016)
		(layer "B.Cu")
		(net "FAN_5_ON")
	)
	(segment
		(start 13.576554 -76.550266)
		(end 13.655294 -76.740258)
		(width 0.1016)
		(layer "B.Cu")
		(net "FAN_5_ON")
	)
	(segment
		(start 13.655294 -76.740258)
		(end 13.655294 -77.45476)
		(width 0.1016)
		(layer "B.Cu")
		(net "FAN_5_ON")
	)
	(segment
		(start 11.811 -76.073)
		(end 12.276836 -76.538836)
		(width 0.2286)
		(layer "In2.Cu")
		(net "FAN_5_ON")
	)
	(segment
		(start 12.276836 -76.538836)
		(end 13.549122 -76.538836)
		(width 0.2286)
		(layer "In2.Cu")
		(net "FAN_5_ON")
	)
	(segment
		(start 11.303 -72.517)
		(end 11.811 -73.025)
		(width 0.2286)
		(layer "In2.Cu")
		(net "FAN_5_ON")
	)
	(segment
		(start 11.811 -73.025)
		(end 11.811 -76.073)
		(width 0.2286)
		(layer "In2.Cu")
		(net "FAN_5_ON")
	)
	(segment
		(start 11.303 -69.282818)
		(end 11.303 -72.517)
		(width 0.2286)
		(layer "In2.Cu")
		(net "FAN_5_ON")
	)
	(segment
		(start 14.478 -136.144)
		(end 14.478 -136.779)
		(width 0.2794)
		(layer "F.Cu")
		(net "FAN_7_TACH_OL")
	)
	(segment
		(start 18.43405 -303.911)
		(end 19.05 -303.911)
		(width 0.2794)
		(layer "F.Cu")
		(net "FAN_7_TACH_OL")
	)
	(via
		(at 14.478 -136.779)
		(size 0.508)
		(drill 0.254)
		(layers "F.Cu" "B.Cu")
		(net "FAN_7_TACH_OL")
	)
	(via
		(at 19.05 -303.911)
		(size 0.508)
		(drill 0.254)
		(layers "F.Cu" "B.Cu")
		(net "FAN_7_TACH_OL")
	)
	(segment
		(start 17.018 -134.239)
		(end 14.478 -136.779)
		(width 0.2794)
		(layer "B.Cu")
		(net "FAN_7_TACH_OL")
	)
	(segment
		(start 17.25295 -134.239)
		(end 17.018 -134.239)
		(width 0.2794)
		(layer "B.Cu")
		(net "FAN_7_TACH_OL")
	)
	(segment
		(start 15.339314 -246.849392)
		(end 15.339314 -215.611202)
		(width 0.2286)
		(layer "In2.Cu")
		(net "FAN_7_TACH_OL")
	)
	(segment
		(start 14.478 -140.550138)
		(end 14.478 -136.779)
		(width 0.2286)
		(layer "In2.Cu")
		(net "FAN_7_TACH_OL")
	)
	(segment
		(start 13.0556 -287.353248)
		(end 21.8694 -278.539448)
		(width 0.2286)
		(layer "In2.Cu")
		(net "FAN_7_TACH_OL")
	)
	(segment
		(start 11.611102 -183.663082)
		(end 17.7927 -177.481484)
		(width 0.2286)
		(layer "In2.Cu")
		(net "FAN_7_TACH_OL")
	)
	(segment
		(start 17.7927 -177.481484)
		(end 17.7927 -173.1645)
		(width 0.2286)
		(layer "In2.Cu")
		(net "FAN_7_TACH_OL")
	)
	(segment
		(start 11.611102 -211.88299)
		(end 11.611102 -183.663082)
		(width 0.2286)
		(layer "In2.Cu")
		(net "FAN_7_TACH_OL")
	)
	(segment
		(start 18.6182 -167.461184)
		(end 15.574772 -164.417756)
		(width 0.2286)
		(layer "In2.Cu")
		(net "FAN_7_TACH_OL")
	)
	(segment
		(start 15.574772 -143.197834)
		(end 14.478 -140.550138)
		(width 0.2286)
		(layer "In2.Cu")
		(net "FAN_7_TACH_OL")
	)
	(segment
		(start 21.8694 -278.539448)
		(end 21.8694 -253.379478)
		(width 0.2286)
		(layer "In2.Cu")
		(net "FAN_7_TACH_OL")
	)
	(segment
		(start 13.0556 -297.408346)
		(end 13.0556 -287.353248)
		(width 0.2286)
		(layer "In2.Cu")
		(net "FAN_7_TACH_OL")
	)
	(segment
		(start 17.7927 -173.1645)
		(end 18.6182 -172.339)
		(width 0.2286)
		(layer "In2.Cu")
		(net "FAN_7_TACH_OL")
	)
	(segment
		(start 21.8694 -253.379478)
		(end 15.339314 -246.849392)
		(width 0.2286)
		(layer "In2.Cu")
		(net "FAN_7_TACH_OL")
	)
	(segment
		(start 19.05 -303.911)
		(end 19.05 -303.402746)
		(width 0.2286)
		(layer "In2.Cu")
		(net "FAN_7_TACH_OL")
	)
	(segment
		(start 18.6182 -172.339)
		(end 18.6182 -167.461184)
		(width 0.2286)
		(layer "In2.Cu")
		(net "FAN_7_TACH_OL")
	)
	(segment
		(start 19.05 -303.402746)
		(end 13.0556 -297.408346)
		(width 0.2286)
		(layer "In2.Cu")
		(net "FAN_7_TACH_OL")
	)
	(segment
		(start 15.339314 -215.611202)
		(end 11.611102 -211.88299)
		(width 0.2286)
		(layer "In2.Cu")
		(net "FAN_7_TACH_OL")
	)
	(segment
		(start 15.574772 -164.417756)
		(end 15.574772 -143.197834)
		(width 0.2286)
		(layer "In2.Cu")
		(net "FAN_7_TACH_OL")
	)
	(segment
		(start 14.474444 -71.831962)
		(end 14.874494 -71.431912)
		(width 0.2794)
		(layer "F.Cu")
		(net "FAN_5_PRESENT_R")
	)
	(segment
		(start 14.874494 -71.431912)
		(end 14.874494 -71.304912)
		(width 0.2794)
		(layer "F.Cu")
		(net "FAN_5_PRESENT_R")
	)
	(segment
		(start 14.474444 -72.066912)
		(end 14.474444 -71.831962)
		(width 0.2794)
		(layer "F.Cu")
		(net "FAN_5_PRESENT_R")
	)
	(via
		(at 14.874494 -71.304912)
		(size 0.508)
		(drill 0.254)
		(layers "F.Cu" "B.Cu")
		(net "FAN_5_PRESENT_R")
	)
	(segment
		(start 14.874494 -71.304912)
		(end 14.874494 -71.431912)
		(width 0.2794)
		(layer "B.Cu")
		(net "FAN_5_PRESENT_R")
	)
	(segment
		(start 14.351508 -71.954898)
		(end 13.1699 -71.954898)
		(width 0.2794)
		(layer "B.Cu")
		(net "FAN_5_PRESENT_R")
	)
	(segment
		(start 14.874494 -71.431912)
		(end 14.351508 -71.954898)
		(width 0.2794)
		(layer "B.Cu")
		(net "FAN_5_PRESENT_R")
	)
	(segment
		(start 14.097 -98.15195)
		(end 15.00505 -98.15195)
		(width 0.2794)
		(layer "F.Cu")
		(net "FAN_5_PRESENT")
	)
	(segment
		(start 19.939 -97.917)
		(end 20.955 -98.933)
		(width 0.2794)
		(layer "F.Cu")
		(net "FAN_5_PRESENT")
	)
	(segment
		(start 15.24 -97.917)
		(end 19.939 -97.917)
		(width 0.2794)
		(layer "F.Cu")
		(net "FAN_5_PRESENT")
	)
	(segment
		(start 15.00505 -98.15195)
		(end 15.24 -97.917)
		(width 0.2794)
		(layer "F.Cu")
		(net "FAN_5_PRESENT")
	)
	(segment
		(start 12.7381 -97.902014)
		(end 13.847064 -97.902014)
		(width 0.2794)
		(layer "F.Cu")
		(net "FAN_5_PRESENT")
	)
	(segment
		(start 15.621 -72.898)
		(end 15.274544 -72.551544)
		(width 0.2794)
		(layer "F.Cu")
		(net "FAN_5_PRESENT")
	)
	(segment
		(start 15.274544 -72.551544)
		(end 15.274544 -72.066912)
		(width 0.2794)
		(layer "F.Cu")
		(net "FAN_5_PRESENT")
	)
	(segment
		(start 13.847064 -97.902014)
		(end 14.097 -98.15195)
		(width 0.2794)
		(layer "F.Cu")
		(net "FAN_5_PRESENT")
	)
	(segment
		(start 16.383 -72.898)
		(end 15.621 -72.898)
		(width 0.2794)
		(layer "F.Cu")
		(net "FAN_5_PRESENT")
	)
	(via
		(at 16.383 -72.898)
		(size 0.508)
		(drill 0.254)
		(layers "F.Cu" "B.Cu")
		(net "FAN_5_PRESENT")
	)
	(via
		(at 20.955 -98.933)
		(size 0.508)
		(drill 0.254)
		(layers "F.Cu" "B.Cu")
		(net "FAN_5_PRESENT")
	)
	(segment
		(start 23.495 -72.898)
		(end 16.383 -72.898)
		(width 0.2794)
		(layer "B.Cu")
		(net "FAN_5_PRESENT")
	)
	(segment
		(start 25.5143 -74.9173)
		(end 23.495 -72.898)
		(width 0.2794)
		(layer "B.Cu")
		(net "FAN_5_PRESENT")
	)
	(segment
		(start 16.156432 -72.671432)
		(end 16.383 -72.898)
		(width 0.2794)
		(layer "B.Cu")
		(net "FAN_5_PRESENT")
	)
	(segment
		(start 16.156432 -72.077834)
		(end 16.156432 -72.671432)
		(width 0.2794)
		(layer "B.Cu")
		(net "FAN_5_PRESENT")
	)
	(segment
		(start 25.5143 -94.3737)
		(end 25.5143 -74.9173)
		(width 0.2794)
		(layer "B.Cu")
		(net "FAN_5_PRESENT")
	)
	(segment
		(start 20.955 -98.933)
		(end 25.5143 -94.3737)
		(width 0.2794)
		(layer "B.Cu")
		(net "FAN_5_PRESENT")
	)
	(segment
		(start 8.309864 -69.469)
		(end 8.309864 -68.256912)
		(width 0.2794)
		(layer "F.Cu")
		(net "FAN_4_ON")
	)
	(via
		(at 8.309864 -69.469)
		(size 0.762)
		(drill 0.254)
		(layers "F.Cu" "B.Cu")
		(net "FAN_4_ON")
	)
	(via
		(at 6.61416 -62.27826)
		(size 0.508)
		(drill 0.254)
		(layers "F.Cu" "B.Cu")
		(net "FAN_4_ON")
	)
	(segment
		(start 6.500114 -62.00267)
		(end 6.500114 -61.345064)
		(width 0.1016)
		(layer "B.Cu")
		(net "FAN_4_ON")
	)
	(segment
		(start 6.61416 -62.27826)
		(end 6.500114 -62.00267)
		(width 0.1016)
		(layer "B.Cu")
		(net "FAN_4_ON")
	)
	(segment
		(start 8.763 -67.670426)
		(end 8.309864 -68.123562)
		(width 0.2286)
		(layer "In2.Cu")
		(net "FAN_4_ON")
	)
	(segment
		(start 7.838186 -61.976)
		(end 8.763 -62.900814)
		(width 0.2286)
		(layer "In2.Cu")
		(net "FAN_4_ON")
	)
	(segment
		(start 6.61416 -62.232032)
		(end 6.870192 -61.976)
		(width 0.2286)
		(layer "In2.Cu")
		(net "FAN_4_ON")
	)
	(segment
		(start 6.870192 -61.976)
		(end 7.838186 -61.976)
		(width 0.2286)
		(layer "In2.Cu")
		(net "FAN_4_ON")
	)
	(segment
		(start 8.763 -62.900814)
		(end 8.763 -67.670426)
		(width 0.2286)
		(layer "In2.Cu")
		(net "FAN_4_ON")
	)
	(segment
		(start 6.61416 -62.27826)
		(end 6.61416 -62.232032)
		(width 0.2286)
		(layer "In2.Cu")
		(net "FAN_4_ON")
	)
	(segment
		(start 8.309864 -68.123562)
		(end 8.309864 -69.469)
		(width 0.2286)
		(layer "In2.Cu")
		(net "FAN_4_ON")
	)
	(segment
		(start 14.45895 -125.857)
		(end 14.45895 -126.492)
		(width 0.2794)
		(layer "F.Cu")
		(net "FAN_4_TACH_OL")
	)
	(segment
		(start 18.161 -32.40405)
		(end 18.161 -33.02)
		(width 0.2794)
		(layer "F.Cu")
		(net "FAN_4_TACH_OL")
	)
	(via
		(at 14.45895 -126.492)
		(size 0.508)
		(drill 0.254)
		(layers "F.Cu" "B.Cu")
		(net "FAN_4_TACH_OL")
	)
	(via
		(at 18.161 -33.02)
		(size 0.508)
		(drill 0.254)
		(layers "F.Cu" "B.Cu")
		(net "FAN_4_TACH_OL")
	)
	(segment
		(start 17.25295 -128.524)
		(end 16.49095 -128.524)
		(width 0.2794)
		(layer "B.Cu")
		(net "FAN_4_TACH_OL")
	)
	(segment
		(start 16.49095 -128.524)
		(end 14.45895 -126.492)
		(width 0.2794)
		(layer "B.Cu")
		(net "FAN_4_TACH_OL")
	)
	(segment
		(start 18.161 -33.02)
		(end 16.463772 -34.717228)
		(width 0.2286)
		(layer "In2.Cu")
		(net "FAN_4_TACH_OL")
	)
	(segment
		(start 19.58086 -108.81614)
		(end 19.58086 -113.247678)
		(width 0.2286)
		(layer "In2.Cu")
		(net "FAN_4_TACH_OL")
	)
	(segment
		(start 20.99818 -84.927186)
		(end 21.540216 -85.469222)
		(width 0.2286)
		(layer "In2.Cu")
		(net "FAN_4_TACH_OL")
	)
	(segment
		(start 22.429978 -102.62743)
		(end 22.429978 -105.967022)
		(width 0.2286)
		(layer "In2.Cu")
		(net "FAN_4_TACH_OL")
	)
	(segment
		(start 22.429978 -105.967022)
		(end 19.58086 -108.81614)
		(width 0.2286)
		(layer "In2.Cu")
		(net "FAN_4_TACH_OL")
	)
	(segment
		(start 18.048478 -122.902472)
		(end 14.45895 -126.492)
		(width 0.2286)
		(layer "In2.Cu")
		(net "FAN_4_TACH_OL")
	)
	(segment
		(start 19.1262 -113.702338)
		(end 19.1262 -117.286278)
		(width 0.2286)
		(layer "In2.Cu")
		(net "FAN_4_TACH_OL")
	)
	(segment
		(start 16.463772 -52.421282)
		(end 20.99818 -63.38443)
		(width 0.2286)
		(layer "In2.Cu")
		(net "FAN_4_TACH_OL")
	)
	(segment
		(start 18.048478 -118.364)
		(end 18.048478 -122.902472)
		(width 0.2286)
		(layer "In2.Cu")
		(net "FAN_4_TACH_OL")
	)
	(segment
		(start 16.463772 -34.717228)
		(end 16.463772 -52.421282)
		(width 0.2286)
		(layer "In2.Cu")
		(net "FAN_4_TACH_OL")
	)
	(segment
		(start 19.58086 -113.247678)
		(end 19.1262 -113.702338)
		(width 0.2286)
		(layer "In2.Cu")
		(net "FAN_4_TACH_OL")
	)
	(segment
		(start 21.540216 -85.469222)
		(end 21.540216 -101.737668)
		(width 0.2286)
		(layer "In2.Cu")
		(net "FAN_4_TACH_OL")
	)
	(segment
		(start 19.1262 -117.286278)
		(end 18.048478 -118.364)
		(width 0.2286)
		(layer "In2.Cu")
		(net "FAN_4_TACH_OL")
	)
	(segment
		(start 21.540216 -101.737668)
		(end 22.429978 -102.62743)
		(width 0.2286)
		(layer "In2.Cu")
		(net "FAN_4_TACH_OL")
	)
	(segment
		(start 20.99818 -63.38443)
		(end 20.99818 -84.927186)
		(width 0.2286)
		(layer "In2.Cu")
		(net "FAN_4_TACH_OL")
	)
	(segment
		(start 5.461 -67.945)
		(end 5.461 -67.437)
		(width 0.2794)
		(layer "F.Cu")
		(net "FAN_4_PRESENT_R")
	)
	(segment
		(start 5.680964 -67.217036)
		(end 5.680964 -66.732912)
		(width 0.2794)
		(layer "F.Cu")
		(net "FAN_4_PRESENT_R")
	)
	(segment
		(start 5.461 -67.437)
		(end 5.680964 -67.217036)
		(width 0.2794)
		(layer "F.Cu")
		(net "FAN_4_PRESENT_R")
	)
	(via
		(at 5.461 -67.945)
		(size 0.762)
		(drill 0.254)
		(layers "F.Cu" "B.Cu")
		(net "FAN_4_PRESENT_R")
	)
	(segment
		(start 5.461 -67.945)
		(end 5.461 -67.437)
		(width 0.2794)
		(layer "B.Cu")
		(net "FAN_4_PRESENT_R")
	)
	(segment
		(start 6.053074 -66.844926)
		(end 6.985508 -66.844926)
		(width 0.2794)
		(layer "B.Cu")
		(net "FAN_4_PRESENT_R")
	)
	(segment
		(start 5.461 -67.437)
		(end 6.053074 -66.844926)
		(width 0.2794)
		(layer "B.Cu")
		(net "FAN_4_PRESENT_R")
	)
	(segment
		(start 22.997414 -30.719014)
		(end 22.5806 -30.3022)
		(width 0.2794)
		(layer "F.Cu")
		(net "FAN_4_PRESENT")
	)
	(segment
		(start 24.652732 -30.719014)
		(end 24.0411 -30.719014)
		(width 0.2794)
		(layer "F.Cu")
		(net "FAN_4_PRESENT")
	)
	(segment
		(start 25.4 -30.33395)
		(end 25.037796 -30.33395)
		(width 0.2794)
		(layer "F.Cu")
		(net "FAN_4_PRESENT")
	)
	(segment
		(start 4.880864 -66.732912)
		(end 4.560062 -67.053714)
		(width 0.2794)
		(layer "F.Cu")
		(net "FAN_4_PRESENT")
	)
	(segment
		(start 25.037796 -30.33395)
		(end 24.652732 -30.719014)
		(width 0.2794)
		(layer "F.Cu")
		(net "FAN_4_PRESENT")
	)
	(segment
		(start 4.560062 -67.053714)
		(end 4.560062 -67.945)
		(width 0.2794)
		(layer "F.Cu")
		(net "FAN_4_PRESENT")
	)
	(segment
		(start 24.0411 -30.719014)
		(end 22.997414 -30.719014)
		(width 0.2794)
		(layer "F.Cu")
		(net "FAN_4_PRESENT")
	)
	(via
		(at 20.447 -69.44868)
		(size 0.6604)
		(drill 0.3302)
		(layers "F.Cu" "B.Cu")
		(net "FAN_4_PRESENT")
	)
	(via
		(at 22.5806 -30.3022)
		(size 0.508)
		(drill 0.254)
		(layers "F.Cu" "B.Cu")
		(net "FAN_4_PRESENT")
	)
	(via
		(at 4.560062 -67.945)
		(size 0.508)
		(drill 0.254)
		(layers "F.Cu" "B.Cu")
		(net "FAN_4_PRESENT")
	)
	(segment
		(start 20.445222 -34.845752)
		(end 20.445222 -57.803034)
		(width 0.2794)
		(layer "B.Cu")
		(net "FAN_4_PRESENT")
	)
	(segment
		(start 15.885668 -71.247)
		(end 14.488668 -72.644)
		(width 0.2794)
		(layer "B.Cu")
		(net "FAN_4_PRESENT")
	)
	(segment
		(start 4.560062 -67.045078)
		(end 4.560062 -67.945)
		(width 0.2794)
		(layer "B.Cu")
		(net "FAN_4_PRESENT")
	)
	(segment
		(start 5.5118 -68.80987)
		(end 4.64693 -67.945)
		(width 0.2794)
		(layer "B.Cu")
		(net "FAN_4_PRESENT")
	)
	(segment
		(start 6.539738 -71.374)
		(end 5.5118 -70.346062)
		(width 0.2794)
		(layer "B.Cu")
		(net "FAN_4_PRESENT")
	)
	(segment
		(start 22.5806 -30.3022)
		(end 22.5806 -32.710374)
		(width 0.2794)
		(layer "B.Cu")
		(net "FAN_4_PRESENT")
	)
	(segment
		(start 5.5118 -70.346062)
		(end 5.5118 -68.80987)
		(width 0.2794)
		(layer "B.Cu")
		(net "FAN_4_PRESENT")
	)
	(segment
		(start 20.447 -69.44868)
		(end 20.447 -70.358)
		(width 0.2794)
		(layer "B.Cu")
		(net "FAN_4_PRESENT")
	)
	(segment
		(start 20.445222 -57.803034)
		(end 20.447 -58.317892)
		(width 0.2794)
		(layer "B.Cu")
		(net "FAN_4_PRESENT")
	)
	(segment
		(start 4.64693 -67.945)
		(end 4.560062 -67.945)
		(width 0.2794)
		(layer "B.Cu")
		(net "FAN_4_PRESENT")
	)
	(segment
		(start 20.447 -70.358)
		(end 19.558 -71.247)
		(width 0.2794)
		(layer "B.Cu")
		(net "FAN_4_PRESENT")
	)
	(segment
		(start 10.033 -72.644)
		(end 8.763 -71.374)
		(width 0.2794)
		(layer "B.Cu")
		(net "FAN_4_PRESENT")
	)
	(segment
		(start 20.447 -58.317892)
		(end 20.447 -69.44868)
		(width 0.2794)
		(layer "B.Cu")
		(net "FAN_4_PRESENT")
	)
	(segment
		(start 14.488668 -72.644)
		(end 10.033 -72.644)
		(width 0.2794)
		(layer "B.Cu")
		(net "FAN_4_PRESENT")
	)
	(segment
		(start 22.5806 -32.710374)
		(end 20.445222 -34.845752)
		(width 0.2794)
		(layer "B.Cu")
		(net "FAN_4_PRESENT")
	)
	(segment
		(start 8.763 -71.374)
		(end 6.539738 -71.374)
		(width 0.2794)
		(layer "B.Cu")
		(net "FAN_4_PRESENT")
	)
	(segment
		(start 19.558 -71.247)
		(end 15.885668 -71.247)
		(width 0.2794)
		(layer "B.Cu")
		(net "FAN_4_PRESENT")
	)
	(segment
		(start 29.5148 -20.05076)
		(end 29.464 -19.99996)
		(width 0.2794)
		(layer "F.Cu")
		(net "FAN_4_PWM")
	)
	(segment
		(start 23.064978 -112.165384)
		(end 27.1399 -112.165384)
		(width 0.2794)
		(layer "F.Cu")
		(net "FAN_4_PWM")
	)
	(segment
		(start 29.5148 -21.17725)
		(end 29.5148 -20.05076)
		(width 0.2794)
		(layer "F.Cu")
		(net "FAN_4_PWM")
	)
	(segment
		(start 21.819362 -113.411)
		(end 23.064978 -112.165384)
		(width 0.2794)
		(layer "F.Cu")
		(net "FAN_4_PWM")
	)
	(segment
		(start 17.526 -113.411)
		(end 21.819362 -113.411)
		(width 0.2794)
		(layer "F.Cu")
		(net "FAN_4_PWM")
	)
	(segment
		(start 17.272 -113.665)
		(end 17.526 -113.411)
		(width 0.2794)
		(layer "F.Cu")
		(net "FAN_4_PWM")
	)
	(segment
		(start 17.018 -115.443)
		(end 17.272 -115.189)
		(width 0.2794)
		(layer "F.Cu")
		(net "FAN_4_PWM")
	)
	(segment
		(start 14.859 -115.443)
		(end 17.018 -115.443)
		(width 0.2794)
		(layer "F.Cu")
		(net "FAN_4_PWM")
	)
	(segment
		(start 29.48305 -21.209)
		(end 29.5148 -21.17725)
		(width 0.2794)
		(layer "F.Cu")
		(net "FAN_4_PWM")
	)
	(segment
		(start 30.09265 -21.209)
		(end 29.48305 -21.209)
		(width 0.2794)
		(layer "F.Cu")
		(net "FAN_4_PWM")
	)
	(segment
		(start 17.272 -115.189)
		(end 17.272 -113.665)
		(width 0.2794)
		(layer "F.Cu")
		(net "FAN_4_PWM")
	)
	(segment
		(start 14.478 -122.047)
		(end 14.478 -122.682)
		(width 0.2794)
		(layer "F.Cu")
		(net "FAN_4_PWM")
	)
	(via
		(at 14.859 -115.443)
		(size 0.508)
		(drill 0.254)
		(layers "F.Cu" "B.Cu")
		(net "FAN_4_PWM")
	)
	(via
		(at 14.478 -122.682)
		(size 0.508)
		(drill 0.254)
		(layers "F.Cu" "B.Cu")
		(net "FAN_4_PWM")
	)
	(via
		(at 27.1399 -112.165384)
		(size 0.508)
		(drill 0.254)
		(layers "F.Cu" "B.Cu")
		(net "FAN_4_PWM")
	)
	(via
		(at 30.09265 -21.209)
		(size 0.508)
		(drill 0.254)
		(layers "F.Cu" "B.Cu")
		(net "FAN_4_PWM")
	)
	(segment
		(start 26.620978 -111.646462)
		(end 27.1399 -112.165384)
		(width 0.2286)
		(layer "In2.Cu")
		(net "FAN_4_PWM")
	)
	(segment
		(start 14.859 -115.443)
		(end 14.78534 -115.51666)
		(width 0.2286)
		(layer "In2.Cu")
		(net "FAN_4_PWM")
	)
	(segment
		(start 20.71243 -51.724306)
		(end 25.18918 -62.549024)
		(width 0.2286)
		(layer "In2.Cu")
		(net "FAN_4_PWM")
	)
	(segment
		(start 25.18918 -83.19008)
		(end 25.731216 -83.732116)
		(width 0.2286)
		(layer "In2.Cu")
		(net "FAN_4_PWM")
	)
	(segment
		(start 14.78534 -115.51666)
		(end 14.78534 -122.37466)
		(width 0.2286)
		(layer "In2.Cu")
		(net "FAN_4_PWM")
	)
	(segment
		(start 25.18918 -62.549024)
		(end 25.18918 -83.19008)
		(width 0.2286)
		(layer "In2.Cu")
		(net "FAN_4_PWM")
	)
	(segment
		(start 25.731216 -99.87026)
		(end 26.620978 -100.760022)
		(width 0.2286)
		(layer "In2.Cu")
		(net "FAN_4_PWM")
	)
	(segment
		(start 20.71243 -38.342824)
		(end 20.71243 -51.724306)
		(width 0.2286)
		(layer "In2.Cu")
		(net "FAN_4_PWM")
	)
	(segment
		(start 27.559 -24.206708)
		(end 27.559 -31.496254)
		(width 0.2286)
		(layer "In2.Cu")
		(net "FAN_4_PWM")
	)
	(segment
		(start 26.620978 -100.760022)
		(end 26.620978 -111.646462)
		(width 0.2286)
		(layer "In2.Cu")
		(net "FAN_4_PWM")
	)
	(segment
		(start 27.559 -31.496254)
		(end 20.71243 -38.342824)
		(width 0.2286)
		(layer "In2.Cu")
		(net "FAN_4_PWM")
	)
	(segment
		(start 14.78534 -122.37466)
		(end 14.478 -122.682)
		(width 0.2286)
		(layer "In2.Cu")
		(net "FAN_4_PWM")
	)
	(segment
		(start 30.09265 -21.209)
		(end 30.092904 -21.671788)
		(width 0.2286)
		(layer "In2.Cu")
		(net "FAN_4_PWM")
	)
	(segment
		(start 25.731216 -83.732116)
		(end 25.731216 -99.87026)
		(width 0.2286)
		(layer "In2.Cu")
		(net "FAN_4_PWM")
	)
	(segment
		(start 30.092904 -21.671788)
		(end 27.559 -24.206708)
		(width 0.2286)
		(layer "In2.Cu")
		(net "FAN_4_PWM")
	)
	(segment
		(start 36.449 -68.8086)
		(end 37.3634 -68.8086)
		(width 0.2794)
		(layer "F.Cu")
		(net "FAN_3_ON")
	)
	(segment
		(start 37.915088 -68.256912)
		(end 39.727378 -68.256912)
		(width 0.2794)
		(layer "F.Cu")
		(net "FAN_3_ON")
	)
	(segment
		(start 36.1696 -68.5292)
		(end 36.449 -68.8086)
		(width 0.2794)
		(layer "F.Cu")
		(net "FAN_3_ON")
	)
	(segment
		(start 37.3634 -68.8086)
		(end 37.915088 -68.256912)
		(width 0.2794)
		(layer "F.Cu")
		(net "FAN_3_ON")
	)
	(via
		(at 36.1696 -68.5292)
		(size 0.762)
		(drill 0.254)
		(layers "F.Cu" "B.Cu")
		(net "FAN_3_ON")
	)
	(via
		(at 38.227 -62.738)
		(size 0.508)
		(drill 0.254)
		(layers "F.Cu" "B.Cu")
		(net "FAN_3_ON")
	)
	(segment
		(start 38.227 -62.68085)
		(end 37.917628 -61.933582)
		(width 0.1016)
		(layer "B.Cu")
		(net "FAN_3_ON")
	)
	(segment
		(start 37.917628 -61.933582)
		(end 37.917628 -61.345064)
		(width 0.1016)
		(layer "B.Cu")
		(net "FAN_3_ON")
	)
	(segment
		(start 38.227 -62.738)
		(end 38.227 -62.68085)
		(width 0.1016)
		(layer "B.Cu")
		(net "FAN_3_ON")
	)
	(segment
		(start 35.7378 -66.5226)
		(end 36.1696 -66.9544)
		(width 0.2286)
		(layer "In2.Cu")
		(net "FAN_3_ON")
	)
	(segment
		(start 37.338 -62.738)
		(end 35.7378 -64.3382)
		(width 0.2286)
		(layer "In2.Cu")
		(net "FAN_3_ON")
	)
	(segment
		(start 38.227 -62.738)
		(end 37.338 -62.738)
		(width 0.2286)
		(layer "In2.Cu")
		(net "FAN_3_ON")
	)
	(segment
		(start 35.7378 -64.3382)
		(end 35.7378 -66.5226)
		(width 0.2286)
		(layer "In2.Cu")
		(net "FAN_3_ON")
	)
	(segment
		(start 36.1696 -66.9544)
		(end 36.1696 -68.5292)
		(width 0.2286)
		(layer "In2.Cu")
		(net "FAN_3_ON")
	)
	(segment
		(start 37.06495 -32.40405)
		(end 36.322 -33.147)
		(width 0.2794)
		(layer "F.Cu")
		(net "FAN_3_PWM_OL")
	)
	(segment
		(start 32.03448 -31.75)
		(end 30.84195 -31.75)
		(width 0.2794)
		(layer "F.Cu")
		(net "FAN_3_PWM_OL")
	)
	(segment
		(start 27.76855 -26.303986)
		(end 28.04795 -26.583386)
		(width 0.2794)
		(layer "F.Cu")
		(net "FAN_3_PWM_OL")
	)
	(segment
		(start 26.60396 -26.303986)
		(end 27.76855 -26.303986)
		(width 0.2794)
		(layer "F.Cu")
		(net "FAN_3_PWM_OL")
	)
	(segment
		(start 28.04795 -26.583386)
		(end 28.04795 -28.956)
		(width 0.2794)
		(layer "F.Cu")
		(net "FAN_3_PWM_OL")
	)
	(segment
		(start 33.43148 -33.147)
		(end 32.03448 -31.75)
		(width 0.2794)
		(layer "F.Cu")
		(net "FAN_3_PWM_OL")
	)
	(segment
		(start 37.06495 -32.217868)
		(end 37.06495 -32.40405)
		(width 0.2794)
		(layer "F.Cu")
		(net "FAN_3_PWM_OL")
	)
	(segment
		(start 30.84195 -31.75)
		(end 28.04795 -28.956)
		(width 0.2794)
		(layer "F.Cu")
		(net "FAN_3_PWM_OL")
	)
	(segment
		(start 36.322 -33.147)
		(end 33.43148 -33.147)
		(width 0.2794)
		(layer "F.Cu")
		(net "FAN_3_PWM_OL")
	)
	(via
		(at 28.04795 -28.956)
		(size 0.762)
		(drill 0.381)
		(layers "F.Cu" "B.Cu")
		(net "FAN_3_PWM_OL")
	)
	(segment
		(start 37.098478 -66.732912)
		(end 37.098478 -66.967862)
		(width 0.2794)
		(layer "F.Cu")
		(net "FAN_3_PRESENT_R")
	)
	(segment
		(start 37.098478 -66.967862)
		(end 36.698428 -67.367912)
		(width 0.2794)
		(layer "F.Cu")
		(net "FAN_3_PRESENT_R")
	)
	(segment
		(start 36.698428 -67.367912)
		(end 36.698428 -67.494912)
		(width 0.2794)
		(layer "F.Cu")
		(net "FAN_3_PRESENT_R")
	)
	(via
		(at 36.698428 -67.494912)
		(size 0.508)
		(drill 0.254)
		(layers "F.Cu" "B.Cu")
		(net "FAN_3_PRESENT_R")
	)
	(segment
		(start 36.698428 -67.367912)
		(end 37.221414 -66.844926)
		(width 0.2794)
		(layer "B.Cu")
		(net "FAN_3_PRESENT_R")
	)
	(segment
		(start 36.698428 -67.494912)
		(end 36.698428 -67.367912)
		(width 0.2794)
		(layer "B.Cu")
		(net "FAN_3_PRESENT_R")
	)
	(segment
		(start 37.221414 -66.844926)
		(end 38.403022 -66.844926)
		(width 0.2794)
		(layer "B.Cu")
		(net "FAN_3_PRESENT_R")
	)
	(segment
		(start 37.973 -130.683)
		(end 37.021516 -130.683)
		(width 0.2794)
		(layer "F.Cu")
		(net "FAN_2_PWM")
	)
	(segment
		(start 23.51405 -113.411)
		(end 25.61209 -113.411)
		(width 0.2794)
		(layer "F.Cu")
		(net "FAN_2_PWM")
	)
	(segment
		(start 38.24605 -130.40995)
		(end 37.973 -130.683)
		(width 0.2794)
		(layer "F.Cu")
		(net "FAN_2_PWM")
	)
	(segment
		(start 22.479 -114.44605)
		(end 22.479 -115.63604)
		(width 0.2794)
		(layer "F.Cu")
		(net "FAN_2_PWM")
	)
	(segment
		(start 22.49805 -114.427)
		(end 22.479 -114.44605)
		(width 0.2794)
		(layer "F.Cu")
		(net "FAN_2_PWM")
	)
	(segment
		(start 38.24605 -130.048)
		(end 38.24605 -130.40995)
		(width 0.2794)
		(layer "F.Cu")
		(net "FAN_2_PWM")
	)
	(segment
		(start 22.49805 -114.427)
		(end 23.51405 -113.411)
		(width 0.2794)
		(layer "F.Cu")
		(net "FAN_2_PWM")
	)
	(segment
		(start 36.513516 -131.191)
		(end 35.941 -131.191)
		(width 0.2794)
		(layer "F.Cu")
		(net "FAN_2_PWM")
	)
	(segment
		(start 37.021516 -130.683)
		(end 36.513516 -131.191)
		(width 0.2794)
		(layer "F.Cu")
		(net "FAN_2_PWM")
	)
	(via
		(at 25.61209 -113.411)
		(size 0.508)
		(drill 0.254)
		(layers "F.Cu" "B.Cu")
		(net "FAN_2_PWM")
	)
	(via
		(at 35.941 -131.191)
		(size 0.508)
		(drill 0.254)
		(layers "F.Cu" "B.Cu")
		(net "FAN_2_PWM")
	)
	(segment
		(start 32.639 -120.142)
		(end 35.941 -123.444)
		(width 0.2286)
		(layer "In2.Cu")
		(net "FAN_2_PWM")
	)
	(segment
		(start 25.61209 -113.877344)
		(end 31.876746 -120.142)
		(width 0.2286)
		(layer "In2.Cu")
		(net "FAN_2_PWM")
	)
	(segment
		(start 31.876746 -120.142)
		(end 32.639 -120.142)
		(width 0.2286)
		(layer "In2.Cu")
		(net "FAN_2_PWM")
	)
	(segment
		(start 25.61209 -113.411)
		(end 25.61209 -113.877344)
		(width 0.2286)
		(layer "In2.Cu")
		(net "FAN_2_PWM")
	)
	(segment
		(start 35.941 -123.444)
		(end 35.941 -131.191)
		(width 0.2286)
		(layer "In2.Cu")
		(net "FAN_2_PWM")
	)
	(segment
		(start 27.5209 -34.050986)
		(end 26.411936 -34.050986)
		(width 0.2794)
		(layer "F.Cu")
		(net "FAN_3_PRESENT")
	)
	(segment
		(start 26.411936 -34.050986)
		(end 26.162 -33.80105)
		(width 0.2794)
		(layer "F.Cu")
		(net "FAN_3_PRESENT")
	)
	(segment
		(start 34.671 -66.294)
		(end 35.109912 -66.732912)
		(width 0.2794)
		(layer "F.Cu")
		(net "FAN_3_PRESENT")
	)
	(segment
		(start 26.162 -33.80105)
		(end 26.162 -34.671)
		(width 0.2794)
		(layer "F.Cu")
		(net "FAN_3_PRESENT")
	)
	(segment
		(start 35.109912 -66.732912)
		(end 36.298378 -66.732912)
		(width 0.2794)
		(layer "F.Cu")
		(net "FAN_3_PRESENT")
	)
	(via
		(at 31.3563 -60.584842)
		(size 0.6604)
		(drill 0.3302)
		(layers "F.Cu" "B.Cu")
		(net "FAN_3_PRESENT")
	)
	(via
		(at 26.162 -34.671)
		(size 0.508)
		(drill 0.254)
		(layers "F.Cu" "B.Cu")
		(net "FAN_3_PRESENT")
	)
	(via
		(at 34.671 -66.294)
		(size 0.508)
		(drill 0.254)
		(layers "F.Cu" "B.Cu")
		(net "FAN_3_PRESENT")
	)
	(segment
		(start 35.09899 -66.72199)
		(end 35.41649 -66.72199)
		(width 0.2794)
		(layer "B.Cu")
		(net "FAN_3_PRESENT")
	)
	(segment
		(start 31.3563 -60.584842)
		(end 31.3563 -65.155826)
		(width 0.2794)
		(layer "B.Cu")
		(net "FAN_3_PRESENT")
	)
	(segment
		(start 26.162 -34.671)
		(end 29.591 -34.671)
		(width 0.2794)
		(layer "B.Cu")
		(net "FAN_3_PRESENT")
	)
	(segment
		(start 29.591 -34.671)
		(end 31.3563 -36.4363)
		(width 0.2794)
		(layer "B.Cu")
		(net "FAN_3_PRESENT")
	)
	(segment
		(start 32.249364 -66.04889)
		(end 34.42589 -66.04889)
		(width 0.2794)
		(layer "B.Cu")
		(net "FAN_3_PRESENT")
	)
	(segment
		(start 31.3563 -65.155826)
		(end 32.249364 -66.04889)
		(width 0.2794)
		(layer "B.Cu")
		(net "FAN_3_PRESENT")
	)
	(segment
		(start 31.3563 -36.4363)
		(end 31.3563 -60.584842)
		(width 0.2794)
		(layer "B.Cu")
		(net "FAN_3_PRESENT")
	)
	(segment
		(start 34.671 -66.294)
		(end 35.09899 -66.72199)
		(width 0.2794)
		(layer "B.Cu")
		(net "FAN_3_PRESENT")
	)
	(segment
		(start 34.42589 -66.04889)
		(end 34.671 -66.294)
		(width 0.2794)
		(layer "B.Cu")
		(net "FAN_3_PRESENT")
	)
	(segment
		(start 33.401 -168.651936)
		(end 32.634682 -168.651936)
		(width 0.2794)
		(layer "F.Cu")
		(net "SMB_PDBV_FAN_R1_IOX_SDA")
	)
	(segment
		(start 29.48305 -167.64)
		(end 29.35605 -167.513)
		(width 0.2794)
		(layer "F.Cu")
		(net "SMB_PDBV_FAN_R1_IOX_SDA")
	)
	(segment
		(start 32.634682 -168.651936)
		(end 31.622746 -167.64)
		(width 0.2794)
		(layer "F.Cu")
		(net "SMB_PDBV_FAN_R1_IOX_SDA")
	)
	(segment
		(start 31.622746 -167.64)
		(end 29.48305 -167.64)
		(width 0.2794)
		(layer "F.Cu")
		(net "SMB_PDBV_FAN_R1_IOX_SDA")
	)
	(via
		(at 31.622746 -167.64)
		(size 0.508)
		(drill 0.254)
		(layers "F.Cu" "B.Cu")
		(net "SMB_PDBV_FAN_R1_IOX_SDA")
	)
	(segment
		(start 30.144974 -113.284)
		(end 32.258 -113.284)
		(width 0.2794)
		(layer "F.Cu")
		(net "FAN_2_PWM_IL")
	)
	(segment
		(start 35.052 -113.284)
		(end 32.258 -113.284)
		(width 0.2794)
		(layer "F.Cu")
		(net "FAN_2_PWM_IL")
	)
	(segment
		(start 36.93795 -114.738912)
		(end 36.506912 -114.738912)
		(width 0.2794)
		(layer "F.Cu")
		(net "FAN_2_PWM_IL")
	)
	(segment
		(start 27.23896 -116.190014)
		(end 30.144974 -113.284)
		(width 0.2794)
		(layer "F.Cu")
		(net "FAN_2_PWM_IL")
	)
	(segment
		(start 36.506912 -114.738912)
		(end 35.052 -113.284)
		(width 0.2794)
		(layer "F.Cu")
		(net "FAN_2_PWM_IL")
	)
	(via
		(at 32.258 -113.284)
		(size 0.762)
		(drill 0.381)
		(layers "F.Cu" "B.Cu")
		(net "FAN_2_PWM_IL")
	)
	(segment
		(start 37.61105 -202.311)
		(end 37.61105 -202.8317)
		(width 0.2794)
		(layer "F.Cu")
		(net "FAN_1_FAIL_R_LED_N")
	)
	(segment
		(start 39.878 -203.581)
		(end 37.635942 -203.581)
		(width 0.2794)
		(layer "F.Cu")
		(net "FAN_1_FAIL_R_LED_N")
	)
	(segment
		(start 39.878 -202.997054)
		(end 39.878 -203.581)
		(width 0.2794)
		(layer "F.Cu")
		(net "FAN_1_FAIL_R_LED_N")
	)
	(segment
		(start 41.865042 -201.010012)
		(end 39.878 -202.997054)
		(width 0.2794)
		(layer "F.Cu")
		(net "FAN_1_FAIL_R_LED_N")
	)
	(segment
		(start 37.61105 -202.8317)
		(end 37.635942 -202.856592)
		(width 0.2794)
		(layer "F.Cu")
		(net "FAN_1_FAIL_R_LED_N")
	)
	(segment
		(start 37.635942 -202.856592)
		(end 37.635942 -203.581)
		(width 0.2794)
		(layer "F.Cu")
		(net "FAN_1_FAIL_R_LED_N")
	)
	(segment
		(start 42.999914 -201.010012)
		(end 41.865042 -201.010012)
		(width 0.2794)
		(layer "F.Cu")
		(net "FAN_1_FAIL_R_LED_N")
	)
	(via
		(at 39.878 -203.581)
		(size 0.762)
		(drill 0.381)
		(layers "F.Cu" "B.Cu")
		(net "FAN_1_FAIL_R_LED_N")
	)
	(via
		(at 46.609 -76.073)
		(size 0.762)
		(drill 0.254)
		(layers "F.Cu" "B.Cu")
		(net "FAN_2_CS")
	)
	(segment
		(start 44.216574 -77.34427)
		(end 44.216574 -77.45476)
		(width 0.1016)
		(layer "B.Cu")
		(net "FAN_2_CS")
	)
	(segment
		(start 44.373546 -77.187298)
		(end 44.216574 -77.34427)
		(width 0.1016)
		(layer "B.Cu")
		(net "FAN_2_CS")
	)
	(segment
		(start 47.498 -75.184)
		(end 46.609 -76.073)
		(width 0.2794)
		(layer "B.Cu")
		(net "FAN_2_CS")
	)
	(segment
		(start 46.609 -76.073)
		(end 45.090842 -76.701904)
		(width 0.2794)
		(layer "B.Cu")
		(net "FAN_2_CS")
	)
	(segment
		(start 45.072046 -76.7207)
		(end 44.373546 -77.187298)
		(width 0.1016)
		(layer "B.Cu")
		(net "FAN_2_CS")
	)
	(segment
		(start 45.090842 -76.701904)
		(end 45.072046 -76.7207)
		(width 0.2794)
		(layer "B.Cu")
		(net "FAN_2_CS")
	)
	(segment
		(start 47.498 -74.371962)
		(end 47.498 -75.184)
		(width 0.2794)
		(layer "B.Cu")
		(net "FAN_2_CS")
	)
	(segment
		(start 44.68495 -179.324)
		(end 43.982132 -180.026818)
		(width 0.2794)
		(layer "F.Cu")
		(net "P52V_FAN_3_BUFF_EN")
	)
	(segment
		(start 41.63695 -179.324)
		(end 41.300908 -179.660042)
		(width 0.2794)
		(layer "F.Cu")
		(net "P52V_FAN_3_BUFF_EN")
	)
	(segment
		(start 43.54576 -180.026818)
		(end 42.231818 -180.026818)
		(width 0.2794)
		(layer "F.Cu")
		(net "P52V_FAN_3_BUFF_EN")
	)
	(segment
		(start 41.63695 -179.43195)
		(end 41.63695 -179.324)
		(width 0.2794)
		(layer "F.Cu")
		(net "P52V_FAN_3_BUFF_EN")
	)
	(segment
		(start 41.300908 -179.660042)
		(end 39.116 -179.660042)
		(width 0.2794)
		(layer "F.Cu")
		(net "P52V_FAN_3_BUFF_EN")
	)
	(segment
		(start 43.982132 -180.026818)
		(end 43.54576 -180.026818)
		(width 0.2794)
		(layer "F.Cu")
		(net "P52V_FAN_3_BUFF_EN")
	)
	(segment
		(start 42.231818 -180.026818)
		(end 41.63695 -179.43195)
		(width 0.2794)
		(layer "F.Cu")
		(net "P52V_FAN_3_BUFF_EN")
	)
	(via
		(at 43.54576 -180.026818)
		(size 0.508)
		(drill 0.254)
		(layers "F.Cu" "B.Cu")
		(net "P52V_FAN_3_BUFF_EN")
	)
	(segment
		(start 31.216346 -168.529)
		(end 29.35605 -168.529)
		(width 0.2794)
		(layer "F.Cu")
		(net "SMB_PDBV_FAN_R1_IOX_SCL")
	)
	(segment
		(start 33.401 -169.301922)
		(end 31.989268 -169.301922)
		(width 0.2794)
		(layer "F.Cu")
		(net "SMB_PDBV_FAN_R1_IOX_SCL")
	)
	(segment
		(start 31.989268 -169.301922)
		(end 31.396432 -168.709086)
		(width 0.2794)
		(layer "F.Cu")
		(net "SMB_PDBV_FAN_R1_IOX_SCL")
	)
	(segment
		(start 31.396432 -168.709086)
		(end 31.216346 -168.529)
		(width 0.2794)
		(layer "F.Cu")
		(net "SMB_PDBV_FAN_R1_IOX_SCL")
	)
	(via
		(at 31.396432 -168.709086)
		(size 0.762)
		(drill 0.381)
		(layers "F.Cu" "B.Cu")
		(net "SMB_PDBV_FAN_R1_IOX_SCL")
	)
	(segment
		(start 22.479 -298.85005)
		(end 21.844 -298.85005)
		(width 0.2794)
		(layer "F.Cu")
		(net "FAN_0_PWM")
	)
	(segment
		(start 22.4536 -300.01464)
		(end 22.4536 -298.87545)
		(width 0.2794)
		(layer "F.Cu")
		(net "FAN_0_PWM")
	)
	(segment
		(start 24.818594 -207.899)
		(end 23.876 -207.899)
		(width 0.2794)
		(layer "F.Cu")
		(net "FAN_0_PWM")
	)
	(segment
		(start 38.227 -137.668)
		(end 38.227 -138.303)
		(width 0.2794)
		(layer "F.Cu")
		(net "FAN_0_PWM")
	)
	(segment
		(start 30.152594 -202.565)
		(end 24.818594 -207.899)
		(width 0.2794)
		(layer "F.Cu")
		(net "FAN_0_PWM")
	)
	(segment
		(start 22.479 -300.04004)
		(end 22.4536 -300.01464)
		(width 0.2794)
		(layer "F.Cu")
		(net "FAN_0_PWM")
	)
	(segment
		(start 22.4536 -298.87545)
		(end 22.479 -298.85005)
		(width 0.2794)
		(layer "F.Cu")
		(net "FAN_0_PWM")
	)
	(via
		(at 38.227 -138.303)
		(size 0.508)
		(drill 0.254)
		(layers "F.Cu" "B.Cu")
		(net "FAN_0_PWM")
	)
	(via
		(at 23.876 -207.899)
		(size 0.508)
		(drill 0.254)
		(layers "F.Cu" "B.Cu")
		(net "FAN_0_PWM")
	)
	(via
		(at 21.844 -298.85005)
		(size 0.508)
		(drill 0.254)
		(layers "F.Cu" "B.Cu")
		(net "FAN_0_PWM")
	)
	(via
		(at 30.152594 -202.565)
		(size 0.508)
		(drill 0.254)
		(layers "F.Cu" "B.Cu")
		(net "FAN_0_PWM")
	)
	(segment
		(start 28.663392 -201.075798)
		(end 28.663392 -194.347084)
		(width 0.2286)
		(layer "In2.Cu")
		(net "FAN_0_PWM")
	)
	(segment
		(start 24.741378 -285.585408)
		(end 24.741378 -294.128952)
		(width 0.2286)
		(layer "In2.Cu")
		(net "FAN_0_PWM")
	)
	(segment
		(start 34.80435 -143.468852)
		(end 38.227 -140.046202)
		(width 0.2286)
		(layer "In2.Cu")
		(net "FAN_0_PWM")
	)
	(segment
		(start 24.741378 -294.128952)
		(end 21.844 -297.02633)
		(width 0.2286)
		(layer "In2.Cu")
		(net "FAN_0_PWM")
	)
	(segment
		(start 25.527 -251.86386)
		(end 25.527 -284.799786)
		(width 0.2286)
		(layer "In2.Cu")
		(net "FAN_0_PWM")
	)
	(segment
		(start 34.80435 -158.08071)
		(end 34.80435 -143.468852)
		(width 0.2286)
		(layer "In2.Cu")
		(net "FAN_0_PWM")
	)
	(segment
		(start 24.45893 -208.48193)
		(end 24.45893 -219.6846)
		(width 0.2286)
		(layer "In2.Cu")
		(net "FAN_0_PWM")
	)
	(segment
		(start 34.961576 -158.459932)
		(end 34.80435 -158.08071)
		(width 0.2286)
		(layer "In2.Cu")
		(net "FAN_0_PWM")
	)
	(segment
		(start 36.26358 -163.40074)
		(end 36.0426 -163.40074)
		(width 0.2286)
		(layer "In2.Cu")
		(net "FAN_0_PWM")
	)
	(segment
		(start 33.095438 -184.895744)
		(end 36.576 -181.415182)
		(width 0.2286)
		(layer "In2.Cu")
		(net "FAN_0_PWM")
	)
	(segment
		(start 33.095438 -189.915038)
		(end 33.095438 -184.895744)
		(width 0.2286)
		(layer "In2.Cu")
		(net "FAN_0_PWM")
	)
	(segment
		(start 19.123914 -225.019616)
		(end 19.123914 -245.460774)
		(width 0.2286)
		(layer "In2.Cu")
		(net "FAN_0_PWM")
	)
	(segment
		(start 38.227 -140.046202)
		(end 38.227 -138.303)
		(width 0.2286)
		(layer "In2.Cu")
		(net "FAN_0_PWM")
	)
	(segment
		(start 25.527 -284.799786)
		(end 24.741378 -285.585408)
		(width 0.2286)
		(layer "In2.Cu")
		(net "FAN_0_PWM")
	)
	(segment
		(start 36.576 -181.415182)
		(end 36.576 -163.71316)
		(width 0.2286)
		(layer "In2.Cu")
		(net "FAN_0_PWM")
	)
	(segment
		(start 28.663392 -194.347084)
		(end 33.095438 -189.915038)
		(width 0.2286)
		(layer "In2.Cu")
		(net "FAN_0_PWM")
	)
	(segment
		(start 30.152594 -202.565)
		(end 28.663392 -201.075798)
		(width 0.2286)
		(layer "In2.Cu")
		(net "FAN_0_PWM")
	)
	(segment
		(start 23.876 -207.899)
		(end 24.45893 -208.48193)
		(width 0.2286)
		(layer "In2.Cu")
		(net "FAN_0_PWM")
	)
	(segment
		(start 24.45893 -219.6846)
		(end 19.123914 -225.019616)
		(width 0.2286)
		(layer "In2.Cu")
		(net "FAN_0_PWM")
	)
	(segment
		(start 19.123914 -245.460774)
		(end 25.527 -251.86386)
		(width 0.2286)
		(layer "In2.Cu")
		(net "FAN_0_PWM")
	)
	(segment
		(start 36.576 -163.71316)
		(end 36.26358 -163.40074)
		(width 0.2286)
		(layer "In2.Cu")
		(net "FAN_0_PWM")
	)
	(segment
		(start 36.0426 -161.067242)
		(end 34.961576 -158.459932)
		(width 0.2286)
		(layer "In2.Cu")
		(net "FAN_0_PWM")
	)
	(segment
		(start 36.0426 -163.40074)
		(end 36.0426 -161.067242)
		(width 0.2286)
		(layer "In2.Cu")
		(net "FAN_0_PWM")
	)
	(segment
		(start 21.844 -297.02633)
		(end 21.844 -298.85005)
		(width 0.2286)
		(layer "In2.Cu")
		(net "FAN_0_PWM")
	)
	(segment
		(start 6.87705 -174.244)
		(end 8.590026 -174.244)
		(width 0.2794)
		(layer "F.Cu")
		(net "FAN_7_PRSNT_BUF_R_N")
	)
	(segment
		(start 6.035802 -175.734472)
		(end 6.87705 -174.893224)
		(width 0.2794)
		(layer "F.Cu")
		(net "FAN_7_PRSNT_BUF_R_N")
	)
	(segment
		(start 6.87705 -174.893224)
		(end 6.87705 -174.244)
		(width 0.2794)
		(layer "F.Cu")
		(net "FAN_7_PRSNT_BUF_R_N")
	)
	(segment
		(start 4.59105 -175.283622)
		(end 5.0419 -175.734472)
		(width 0.2794)
		(layer "F.Cu")
		(net "FAN_7_PRSNT_BUF_R_N")
	)
	(segment
		(start 4.59105 -174.244)
		(end 4.59105 -175.283622)
		(width 0.2794)
		(layer "F.Cu")
		(net "FAN_7_PRSNT_BUF_R_N")
	)
	(segment
		(start 5.0419 -175.734472)
		(end 6.035802 -175.734472)
		(width 0.2794)
		(layer "F.Cu")
		(net "FAN_7_PRSNT_BUF_R_N")
	)
	(segment
		(start 8.590026 -174.244)
		(end 8.95604 -173.877986)
		(width 0.2794)
		(layer "F.Cu")
		(net "FAN_7_PRSNT_BUF_R_N")
	)
	(via
		(at 5.0419 -175.734472)
		(size 0.762)
		(drill 0.381)
		(layers "F.Cu" "B.Cu")
		(net "FAN_7_PRSNT_BUF_R_N")
	)
	(segment
		(start 37.871654 -201.0156)
		(end 37.762942 -201.0156)
		(width 0.2794)
		(layer "F.Cu")
		(net "FAN_1_OK_R_LED_N")
	)
	(segment
		(start 37.762942 -201.0156)
		(end 37.762942 -201.041)
		(width 0.2794)
		(layer "F.Cu")
		(net "FAN_1_OK_R_LED_N")
	)
	(segment
		(start 42.999914 -199.010016)
		(end 40.816784 -199.010016)
		(width 0.2794)
		(layer "F.Cu")
		(net "FAN_1_OK_R_LED_N")
	)
	(segment
		(start 39.751 -200.0758)
		(end 38.811454 -200.0758)
		(width 0.2794)
		(layer "F.Cu")
		(net "FAN_1_OK_R_LED_N")
	)
	(segment
		(start 40.816784 -199.010016)
		(end 39.751 -200.0758)
		(width 0.2794)
		(layer "F.Cu")
		(net "FAN_1_OK_R_LED_N")
	)
	(segment
		(start 38.811454 -200.0758)
		(end 37.871654 -201.0156)
		(width 0.2794)
		(layer "F.Cu")
		(net "FAN_1_OK_R_LED_N")
	)
	(segment
		(start 37.61105 -200.863708)
		(end 37.61105 -199.771)
		(width 0.2794)
		(layer "F.Cu")
		(net "FAN_1_OK_R_LED_N")
	)
	(segment
		(start 37.762942 -201.0156)
		(end 37.61105 -200.863708)
		(width 0.2794)
		(layer "F.Cu")
		(net "FAN_1_OK_R_LED_N")
	)
	(via
		(at 39.751 -200.0758)
		(size 0.762)
		(drill 0.381)
		(layers "F.Cu" "B.Cu")
		(net "FAN_1_OK_R_LED_N")
	)
	(via
		(at 42.418 -75.26274)
		(size 0.762)
		(drill 0.254)
		(layers "F.Cu" "B.Cu")
		(net "FAN_2_CLREF")
	)
	(segment
		(start 43.434 -74.371962)
		(end 42.418 -74.371962)
		(width 0.2794)
		(layer "B.Cu")
		(net "FAN_2_CLREF")
	)
	(segment
		(start 42.216578 -76.247498)
		(end 42.216578 -77.45476)
		(width 0.1016)
		(layer "B.Cu")
		(net "FAN_2_CLREF")
	)
	(segment
		(start 42.41165 -75.267058)
		(end 42.216578 -76.247498)
		(width 0.1016)
		(layer "B.Cu")
		(net "FAN_2_CLREF")
	)
	(segment
		(start 42.418 -75.26274)
		(end 42.41165 -75.267058)
		(width 0.1016)
		(layer "B.Cu")
		(net "FAN_2_CLREF")
	)
	(segment
		(start 42.418 -74.371962)
		(end 42.418 -75.26274)
		(width 0.2794)
		(layer "B.Cu")
		(net "FAN_2_CLREF")
	)
	(segment
		(start 31.720028 -180.310028)
		(end 31.24835 -179.83835)
		(width 0.2794)
		(layer "F.Cu")
		(net "P52V_FAN_2_BUFF_EN")
	)
	(segment
		(start 30.231842 -178.1429)
		(end 28.534106 -178.1429)
		(width 0.2794)
		(layer "F.Cu")
		(net "P52V_FAN_2_BUFF_EN")
	)
	(segment
		(start 27.83205 -179.451)
		(end 27.83205 -178.645312)
		(width 0.2794)
		(layer "F.Cu")
		(net "P52V_FAN_2_BUFF_EN")
	)
	(segment
		(start 30.75305 -178.816)
		(end 30.75305 -178.664108)
		(width 0.2794)
		(layer "F.Cu")
		(net "P52V_FAN_2_BUFF_EN")
	)
	(segment
		(start 30.75305 -178.664108)
		(end 30.231842 -178.1429)
		(width 0.2794)
		(layer "F.Cu")
		(net "P52V_FAN_2_BUFF_EN")
	)
	(segment
		(start 27.83205 -178.645312)
		(end 28.334462 -178.1429)
		(width 0.2794)
		(layer "F.Cu")
		(net "P52V_FAN_2_BUFF_EN")
	)
	(segment
		(start 28.334462 -178.1429)
		(end 28.534106 -178.1429)
		(width 0.2794)
		(layer "F.Cu")
		(net "P52V_FAN_2_BUFF_EN")
	)
	(segment
		(start 31.24835 -179.07)
		(end 30.99435 -178.816)
		(width 0.2794)
		(layer "F.Cu")
		(net "P52V_FAN_2_BUFF_EN")
	)
	(segment
		(start 30.99435 -178.816)
		(end 30.75305 -178.816)
		(width 0.2794)
		(layer "F.Cu")
		(net "P52V_FAN_2_BUFF_EN")
	)
	(segment
		(start 31.24835 -179.83835)
		(end 31.24835 -179.07)
		(width 0.2794)
		(layer "F.Cu")
		(net "P52V_FAN_2_BUFF_EN")
	)
	(segment
		(start 33.274 -180.310028)
		(end 31.720028 -180.310028)
		(width 0.2794)
		(layer "F.Cu")
		(net "P52V_FAN_2_BUFF_EN")
	)
	(via
		(at 28.534106 -178.1429)
		(size 0.762)
		(drill 0.381)
		(layers "F.Cu" "B.Cu")
		(net "P52V_FAN_2_BUFF_EN")
	)
	(segment
		(start 43.18 -216.916)
		(end 43.18 -218.488006)
		(width 0.4572)
		(layer "F.Cu")
		(net "P12V_LED")
	)
	(segment
		(start 46.08195 -216.408)
		(end 45.466 -217.02395)
		(width 0.4572)
		(layer "F.Cu")
		(net "P12V_LED")
	)
	(segment
		(start 18.669 -217.043)
		(end 19.177 -216.535)
		(width 0.4572)
		(layer "F.Cu")
		(net "P12V_LED")
	)
	(segment
		(start 6.985 -312.43905)
		(end 6.985 -312.2676)
		(width 0.4572)
		(layer "F.Cu")
		(net "P12V_LED")
	)
	(segment
		(start 31.877 -244.983)
		(end 31.877 -219.1258)
		(width 0.4572)
		(layer "F.Cu")
		(net "P12V_LED")
	)
	(segment
		(start 41.2496 -312.3946)
		(end 13.9954 -312.3946)
		(width 0.4572)
		(layer "F.Cu")
		(net "P12V_LED")
	)
	(segment
		(start 20.32 -35.941)
		(end 20.4216 -35.941)
		(width 0.4572)
		(layer "F.Cu")
		(net "P12V_LED")
	)
	(segment
		(start 24.764746 -213.868)
		(end 21.922994 -213.868)
		(width 0.4572)
		(layer "F.Cu")
		(net "P12V_LED")
	)
	(segment
		(start 27.305 -98.933)
		(end 27.178 -98.933)
		(width 0.4572)
		(layer "F.Cu")
		(net "P12V_LED")
	)
	(segment
		(start 25.908 -97.663)
		(end 27.178 -98.933)
		(width 0.4572)
		(layer "F.Cu")
		(net "P12V_LED")
	)
	(segment
		(start 19.304 -34.925)
		(end 20.32 -35.941)
		(width 0.4572)
		(layer "F.Cu")
		(net "P12V_LED")
	)
	(segment
		(start 44.43095 -313.89955)
		(end 42.926 -312.3946)
		(width 0.4572)
		(layer "F.Cu")
		(net "P12V_LED")
	)
	(segment
		(start 2.413 -99.187)
		(end 2.413 -97.6884)
		(width 0.4572)
		(layer "F.Cu")
		(net "P12V_LED")
	)
	(segment
		(start 19.304 -33.909)
		(end 19.304 -34.925)
		(width 0.4572)
		(layer "F.Cu")
		(net "P12V_LED")
	)
	(segment
		(start 1.524 -94.2086)
		(end 1.524 -11.557)
		(width 0.4572)
		(layer "F.Cu")
		(net "P12V_LED")
	)
	(segment
		(start 42.037 -312.3946)
		(end 41.2496 -312.3946)
		(width 0.4572)
		(layer "F.Cu")
		(net "P12V_LED")
	)
	(segment
		(start 28.067 -248.793)
		(end 31.877 -244.983)
		(width 0.4572)
		(layer "F.Cu")
		(net "P12V_LED")
	)
	(segment
		(start 43.633898 -216.462102)
		(end 43.18 -216.916)
		(width 0.4572)
		(layer "F.Cu")
		(net "P12V_LED")
	)
	(segment
		(start 1.524 -11.557)
		(end 1.905 -11.176)
		(width 0.4572)
		(layer "F.Cu")
		(net "P12V_LED")
	)
	(segment
		(start 22.225 -34.56305)
		(end 20.84705 -35.941)
		(width 0.4572)
		(layer "F.Cu")
		(net "P12V_LED")
	)
	(segment
		(start 20.4216 -35.941)
		(end 20.4216 -54.9656)
		(width 0.4572)
		(layer "F.Cu")
		(net "P12V_LED")
	)
	(segment
		(start 13.9954 -312.3946)
		(end 11.557 -314.833)
		(width 0.4572)
		(layer "F.Cu")
		(net "P12V_LED")
	)
	(segment
		(start 32.131 -34.3916)
		(end 31.0134 -33.274)
		(width 0.4572)
		(layer "F.Cu")
		(net "P12V_LED")
	)
	(segment
		(start 16.3576 -217.043)
		(end 18.669 -217.043)
		(width 0.4572)
		(layer "F.Cu")
		(net "P12V_LED")
	)
	(segment
		(start 30.022546 -219.1258)
		(end 24.764746 -213.868)
		(width 0.4572)
		(layer "F.Cu")
		(net "P12V_LED")
	)
	(segment
		(start 44.43095 -314.071)
		(end 44.43095 -313.89955)
		(width 0.4572)
		(layer "F.Cu")
		(net "P12V_LED")
	)
	(segment
		(start 31.877 -219.1258)
		(end 30.022546 -219.1258)
		(width 0.4572)
		(layer "F.Cu")
		(net "P12V_LED")
	)
	(segment
		(start 46.39945 -98.40595)
		(end 45.466 -98.40595)
		(width 0.4572)
		(layer "F.Cu")
		(net "P12V_LED")
	)
	(segment
		(start 26.035 -248.793)
		(end 28.067 -248.793)
		(width 0.4572)
		(layer "F.Cu")
		(net "P12V_LED")
	)
	(segment
		(start 32.258 -218.7448)
		(end 31.877 -219.1258)
		(width 0.4572)
		(layer "F.Cu")
		(net "P12V_LED")
	)
	(segment
		(start 8.36295 -313.817)
		(end 6.985 -312.43905)
		(width 0.4572)
		(layer "F.Cu")
		(net "P12V_LED")
	)
	(segment
		(start 31.496 -36.81095)
		(end 31.38805 -36.703)
		(width 0.4572)
		(layer "F.Cu")
		(net "P12V_LED")
	)
	(segment
		(start 3.7084 -96.393)
		(end 4.80314 -95.29826)
		(width 0.4572)
		(layer "F.Cu")
		(net "P12V_LED")
	)
	(segment
		(start 22.82063 -96.901)
		(end 23.005542 -96.716088)
		(width 0.4572)
		(layer "F.Cu")
		(net "P12V_LED")
	)
	(segment
		(start 25.908 -60.452)
		(end 31.496 -54.864)
		(width 0.4572)
		(layer "F.Cu")
		(net "P12V_LED")
	)
	(segment
		(start 3.40995 -99.822)
		(end 3.048 -99.822)
		(width 0.4572)
		(layer "F.Cu")
		(net "P12V_LED")
	)
	(segment
		(start 44.21505 -97.155)
		(end 29.083 -97.155)
		(width 0.4572)
		(layer "F.Cu")
		(net "P12V_LED")
	)
	(segment
		(start 2.413 -97.6884)
		(end 3.7084 -96.393)
		(width 0.4572)
		(layer "F.Cu")
		(net "P12V_LED")
	)
	(segment
		(start 45.466 -98.40595)
		(end 44.21505 -97.155)
		(width 0.4572)
		(layer "F.Cu")
		(net "P12V_LED")
	)
	(segment
		(start 45.466 -217.02395)
		(end 44.904152 -216.462102)
		(width 0.4572)
		(layer "F.Cu")
		(net "P12V_LED")
	)
	(segment
		(start 43.18 -218.488006)
		(end 42.923206 -218.7448)
		(width 0.4572)
		(layer "F.Cu")
		(net "P12V_LED")
	)
	(segment
		(start 21.336 -214.454994)
		(end 21.336 -214.6173)
		(width 0.4572)
		(layer "F.Cu")
		(net "P12V_LED")
	)
	(segment
		(start 11.557 -314.833)
		(end 9.150858 -314.833)
		(width 0.4572)
		(layer "F.Cu")
		(net "P12V_LED")
	)
	(segment
		(start 19.177 -216.535)
		(end 19.177 -215.79205)
		(width 0.4572)
		(layer "F.Cu")
		(net "P12V_LED")
	)
	(segment
		(start 8.36295 -314.045092)
		(end 8.36295 -313.817)
		(width 0.4572)
		(layer "F.Cu")
		(net "P12V_LED")
	)
	(segment
		(start 47.1424 -216.408)
		(end 46.08195 -216.408)
		(width 0.4572)
		(layer "F.Cu")
		(net "P12V_LED")
	)
	(segment
		(start 44.904152 -216.462102)
		(end 43.633898 -216.462102)
		(width 0.4572)
		(layer "F.Cu")
		(net "P12V_LED")
	)
	(segment
		(start 31.496 -38.26002)
		(end 31.496 -36.81095)
		(width 0.4572)
		(layer "F.Cu")
		(net "P12V_LED")
	)
	(segment
		(start 42.923206 -218.7448)
		(end 32.258 -218.7448)
		(width 0.4572)
		(layer "F.Cu")
		(net "P12V_LED")
	)
	(segment
		(start 47.2694 -97.536)
		(end 46.39945 -98.40595)
		(width 0.4572)
		(layer "F.Cu")
		(net "P12V_LED")
	)
	(segment
		(start 3.048 -99.822)
		(end 2.413 -99.187)
		(width 0.4572)
		(layer "F.Cu")
		(net "P12V_LED")
	)
	(segment
		(start 31.496 -54.864)
		(end 31.496 -38.26002)
		(width 0.4572)
		(layer "F.Cu")
		(net "P12V_LED")
	)
	(segment
		(start 4.80314 -95.29826)
		(end 9.44626 -95.29826)
		(width 0.4572)
		(layer "F.Cu")
		(net "P12V_LED")
	)
	(segment
		(start 9.44626 -95.29826)
		(end 11.049 -96.901)
		(width 0.4572)
		(layer "F.Cu")
		(net "P12V_LED")
	)
	(segment
		(start 21.922994 -213.868)
		(end 21.336 -214.454994)
		(width 0.4572)
		(layer "F.Cu")
		(net "P12V_LED")
	)
	(segment
		(start 31.38805 -36.703)
		(end 32.131 -35.96005)
		(width 0.4572)
		(layer "F.Cu")
		(net "P12V_LED")
	)
	(segment
		(start 25.908 -60.452)
		(end 25.908 -95.758)
		(width 0.4572)
		(layer "F.Cu")
		(net "P12V_LED")
	)
	(segment
		(start 23.005542 -96.716088)
		(end 23.963884 -95.758)
		(width 0.4572)
		(layer "F.Cu")
		(net "P12V_LED")
	)
	(segment
		(start 9.150858 -314.833)
		(end 8.36295 -314.045092)
		(width 0.4572)
		(layer "F.Cu")
		(net "P12V_LED")
	)
	(segment
		(start 3.7084 -96.393)
		(end 1.524 -94.2086)
		(width 0.4572)
		(layer "F.Cu")
		(net "P12V_LED")
	)
	(segment
		(start 29.083 -97.155)
		(end 27.305 -98.933)
		(width 0.4572)
		(layer "F.Cu")
		(net "P12V_LED")
	)
	(segment
		(start 20.4216 -54.9656)
		(end 25.908 -60.452)
		(width 0.4572)
		(layer "F.Cu")
		(net "P12V_LED")
	)
	(segment
		(start 11.049 -96.901)
		(end 22.82063 -96.901)
		(width 0.4572)
		(layer "F.Cu")
		(net "P12V_LED")
	)
	(segment
		(start 32.131 -35.96005)
		(end 32.131 -34.3916)
		(width 0.4572)
		(layer "F.Cu")
		(net "P12V_LED")
	)
	(segment
		(start 25.908 -95.758)
		(end 25.908 -97.663)
		(width 0.4572)
		(layer "F.Cu")
		(net "P12V_LED")
	)
	(segment
		(start 42.926 -312.3946)
		(end 42.037 -312.3946)
		(width 0.4572)
		(layer "F.Cu")
		(net "P12V_LED")
	)
	(segment
		(start 20.84705 -35.941)
		(end 20.4216 -35.941)
		(width 0.4572)
		(layer "F.Cu")
		(net "P12V_LED")
	)
	(segment
		(start 23.963884 -95.758)
		(end 25.908 -95.758)
		(width 0.4572)
		(layer "F.Cu")
		(net "P12V_LED")
	)
	(via
		(at 26.035 -248.793)
		(size 0.762)
		(drill 0.254)
		(layers "F.Cu" "B.Cu")
		(net "P12V_LED")
	)
	(via
		(at 19.177 -216.535)
		(size 0.508)
		(drill 0.254)
		(layers "F.Cu" "B.Cu")
		(net "P12V_LED")
	)
	(via
		(at 42.037 -312.3946)
		(size 0.508)
		(drill 0.254)
		(layers "F.Cu" "B.Cu")
		(net "P12V_LED")
	)
	(via
		(at 31.496 -38.26002)
		(size 0.762)
		(drill 0.381)
		(layers "F.Cu" "B.Cu")
		(net "P12V_LED")
	)
	(via
		(at 1.905 -11.176)
		(size 0.508)
		(drill 0.254)
		(layers "F.Cu" "B.Cu")
		(net "P12V_LED")
	)
	(via
		(at 27.178 -98.933)
		(size 0.508)
		(drill 0.254)
		(layers "F.Cu" "B.Cu")
		(net "P12V_LED")
	)
	(via
		(at 19.304 -33.909)
		(size 0.508)
		(drill 0.254)
		(layers "F.Cu" "B.Cu")
		(net "P12V_LED")
	)
	(via
		(at 21.336 -214.6173)
		(size 0.508)
		(drill 0.254)
		(layers "F.Cu" "B.Cu")
		(net "P12V_LED")
	)
	(via
		(at 41.2496 -312.3946)
		(size 0.762)
		(drill 0.381)
		(layers "F.Cu" "B.Cu")
		(net "P12V_LED")
	)
	(segment
		(start 26.0731 -279.551892)
		(end 25.273 -280.351992)
		(width 0.4572)
		(layer "B.Cu")
		(net "P12V_LED")
	)
	(segment
		(start 21.920708 -29.641292)
		(end 21.920708 -26.187908)
		(width 0.4572)
		(layer "B.Cu")
		(net "P12V_LED")
	)
	(segment
		(start 21.920708 -26.187908)
		(end 20.6502 -24.9174)
		(width 0.4572)
		(layer "B.Cu")
		(net "P12V_LED")
	)
	(segment
		(start 27.178 -98.933)
		(end 24.638 -101.473)
		(width 0.4572)
		(layer "B.Cu")
		(net "P12V_LED")
	)
	(segment
		(start 14.986 -119.38)
		(end 12.319 -119.38)
		(width 0.4572)
		(layer "B.Cu")
		(net "P12V_LED")
	)
	(segment
		(start 14.88948 -191.8589)
		(end 20.4089 -191.8589)
		(width 0.4572)
		(layer "B.Cu")
		(net "P12V_LED")
	)
	(segment
		(start 20.4089 -191.8589)
		(end 22.479 -193.929)
		(width 0.4572)
		(layer "B.Cu")
		(net "P12V_LED")
	)
	(segment
		(start 17.8816 -15.24)
		(end 16.002 -15.24)
		(width 0.4572)
		(layer "B.Cu")
		(net "P12V_LED")
	)
	(segment
		(start 9.398 -8.636)
		(end 4.445 -8.636)
		(width 0.4572)
		(layer "B.Cu")
		(net "P12V_LED")
	)
	(segment
		(start 25.273 -296.545)
		(end 31.369 -302.641)
		(width 0.4572)
		(layer "B.Cu")
		(net "P12V_LED")
	)
	(segment
		(start 18.3642 -15.7226)
		(end 17.8816 -15.24)
		(width 0.4572)
		(layer "B.Cu")
		(net "P12V_LED")
	)
	(segment
		(start 12.319 -119.38)
		(end 11.557 -120.142)
		(width 0.4572)
		(layer "B.Cu")
		(net "P12V_LED")
	)
	(segment
		(start 20.955 -119.253)
		(end 18.669 -119.253)
		(width 0.4572)
		(layer "B.Cu")
		(net "P12V_LED")
	)
	(segment
		(start 20.6502 -24.9174)
		(end 20.6502 -23.2156)
		(width 0.4572)
		(layer "B.Cu")
		(net "P12V_LED")
	)
	(segment
		(start 18.669 -119.253)
		(end 17.399 -120.523)
		(width 0.4572)
		(layer "B.Cu")
		(net "P12V_LED")
	)
	(segment
		(start 19.939 -33.274)
		(end 19.939 -31.623)
		(width 0.4572)
		(layer "B.Cu")
		(net "P12V_LED")
	)
	(segment
		(start 24.638 -101.473)
		(end 24.638 -115.57)
		(width 0.4572)
		(layer "B.Cu")
		(net "P12V_LED")
	)
	(segment
		(start 1.651 -121.793)
		(end 1.651 -183.47944)
		(width 0.4572)
		(layer "B.Cu")
		(net "P12V_LED")
	)
	(segment
		(start 16.129 -120.523)
		(end 14.986 -119.38)
		(width 0.4572)
		(layer "B.Cu")
		(net "P12V_LED")
	)
	(segment
		(start 22.479 -213.4743)
		(end 21.336 -214.6173)
		(width 0.4572)
		(layer "B.Cu")
		(net "P12V_LED")
	)
	(segment
		(start 22.606 -8.121396)
		(end 22.606 -11.262614)
		(width 0.8128)
		(layer "B.Cu")
		(net "P12V_LED")
	)
	(segment
		(start 22.479 -193.929)
		(end 22.479 -213.4743)
		(width 0.4572)
		(layer "B.Cu")
		(net "P12V_LED")
	)
	(segment
		(start 4.826 -191.897)
		(end 5.461 -191.262)
		(width 0.4572)
		(layer "B.Cu")
		(net "P12V_LED")
	)
	(segment
		(start 14.29258 -191.262)
		(end 14.88948 -191.8589)
		(width 0.4572)
		(layer "B.Cu")
		(net "P12V_LED")
	)
	(segment
		(start 5.461 -191.262)
		(end 14.29258 -191.262)
		(width 0.4572)
		(layer "B.Cu")
		(net "P12V_LED")
	)
	(segment
		(start 17.399 -120.523)
		(end 16.129 -120.523)
		(width 0.4572)
		(layer "B.Cu")
		(net "P12V_LED")
	)
	(segment
		(start 19.939 -31.623)
		(end 21.920708 -29.641292)
		(width 0.4572)
		(layer "B.Cu")
		(net "P12V_LED")
	)
	(segment
		(start 21.3614 -14.5796)
		(end 19.5072 -14.5796)
		(width 0.4572)
		(layer "B.Cu")
		(net "P12V_LED")
	)
	(segment
		(start 21.336 -214.6173)
		(end 19.4183 -216.535)
		(width 0.4572)
		(layer "B.Cu")
		(net "P12V_LED")
	)
	(segment
		(start 19.304 -33.909)
		(end 19.939 -33.274)
		(width 0.4572)
		(layer "B.Cu")
		(net "P12V_LED")
	)
	(segment
		(start 3.048 -191.897)
		(end 4.826 -191.897)
		(width 0.4572)
		(layer "B.Cu")
		(net "P12V_LED")
	)
	(segment
		(start 31.369 -302.641)
		(end 35.941 -302.641)
		(width 0.4572)
		(layer "B.Cu")
		(net "P12V_LED")
	)
	(segment
		(start 26.035 -248.793)
		(end 26.0731 -248.8311)
		(width 0.4572)
		(layer "B.Cu")
		(net "P12V_LED")
	)
	(segment
		(start 3.302 -120.142)
		(end 1.651 -121.793)
		(width 0.4572)
		(layer "B.Cu")
		(net "P12V_LED")
	)
	(segment
		(start 22.606 -13.335)
		(end 21.3614 -14.5796)
		(width 0.4572)
		(layer "B.Cu")
		(net "P12V_LED")
	)
	(segment
		(start 2.286 -184.11444)
		(end 2.286 -191.135)
		(width 0.4572)
		(layer "B.Cu")
		(net "P12V_LED")
	)
	(segment
		(start 42.037 -308.737)
		(end 42.037 -312.3946)
		(width 0.4572)
		(layer "B.Cu")
		(net "P12V_LED")
	)
	(segment
		(start 1.651 -183.47944)
		(end 2.286 -184.11444)
		(width 0.4572)
		(layer "B.Cu")
		(net "P12V_LED")
	)
	(segment
		(start 21.4884 -22.3774)
		(end 21.4884 -18.288)
		(width 0.4572)
		(layer "B.Cu")
		(net "P12V_LED")
	)
	(segment
		(start 20.9804 -17.78)
		(end 19.5834 -17.78)
		(width 0.4572)
		(layer "B.Cu")
		(net "P12V_LED")
	)
	(segment
		(start 19.4183 -216.535)
		(end 19.177 -216.535)
		(width 0.4572)
		(layer "B.Cu")
		(net "P12V_LED")
	)
	(segment
		(start 35.941 -302.641)
		(end 42.037 -308.737)
		(width 0.4572)
		(layer "B.Cu")
		(net "P12V_LED")
	)
	(segment
		(start 19.5072 -14.5796)
		(end 18.3642 -15.7226)
		(width 0.4572)
		(layer "B.Cu")
		(net "P12V_LED")
	)
	(segment
		(start 11.557 -120.142)
		(end 3.302 -120.142)
		(width 0.4572)
		(layer "B.Cu")
		(net "P12V_LED")
	)
	(segment
		(start 18.3642 -16.5608)
		(end 18.3642 -15.7226)
		(width 0.4572)
		(layer "B.Cu")
		(net "P12V_LED")
	)
	(segment
		(start 21.4884 -18.288)
		(end 20.9804 -17.78)
		(width 0.4572)
		(layer "B.Cu")
		(net "P12V_LED")
	)
	(segment
		(start 22.606 -11.262614)
		(end 22.606 -13.335)
		(width 0.4572)
		(layer "B.Cu")
		(net "P12V_LED")
	)
	(segment
		(start 22.349968 -4.350004)
		(end 22.349968 -7.865364)
		(width 0.8128)
		(layer "B.Cu")
		(net "P12V_LED")
	)
	(segment
		(start 4.445 -8.636)
		(end 1.905 -11.176)
		(width 0.4572)
		(layer "B.Cu")
		(net "P12V_LED")
	)
	(segment
		(start 24.638 -115.57)
		(end 20.955 -119.253)
		(width 0.4572)
		(layer "B.Cu")
		(net "P12V_LED")
	)
	(segment
		(start 22.349968 -7.865364)
		(end 22.606 -8.121396)
		(width 0.8128)
		(layer "B.Cu")
		(net "P12V_LED")
	)
	(segment
		(start 16.002 -15.24)
		(end 9.398 -8.636)
		(width 0.4572)
		(layer "B.Cu")
		(net "P12V_LED")
	)
	(segment
		(start 25.273 -280.351992)
		(end 25.273 -296.545)
		(width 0.4572)
		(layer "B.Cu")
		(net "P12V_LED")
	)
	(segment
		(start 20.6502 -23.2156)
		(end 21.4884 -22.3774)
		(width 0.4572)
		(layer "B.Cu")
		(net "P12V_LED")
	)
	(segment
		(start 26.0731 -248.8311)
		(end 26.0731 -279.551892)
		(width 0.4572)
		(layer "B.Cu")
		(net "P12V_LED")
	)
	(segment
		(start 2.286 -191.135)
		(end 3.048 -191.897)
		(width 0.4572)
		(layer "B.Cu")
		(net "P12V_LED")
	)
	(segment
		(start 19.5834 -17.78)
		(end 18.3642 -16.5608)
		(width 0.4572)
		(layer "B.Cu")
		(net "P12V_LED")
	)
	(segment
		(start 34.797746 -298.577)
		(end 35.559746 -299.339)
		(width 0.2794)
		(layer "F.Cu")
		(net "FAN_0_PWM_IL")
	)
	(segment
		(start 26.73096 -300.340014)
		(end 29.001974 -298.069)
		(width 0.2794)
		(layer "F.Cu")
		(net "FAN_0_PWM_IL")
	)
	(segment
		(start 32.694372 -298.577)
		(end 34.797746 -298.577)
		(width 0.2794)
		(layer "F.Cu")
		(net "FAN_0_PWM_IL")
	)
	(segment
		(start 35.559746 -299.339)
		(end 36.93795 -299.339)
		(width 0.2794)
		(layer "F.Cu")
		(net "FAN_0_PWM_IL")
	)
	(segment
		(start 31.242 -298.069)
		(end 32.186372 -298.069)
		(width 0.2794)
		(layer "F.Cu")
		(net "FAN_0_PWM_IL")
	)
	(segment
		(start 29.001974 -298.069)
		(end 31.242 -298.069)
		(width 0.2794)
		(layer "F.Cu")
		(net "FAN_0_PWM_IL")
	)
	(segment
		(start 32.186372 -298.069)
		(end 32.694372 -298.577)
		(width 0.2794)
		(layer "F.Cu")
		(net "FAN_0_PWM_IL")
	)
	(via
		(at 31.242 -298.069)
		(size 0.762)
		(drill 0.381)
		(layers "F.Cu" "B.Cu")
		(net "FAN_0_PWM_IL")
	)
	(segment
		(start 6.59765 -172.212)
		(end 6.87705 -172.4914)
		(width 0.2794)
		(layer "F.Cu")
		(net "FAN_6_PRSNT_BUF_R_N")
	)
	(segment
		(start 4.59105 -172.847)
		(end 4.59105 -172.8216)
		(width 0.2794)
		(layer "F.Cu")
		(net "FAN_6_PRSNT_BUF_R_N")
	)
	(segment
		(start 6.87705 -172.847)
		(end 7.619746 -172.847)
		(width 0.2794)
		(layer "F.Cu")
		(net "FAN_6_PRSNT_BUF_R_N")
	)
	(segment
		(start 4.59105 -172.8216)
		(end 5.20065 -172.212)
		(width 0.2794)
		(layer "F.Cu")
		(net "FAN_6_PRSNT_BUF_R_N")
	)
	(segment
		(start 8.95604 -172.578014)
		(end 8.844026 -172.466)
		(width 0.2794)
		(layer "F.Cu")
		(net "FAN_6_PRSNT_BUF_R_N")
	)
	(segment
		(start 8.000746 -172.466)
		(end 8.312912 -172.466)
		(width 0.2794)
		(layer "F.Cu")
		(net "FAN_6_PRSNT_BUF_R_N")
	)
	(segment
		(start 5.20065 -172.212)
		(end 6.59765 -172.212)
		(width 0.2794)
		(layer "F.Cu")
		(net "FAN_6_PRSNT_BUF_R_N")
	)
	(segment
		(start 7.619746 -172.847)
		(end 8.000746 -172.466)
		(width 0.2794)
		(layer "F.Cu")
		(net "FAN_6_PRSNT_BUF_R_N")
	)
	(segment
		(start 8.844026 -172.466)
		(end 8.312912 -172.466)
		(width 0.2794)
		(layer "F.Cu")
		(net "FAN_6_PRSNT_BUF_R_N")
	)
	(segment
		(start 6.87705 -172.4914)
		(end 6.87705 -172.847)
		(width 0.2794)
		(layer "F.Cu")
		(net "FAN_6_PRSNT_BUF_R_N")
	)
	(via
		(at 8.312912 -172.466)
		(size 0.508)
		(drill 0.254)
		(layers "F.Cu" "B.Cu")
		(net "FAN_6_PRSNT_BUF_R_N")
	)
	(segment
		(start 32.68218 -173.26102)
		(end 32.741108 -173.202092)
		(width 0.2794)
		(layer "F.Cu")
		(net "FAN_5_FAIL_LED")
	)
	(segment
		(start 32.741108 -173.202092)
		(end 33.401 -173.202092)
		(width 0.2794)
		(layer "F.Cu")
		(net "FAN_5_FAIL_LED")
	)
	(segment
		(start 30.96768 -173.83252)
		(end 31.153354 -173.646846)
		(width 0.2794)
		(layer "F.Cu")
		(net "FAN_5_FAIL_LED")
	)
	(segment
		(start 30.1752 -174.625)
		(end 30.96768 -173.83252)
		(width 0.2794)
		(layer "F.Cu")
		(net "FAN_5_FAIL_LED")
	)
	(segment
		(start 32.085026 -173.26102)
		(end 32.68218 -173.26102)
		(width 0.2794)
		(layer "F.Cu")
		(net "FAN_5_FAIL_LED")
	)
	(segment
		(start 29.35605 -174.625)
		(end 30.1752 -174.625)
		(width 0.2794)
		(layer "F.Cu")
		(net "FAN_5_FAIL_LED")
	)
	(segment
		(start 31.153354 -173.646846)
		(end 32.085026 -173.26102)
		(width 0.2794)
		(layer "F.Cu")
		(net "FAN_5_FAIL_LED")
	)
	(via
		(at 30.96768 -173.83252)
		(size 0.762)
		(drill 0.381)
		(layers "F.Cu" "B.Cu")
		(net "FAN_5_FAIL_LED")
	)
	(via
		(at 38.71468 -75.311)
		(size 0.762)
		(drill 0.254)
		(layers "F.Cu" "B.Cu")
		(net "FAN_2_TEMP")
	)
	(segment
		(start 39.64813 -76.31811)
		(end 39.648638 -76.318618)
		(width 0.2794)
		(layer "B.Cu")
		(net "FAN_2_TEMP")
	)
	(segment
		(start 38.71468 -75.311)
		(end 38.71468 -74.362818)
		(width 0.2794)
		(layer "B.Cu")
		(net "FAN_2_TEMP")
	)
	(segment
		(start 39.648638 -76.318618)
		(end 40.216582 -76.886562)
		(width 0.1016)
		(layer "B.Cu")
		(net "FAN_2_TEMP")
	)
	(segment
		(start 38.71468 -75.311)
		(end 39.64813 -76.31811)
		(width 0.2794)
		(layer "B.Cu")
		(net "FAN_2_TEMP")
	)
	(segment
		(start 38.71468 -74.362818)
		(end 37.719 -74.362818)
		(width 0.2794)
		(layer "B.Cu")
		(net "FAN_2_TEMP")
	)
	(segment
		(start 40.216582 -76.886562)
		(end 40.216582 -77.45476)
		(width 0.1016)
		(layer "B.Cu")
		(net "FAN_2_TEMP")
	)
	(segment
		(start 30.75305 -180.829204)
		(end 30.391354 -181.1909)
		(width 0.2794)
		(layer "F.Cu")
		(net "P52V_FAN_1_BUFF_EN")
	)
	(segment
		(start 30.75305 -180.594)
		(end 30.75305 -180.829204)
		(width 0.2794)
		(layer "F.Cu")
		(net "P52V_FAN_1_BUFF_EN")
	)
	(segment
		(start 28.42895 -181.1909)
		(end 27.83205 -180.594)
		(width 0.2794)
		(layer "F.Cu")
		(net "P52V_FAN_1_BUFF_EN")
	)
	(segment
		(start 31.76905 -181.61)
		(end 33.274 -181.61)
		(width 0.2794)
		(layer "F.Cu")
		(net "P52V_FAN_1_BUFF_EN")
	)
	(segment
		(start 30.391354 -181.1909)
		(end 28.42895 -181.1909)
		(width 0.2794)
		(layer "F.Cu")
		(net "P52V_FAN_1_BUFF_EN")
	)
	(segment
		(start 31.76905 -181.61)
		(end 30.75305 -180.594)
		(width 0.2794)
		(layer "F.Cu")
		(net "P52V_FAN_1_BUFF_EN")
	)
	(via
		(at 31.76905 -181.61)
		(size 0.508)
		(drill 0.254)
		(layers "F.Cu" "B.Cu")
		(net "P52V_FAN_1_BUFF_EN")
	)
	(segment
		(start 26.60396 -25.004014)
		(end 32.342836 -25.004014)
		(width 0.2794)
		(layer "F.Cu")
		(net "FAN_3_PWM_IL")
	)
	(segment
		(start 36.43884 -27.391868)
		(end 35.489388 -26.442416)
		(width 0.2794)
		(layer "F.Cu")
		(net "FAN_3_PWM_IL")
	)
	(segment
		(start 33.323022 -25.9842)
		(end 34.4678 -25.9842)
		(width 0.2794)
		(layer "F.Cu")
		(net "FAN_3_PWM_IL")
	)
	(segment
		(start 35.489388 -26.442416)
		(end 34.926016 -26.442416)
		(width 0.2794)
		(layer "F.Cu")
		(net "FAN_3_PWM_IL")
	)
	(segment
		(start 34.926016 -26.442416)
		(end 34.4678 -25.9842)
		(width 0.2794)
		(layer "F.Cu")
		(net "FAN_3_PWM_IL")
	)
	(segment
		(start 32.342836 -25.004014)
		(end 33.323022 -25.9842)
		(width 0.2794)
		(layer "F.Cu")
		(net "FAN_3_PWM_IL")
	)
	(segment
		(start 36.93795 -27.391868)
		(end 36.43884 -27.391868)
		(width 0.2794)
		(layer "F.Cu")
		(net "FAN_3_PWM_IL")
	)
	(via
		(at 34.4678 -25.9842)
		(size 0.762)
		(drill 0.381)
		(layers "F.Cu" "B.Cu")
		(net "FAN_3_PWM_IL")
	)
	(segment
		(start 6.355842 -170.1419)
		(end 5.26415 -170.1419)
		(width 0.2794)
		(layer "F.Cu")
		(net "FAN_5_PRSNT_BUF_R_N")
	)
	(segment
		(start 6.87705 -170.815)
		(end 6.87705 -170.663108)
		(width 0.2794)
		(layer "F.Cu")
		(net "FAN_5_PRSNT_BUF_R_N")
	)
	(segment
		(start 6.87705 -170.663108)
		(end 6.355842 -170.1419)
		(width 0.2794)
		(layer "F.Cu")
		(net "FAN_5_PRSNT_BUF_R_N")
	)
	(segment
		(start 5.26415 -170.1419)
		(end 4.59105 -170.815)
		(width 0.2794)
		(layer "F.Cu")
		(net "FAN_5_PRSNT_BUF_R_N")
	)
	(segment
		(start 6.87705 -170.815)
		(end 8.844026 -170.815)
		(width 0.2794)
		(layer "F.Cu")
		(net "FAN_5_PRSNT_BUF_R_N")
	)
	(segment
		(start 8.844026 -170.815)
		(end 8.95604 -170.702986)
		(width 0.2794)
		(layer "F.Cu")
		(net "FAN_5_PRSNT_BUF_R_N")
	)
	(via
		(at 6.355842 -170.1419)
		(size 0.508)
		(drill 0.254)
		(layers "F.Cu" "B.Cu")
		(net "FAN_5_PRSNT_BUF_R_N")
	)
	(segment
		(start 27.072336 -127.90805)
		(end 27.051 -127.90805)
		(width 0.2794)
		(layer "F.Cu")
		(net "MAX31790_U317_PWM_START1")
	)
	(segment
		(start 27.688286 -128.524)
		(end 27.072336 -127.90805)
		(width 0.2794)
		(layer "F.Cu")
		(net "MAX31790_U317_PWM_START1")
	)
	(segment
		(start 28.194 -128.524)
		(end 27.688286 -128.524)
		(width 0.2794)
		(layer "F.Cu")
		(net "MAX31790_U317_PWM_START1")
	)
	(segment
		(start 27.051 -127.90805)
		(end 25.92705 -129.032)
		(width 0.2794)
		(layer "F.Cu")
		(net "MAX31790_U317_PWM_START1")
	)
	(segment
		(start 29.496004 -128.75895)
		(end 28.42895 -128.75895)
		(width 0.1016)
		(layer "F.Cu")
		(net "MAX31790_U317_PWM_START1")
	)
	(segment
		(start 28.42895 -128.75895)
		(end 28.194 -128.524)
		(width 0.1016)
		(layer "F.Cu")
		(net "MAX31790_U317_PWM_START1")
	)
	(segment
		(start 25.92705 -129.032)
		(end 25.92705 -129.413)
		(width 0.2794)
		(layer "F.Cu")
		(net "MAX31790_U317_PWM_START1")
	)
	(via
		(at 28.194 -128.524)
		(size 0.508)
		(drill 0.254)
		(layers "F.Cu" "B.Cu")
		(net "MAX31790_U317_PWM_START1")
	)
	(segment
		(start 31.09595 -175.93945)
		(end 31.09595 -176.403)
		(width 0.2794)
		(layer "F.Cu")
		(net "FAN_4_FAIL_LED")
	)
	(segment
		(start 32.533336 -174.502064)
		(end 32.05099 -174.98441)
		(width 0.2794)
		(layer "F.Cu")
		(net "FAN_4_FAIL_LED")
	)
	(segment
		(start 33.401 -174.502064)
		(end 32.533336 -174.502064)
		(width 0.2794)
		(layer "F.Cu")
		(net "FAN_4_FAIL_LED")
	)
	(segment
		(start 32.05099 -174.98441)
		(end 31.09595 -175.93945)
		(width 0.2794)
		(layer "F.Cu")
		(net "FAN_4_FAIL_LED")
	)
	(via
		(at 32.05099 -174.98441)
		(size 0.508)
		(drill 0.254)
		(layers "F.Cu" "B.Cu")
		(net "FAN_4_FAIL_LED")
	)
	(segment
		(start 43.270932 -74.912982)
		(end 43.270932 -75.909932)
		(width 0.2794)
		(layer "F.Cu")
		(net "FAN_2_FAULT")
	)
	(segment
		(start 42.418 -74.06005)
		(end 43.270932 -74.912982)
		(width 0.2794)
		(layer "F.Cu")
		(net "FAN_2_FAULT")
	)
	(via
		(at 43.270932 -75.909932)
		(size 0.508)
		(drill 0.254)
		(layers "F.Cu" "B.Cu")
		(net "FAN_2_FAULT")
	)
	(segment
		(start 43.270932 -75.909932)
		(end 43.270932 -76.257404)
		(width 0.2794)
		(layer "B.Cu")
		(net "FAN_2_FAULT")
	)
	(segment
		(start 43.016678 -76.871576)
		(end 43.016678 -77.45476)
		(width 0.1016)
		(layer "B.Cu")
		(net "FAN_2_FAULT")
	)
	(segment
		(start 43.270932 -76.257404)
		(end 43.016678 -76.871576)
		(width 0.1016)
		(layer "B.Cu")
		(net "FAN_2_FAULT")
	)
	(segment
		(start 30.75305 -182.372)
		(end 31.876746 -182.372)
		(width 0.2794)
		(layer "F.Cu")
		(net "P52V_FAN_0_BUFF_EN")
	)
	(segment
		(start 30.75305 -183.396128)
		(end 30.75305 -182.372)
		(width 0.2794)
		(layer "F.Cu")
		(net "P52V_FAN_0_BUFF_EN")
	)
	(segment
		(start 27.83205 -182.372)
		(end 29.135578 -183.675528)
		(width 0.2794)
		(layer "F.Cu")
		(net "P52V_FAN_0_BUFF_EN")
	)
	(segment
		(start 31.876746 -182.372)
		(end 32.414718 -182.909972)
		(width 0.2794)
		(layer "F.Cu")
		(net "P52V_FAN_0_BUFF_EN")
	)
	(segment
		(start 30.47365 -183.675528)
		(end 30.75305 -183.396128)
		(width 0.2794)
		(layer "F.Cu")
		(net "P52V_FAN_0_BUFF_EN")
	)
	(segment
		(start 32.414718 -182.909972)
		(end 33.274 -182.909972)
		(width 0.2794)
		(layer "F.Cu")
		(net "P52V_FAN_0_BUFF_EN")
	)
	(segment
		(start 29.135578 -183.675528)
		(end 30.47365 -183.675528)
		(width 0.2794)
		(layer "F.Cu")
		(net "P52V_FAN_0_BUFF_EN")
	)
	(via
		(at 30.47365 -183.675528)
		(size 0.762)
		(drill 0.381)
		(layers "F.Cu" "B.Cu")
		(net "P52V_FAN_0_BUFF_EN")
	)
	(segment
		(start 23.128986 -301.93996)
		(end 23.128986 -303.017936)
		(width 0.2794)
		(layer "F.Cu")
		(net "FAN_0_PWM_BUF")
	)
	(segment
		(start 24.83104 -303.22012)
		(end 23.33117 -303.22012)
		(width 0.2794)
		(layer "F.Cu")
		(net "FAN_0_PWM_BUF")
	)
	(segment
		(start 23.128986 -303.017936)
		(end 23.241 -303.12995)
		(width 0.2794)
		(layer "F.Cu")
		(net "FAN_0_PWM_BUF")
	)
	(segment
		(start 23.33117 -303.22012)
		(end 23.241 -303.12995)
		(width 0.2794)
		(layer "F.Cu")
		(net "FAN_0_PWM_BUF")
	)
	(segment
		(start 24.83104 -300.99)
		(end 24.83104 -303.22012)
		(width 0.2794)
		(layer "F.Cu")
		(net "FAN_0_PWM_BUF")
	)
	(via
		(at 24.83104 -303.22012)
		(size 0.762)
		(drill 0.381)
		(layers "F.Cu" "B.Cu")
		(net "FAN_0_PWM_BUF")
	)
	(segment
		(start 6.87705 -169.291)
		(end 8.844026 -169.291)
		(width 0.2794)
		(layer "F.Cu")
		(net "FAN_4_PRSNT_BUF_R_N")
	)
	(segment
		(start 6.355842 -168.6179)
		(end 5.26415 -168.6179)
		(width 0.2794)
		(layer "F.Cu")
		(net "FAN_4_PRSNT_BUF_R_N")
	)
	(segment
		(start 6.87705 -169.291)
		(end 6.87705 -169.139108)
		(width 0.2794)
		(layer "F.Cu")
		(net "FAN_4_PRSNT_BUF_R_N")
	)
	(segment
		(start 5.26415 -168.6179)
		(end 4.59105 -169.291)
		(width 0.2794)
		(layer "F.Cu")
		(net "FAN_4_PRSNT_BUF_R_N")
	)
	(segment
		(start 6.87705 -169.139108)
		(end 6.355842 -168.6179)
		(width 0.2794)
		(layer "F.Cu")
		(net "FAN_4_PRSNT_BUF_R_N")
	)
	(segment
		(start 8.844026 -169.291)
		(end 8.95604 -169.403014)
		(width 0.2794)
		(layer "F.Cu")
		(net "FAN_4_PRSNT_BUF_R_N")
	)
	(via
		(at 6.355842 -168.6179)
		(size 0.508)
		(drill 0.254)
		(layers "F.Cu" "B.Cu")
		(net "FAN_4_PRSNT_BUF_R_N")
	)
	(segment
		(start 30.6197 -175.1711)
		(end 31.01086 -175.1711)
		(width 0.2794)
		(layer "F.Cu")
		(net "FAN_5_OK_LED")
	)
	(segment
		(start 29.844746 -176.022)
		(end 30.6197 -175.247046)
		(width 0.2794)
		(layer "F.Cu")
		(net "FAN_5_OK_LED")
	)
	(segment
		(start 32.329882 -173.852078)
		(end 33.401 -173.852078)
		(width 0.2794)
		(layer "F.Cu")
		(net "FAN_5_OK_LED")
	)
	(segment
		(start 29.35605 -176.022)
		(end 29.844746 -176.022)
		(width 0.2794)
		(layer "F.Cu")
		(net "FAN_5_OK_LED")
	)
	(segment
		(start 31.01086 -175.1711)
		(end 32.329882 -173.852078)
		(width 0.2794)
		(layer "F.Cu")
		(net "FAN_5_OK_LED")
	)
	(segment
		(start 30.6197 -175.247046)
		(end 30.6197 -175.1711)
		(width 0.2794)
		(layer "F.Cu")
		(net "FAN_5_OK_LED")
	)
	(via
		(at 30.6197 -175.1711)
		(size 0.762)
		(drill 0.381)
		(layers "F.Cu" "B.Cu")
		(net "FAN_5_OK_LED")
	)
	(segment
		(start 40.64 -75.819)
		(end 40.386 -76.073)
		(width 0.2794)
		(layer "F.Cu")
		(net "FAN_2_P3V_R")
	)
	(segment
		(start 40.259 -73.25995)
		(end 40.36695 -73.152)
		(width 0.2794)
		(layer "F.Cu")
		(net "FAN_2_P3V_R")
	)
	(segment
		(start 37.211 -75.438)
		(end 37.211 -73.914)
		(width 0.2794)
		(layer "F.Cu")
		(net "FAN_2_P3V_R")
	)
	(segment
		(start 39.243 -73.25995)
		(end 40.259 -73.25995)
		(width 0.2794)
		(layer "F.Cu")
		(net "FAN_2_P3V_R")
	)
	(segment
		(start 37.211 -73.914)
		(end 37.86505 -73.25995)
		(width 0.2794)
		(layer "F.Cu")
		(net "FAN_2_P3V_R")
	)
	(segment
		(start 37.86505 -73.25995)
		(end 39.243 -73.25995)
		(width 0.2794)
		(layer "F.Cu")
		(net "FAN_2_P3V_R")
	)
	(segment
		(start 40.386 -76.073)
		(end 37.846 -76.073)
		(width 0.2794)
		(layer "F.Cu")
		(net "FAN_2_P3V_R")
	)
	(segment
		(start 37.846 -76.073)
		(end 37.211 -75.438)
		(width 0.2794)
		(layer "F.Cu")
		(net "FAN_2_P3V_R")
	)
	(via
		(at 40.64 -75.819)
		(size 0.762)
		(drill 0.254)
		(layers "F.Cu" "B.Cu")
		(net "FAN_2_P3V_R")
	)
	(segment
		(start 41.016682 -77.063092)
		(end 41.016682 -77.45476)
		(width 0.1016)
		(layer "B.Cu")
		(net "FAN_2_P3V_R")
	)
	(segment
		(start 40.64 -75.819)
		(end 40.746426 -75.906122)
		(width 0.1016)
		(layer "B.Cu")
		(net "FAN_2_P3V_R")
	)
	(segment
		(start 40.746426 -75.906122)
		(end 40.812212 -76.569062)
		(width 0.1016)
		(layer "B.Cu")
		(net "FAN_2_P3V_R")
	)
	(segment
		(start 40.767 -74.371962)
		(end 40.767 -75.692)
		(width 0.2794)
		(layer "B.Cu")
		(net "FAN_2_P3V_R")
	)
	(segment
		(start 40.767 -75.692)
		(end 40.64 -75.819)
		(width 0.2794)
		(layer "B.Cu")
		(net "FAN_2_P3V_R")
	)
	(segment
		(start 40.812212 -76.569062)
		(end 41.016682 -77.063092)
		(width 0.1016)
		(layer "B.Cu")
		(net "FAN_2_P3V_R")
	)
	(segment
		(start 34.671 -185.039)
		(end 33.67405 -185.039)
		(width 0.2794)
		(layer "F.Cu")
		(net "P52V_FAN_BUFF_EN_R")
	)
	(segment
		(start 31.179008 -191.433958)
		(end 33.401 -191.433958)
		(width 0.2794)
		(layer "F.Cu")
		(net "P52V_FAN_BUFF_EN_R")
	)
	(segment
		(start 34.671 -191.135)
		(end 34.372042 -191.433958)
		(width 0.2794)
		(layer "F.Cu")
		(net "P52V_FAN_BUFF_EN_R")
	)
	(segment
		(start 39.243 -188.184028)
		(end 34.954972 -188.184028)
		(width 0.2794)
		(layer "F.Cu")
		(net "P52V_FAN_BUFF_EN_R")
	)
	(segment
		(start 34.671 -189.738)
		(end 34.304986 -190.104014)
		(width 0.2794)
		(layer "F.Cu")
		(net "P52V_FAN_BUFF_EN_R")
	)
	(segment
		(start 34.671 -190.5)
		(end 34.671 -191.135)
		(width 0.2794)
		(layer "F.Cu")
		(net "P52V_FAN_BUFF_EN_R")
	)
	(segment
		(start 34.671 -181.229)
		(end 34.402014 -180.960014)
		(width 0.2794)
		(layer "F.Cu")
		(net "P52V_FAN_BUFF_EN_R")
	)
	(segment
		(start 34.473388 -182.259986)
		(end 34.671 -182.457598)
		(width 0.2794)
		(layer "F.Cu")
		(net "P52V_FAN_BUFF_EN_R")
	)
	(segment
		(start 33.401 -190.133986)
		(end 34.304986 -190.133986)
		(width 0.2794)
		(layer "F.Cu")
		(net "P52V_FAN_BUFF_EN_R")
	)
	(segment
		(start 33.274 -184.57926)
		(end 33.274 -183.559958)
		(width 0.2794)
		(layer "F.Cu")
		(net "P52V_FAN_BUFF_EN_R")
	)
	(segment
		(start 34.671 -182.457598)
		(end 34.671 -183.261)
		(width 0.2794)
		(layer "F.Cu")
		(net "P52V_FAN_BUFF_EN_R")
	)
	(segment
		(start 34.304986 -190.133986)
		(end 34.671 -190.5)
		(width 0.2794)
		(layer "F.Cu")
		(net "P52V_FAN_BUFF_EN_R")
	)
	(segment
		(start 34.473388 -182.259986)
		(end 34.671 -182.062374)
		(width 0.2794)
		(layer "F.Cu")
		(net "P52V_FAN_BUFF_EN_R")
	)
	(segment
		(start 34.671 -188.468)
		(end 34.671 -189.738)
		(width 0.2794)
		(layer "F.Cu")
		(net "P52V_FAN_BUFF_EN_R")
	)
	(segment
		(start 33.274 -182.259986)
		(end 34.473388 -182.259986)
		(width 0.2794)
		(layer "F.Cu")
		(net "P52V_FAN_BUFF_EN_R")
	)
	(segment
		(start 34.671 -188.468)
		(end 34.304986 -188.834014)
		(width 0.2794)
		(layer "F.Cu")
		(net "P52V_FAN_BUFF_EN_R")
	)
	(segment
		(start 34.671 -182.062374)
		(end 34.671 -181.229)
		(width 0.2794)
		(layer "F.Cu")
		(net "P52V_FAN_BUFF_EN_R")
	)
	(segment
		(start 34.304986 -188.834014)
		(end 33.401 -188.834014)
		(width 0.2794)
		(layer "F.Cu")
		(net "P52V_FAN_BUFF_EN_R")
	)
	(segment
		(start 34.304986 -190.104014)
		(end 34.304986 -190.133986)
		(width 0.2794)
		(layer "F.Cu")
		(net "P52V_FAN_BUFF_EN_R")
	)
	(segment
		(start 35.052 -180.310028)
		(end 34.402014 -180.960014)
		(width 0.2794)
		(layer "F.Cu")
		(net "P52V_FAN_BUFF_EN_R")
	)
	(segment
		(start 34.954972 -188.184028)
		(end 34.671 -188.468)
		(width 0.2794)
		(layer "F.Cu")
		(net "P52V_FAN_BUFF_EN_R")
	)
	(segment
		(start 34.402014 -180.960014)
		(end 33.274 -180.960014)
		(width 0.2794)
		(layer "F.Cu")
		(net "P52V_FAN_BUFF_EN_R")
	)
	(segment
		(start 34.372042 -191.433958)
		(end 33.401 -191.433958)
		(width 0.2794)
		(layer "F.Cu")
		(net "P52V_FAN_BUFF_EN_R")
	)
	(segment
		(start 30.75305 -191.008)
		(end 31.179008 -191.433958)
		(width 0.2794)
		(layer "F.Cu")
		(net "P52V_FAN_BUFF_EN_R")
	)
	(segment
		(start 34.372042 -183.559958)
		(end 33.274 -183.559958)
		(width 0.2794)
		(layer "F.Cu")
		(net "P52V_FAN_BUFF_EN_R")
	)
	(segment
		(start 33.67405 -185.039)
		(end 33.67405 -184.97931)
		(width 0.2794)
		(layer "F.Cu")
		(net "P52V_FAN_BUFF_EN_R")
	)
	(segment
		(start 39.116 -180.310028)
		(end 35.052 -180.310028)
		(width 0.2794)
		(layer "F.Cu")
		(net "P52V_FAN_BUFF_EN_R")
	)
	(segment
		(start 34.671 -183.261)
		(end 34.372042 -183.559958)
		(width 0.2794)
		(layer "F.Cu")
		(net "P52V_FAN_BUFF_EN_R")
	)
	(segment
		(start 33.67405 -184.97931)
		(end 33.274 -184.57926)
		(width 0.2794)
		(layer "F.Cu")
		(net "P52V_FAN_BUFF_EN_R")
	)
	(via
		(at 34.671 -185.039)
		(size 0.508)
		(drill 0.254)
		(layers "F.Cu" "B.Cu")
		(net "P52V_FAN_BUFF_EN_R")
	)
	(via
		(at 34.671 -188.468)
		(size 0.508)
		(drill 0.254)
		(layers "F.Cu" "B.Cu")
		(net "P52V_FAN_BUFF_EN_R")
	)
	(segment
		(start 34.671 -188.468)
		(end 34.671 -185.039)
		(width 0.2286)
		(layer "In2.Cu")
		(net "P52V_FAN_BUFF_EN_R")
	)
	(segment
		(start 20.568412 -147.955)
		(end 21.18995 -148.576538)
		(width 0.2794)
		(layer "F.Cu")
		(net "PD_TCA9548_SML1_U321_A0")
	)
	(segment
		(start 17.272 -147.193)
		(end 17.272 -146.45005)
		(width 0.2794)
		(layer "F.Cu")
		(net "PD_TCA9548_SML1_U321_A0")
	)
	(segment
		(start 21.18995 -148.576538)
		(end 21.18995 -149.098)
		(width 0.2794)
		(layer "F.Cu")
		(net "PD_TCA9548_SML1_U321_A0")
	)
	(segment
		(start 16.51 -144.7292)
		(end 16.94815 -144.29105)
		(width 0.2794)
		(layer "F.Cu")
		(net "PD_TCA9548_SML1_U321_A0")
	)
	(segment
		(start 18.516346 -147.955)
		(end 18.034 -147.955)
		(width 0.2794)
		(layer "F.Cu")
		(net "PD_TCA9548_SML1_U321_A0")
	)
	(segment
		(start 16.94815 -144.29105)
		(end 17.272 -144.29105)
		(width 0.2794)
		(layer "F.Cu")
		(net "PD_TCA9548_SML1_U321_A0")
	)
	(segment
		(start 18.034 -147.955)
		(end 17.272 -147.193)
		(width 0.2794)
		(layer "F.Cu")
		(net "PD_TCA9548_SML1_U321_A0")
	)
	(segment
		(start 18.516346 -147.955)
		(end 20.568412 -147.955)
		(width 0.2794)
		(layer "F.Cu")
		(net "PD_TCA9548_SML1_U321_A0")
	)
	(segment
		(start 16.51 -145.839942)
		(end 16.51 -144.7292)
		(width 0.2794)
		(layer "F.Cu")
		(net "PD_TCA9548_SML1_U321_A0")
	)
	(segment
		(start 17.120108 -146.45005)
		(end 16.51 -145.839942)
		(width 0.2794)
		(layer "F.Cu")
		(net "PD_TCA9548_SML1_U321_A0")
	)
	(segment
		(start 17.272 -146.45005)
		(end 17.120108 -146.45005)
		(width 0.2794)
		(layer "F.Cu")
		(net "PD_TCA9548_SML1_U321_A0")
	)
	(via
		(at 18.516346 -147.955)
		(size 0.762)
		(drill 0.381)
		(layers "F.Cu" "B.Cu")
		(net "PD_TCA9548_SML1_U321_A0")
	)
	(segment
		(start 26.73096 -209.991706)
		(end 29.718254 -212.979)
		(width 0.2794)
		(layer "F.Cu")
		(net "FAN_1_PWM_OL")
	)
	(segment
		(start 29.718254 -212.979)
		(end 30.988 -212.979)
		(width 0.2794)
		(layer "F.Cu")
		(net "FAN_1_PWM_OL")
	)
	(segment
		(start 26.73096 -209.437986)
		(end 26.73096 -209.991706)
		(width 0.2794)
		(layer "F.Cu")
		(net "FAN_1_PWM_OL")
	)
	(segment
		(start 37.06495 -211.864956)
		(end 35.696906 -213.233)
		(width 0.2794)
		(layer "F.Cu")
		(net "FAN_1_PWM_OL")
	)
	(segment
		(start 31.242 -213.233)
		(end 30.988 -212.979)
		(width 0.2794)
		(layer "F.Cu")
		(net "FAN_1_PWM_OL")
	)
	(segment
		(start 35.696906 -213.233)
		(end 31.242 -213.233)
		(width 0.2794)
		(layer "F.Cu")
		(net "FAN_1_PWM_OL")
	)
	(via
		(at 30.988 -212.979)
		(size 0.762)
		(drill 0.381)
		(layers "F.Cu" "B.Cu")
		(net "FAN_1_PWM_OL")
	)
	(segment
		(start 15.22095 -174.141892)
		(end 15.742158 -174.6631)
		(width 0.2794)
		(layer "F.Cu")
		(net "FAN_7_PRESENT_N")
	)
	(segment
		(start 13.40231 -175.19904)
		(end 12.93495 -174.73168)
		(width 0.2794)
		(layer "F.Cu")
		(net "FAN_7_PRESENT_N")
	)
	(segment
		(start 16.83385 -174.6631)
		(end 17.50695 -173.99)
		(width 0.2794)
		(layer "F.Cu")
		(net "FAN_7_PRESENT_N")
	)
	(segment
		(start 15.22095 -173.99)
		(end 15.22095 -174.141892)
		(width 0.2794)
		(layer "F.Cu")
		(net "FAN_7_PRESENT_N")
	)
	(segment
		(start 10.85596 -173.877986)
		(end 10.967974 -173.99)
		(width 0.2794)
		(layer "F.Cu")
		(net "FAN_7_PRESENT_N")
	)
	(segment
		(start 14.01191 -175.19904)
		(end 13.75664 -175.19904)
		(width 0.2794)
		(layer "F.Cu")
		(net "FAN_7_PRESENT_N")
	)
	(segment
		(start 12.93495 -174.73168)
		(end 12.93495 -173.99)
		(width 0.2794)
		(layer "F.Cu")
		(net "FAN_7_PRESENT_N")
	)
	(segment
		(start 15.742158 -174.6631)
		(end 16.83385 -174.6631)
		(width 0.2794)
		(layer "F.Cu")
		(net "FAN_7_PRESENT_N")
	)
	(segment
		(start 13.75664 -175.19904)
		(end 13.40231 -175.19904)
		(width 0.2794)
		(layer "F.Cu")
		(net "FAN_7_PRESENT_N")
	)
	(segment
		(start 10.967974 -173.99)
		(end 12.93495 -173.99)
		(width 0.2794)
		(layer "F.Cu")
		(net "FAN_7_PRESENT_N")
	)
	(segment
		(start 15.22095 -173.99)
		(end 14.01191 -175.19904)
		(width 0.2794)
		(layer "F.Cu")
		(net "FAN_7_PRESENT_N")
	)
	(via
		(at 13.75664 -175.19904)
		(size 0.762)
		(drill 0.381)
		(layers "F.Cu" "B.Cu")
		(net "FAN_7_PRESENT_N")
	)
	(segment
		(start 41.364916 -174.240444)
		(end 40.326564 -173.202092)
		(width 0.2794)
		(layer "F.Cu")
		(net "FAN_2_FAIL_LED")
	)
	(segment
		(start 40.326564 -173.202092)
		(end 39.243 -173.202092)
		(width 0.2794)
		(layer "F.Cu")
		(net "FAN_2_FAIL_LED")
	)
	(segment
		(start 42.522394 -174.240444)
		(end 41.918128 -174.240444)
		(width 0.2794)
		(layer "F.Cu")
		(net "FAN_2_FAIL_LED")
	)
	(segment
		(start 41.918128 -174.240444)
		(end 41.364916 -174.240444)
		(width 0.2794)
		(layer "F.Cu")
		(net "FAN_2_FAIL_LED")
	)
	(segment
		(start 43.16095 -174.879)
		(end 42.522394 -174.240444)
		(width 0.2794)
		(layer "F.Cu")
		(net "FAN_2_FAIL_LED")
	)
	(via
		(at 41.918128 -174.240444)
		(size 0.762)
		(drill 0.381)
		(layers "F.Cu" "B.Cu")
		(net "FAN_2_FAIL_LED")
	)
	(segment
		(start 37.973 -74.929746)
		(end 38.842696 -74.06005)
		(width 0.2794)
		(layer "F.Cu")
		(net "FAN_2_MODE")
	)
	(segment
		(start 39.243 -74.06005)
		(end 40.259 -74.06005)
		(width 0.2794)
		(layer "F.Cu")
		(net "FAN_2_MODE")
	)
	(segment
		(start 37.973 -75.057)
		(end 37.973 -74.929746)
		(width 0.2794)
		(layer "F.Cu")
		(net "FAN_2_MODE")
	)
	(segment
		(start 40.259 -74.06005)
		(end 40.36695 -74.168)
		(width 0.2794)
		(layer "F.Cu")
		(net "FAN_2_MODE")
	)
	(segment
		(start 38.842696 -74.06005)
		(end 39.243 -74.06005)
		(width 0.2794)
		(layer "F.Cu")
		(net "FAN_2_MODE")
	)
	(via
		(at 38.16858 -75.84186)
		(size 0.6604)
		(drill 0.3302)
		(layers "F.Cu" "B.Cu")
		(net "FAN_2_MODE")
	)
	(via
		(at 37.973 -75.057)
		(size 0.508)
		(drill 0.254)
		(layers "F.Cu" "B.Cu")
		(net "FAN_2_MODE")
	)
	(segment
		(start 39.816786 -77.375766)
		(end 39.714932 -77.273912)
		(width 0.1016)
		(layer "B.Cu")
		(net "FAN_2_MODE")
	)
	(segment
		(start 39.816786 -77.45476)
		(end 39.816786 -77.375766)
		(width 0.1016)
		(layer "B.Cu")
		(net "FAN_2_MODE")
	)
	(segment
		(start 39.714932 -77.273912)
		(end 38.28288 -75.84186)
		(width 0.2794)
		(layer "B.Cu")
		(net "FAN_2_MODE")
	)
	(segment
		(start 38.28288 -75.84186)
		(end 38.16858 -75.84186)
		(width 0.2794)
		(layer "B.Cu")
		(net "FAN_2_MODE")
	)
	(segment
		(start 38.16858 -75.84186)
		(end 37.973 -75.64628)
		(width 0.2794)
		(layer "B.Cu")
		(net "FAN_2_MODE")
	)
	(segment
		(start 37.973 -75.64628)
		(end 37.973 -75.057)
		(width 0.2794)
		(layer "B.Cu")
		(net "FAN_2_MODE")
	)
	(segment
		(start 41.63695 -186.182)
		(end 41.63695 -186.28995)
		(width 0.2794)
		(layer "F.Cu")
		(net "P52V_FAN_7_BUFF_EN")
	)
	(segment
		(start 44.68495 -186.182)
		(end 44.003468 -186.863482)
		(width 0.2794)
		(layer "F.Cu")
		(net "P52V_FAN_7_BUFF_EN")
	)
	(segment
		(start 39.243 -187.534042)
		(end 40.284908 -187.534042)
		(width 0.2794)
		(layer "F.Cu")
		(net "P52V_FAN_7_BUFF_EN")
	)
	(segment
		(start 41.63695 -186.28995)
		(end 42.210482 -186.863482)
		(width 0.2794)
		(layer "F.Cu")
		(net "P52V_FAN_7_BUFF_EN")
	)
	(segment
		(start 44.003468 -186.863482)
		(end 43.582844 -186.863482)
		(width 0.2794)
		(layer "F.Cu")
		(net "P52V_FAN_7_BUFF_EN")
	)
	(segment
		(start 42.210482 -186.863482)
		(end 43.582844 -186.863482)
		(width 0.2794)
		(layer "F.Cu")
		(net "P52V_FAN_7_BUFF_EN")
	)
	(segment
		(start 40.284908 -187.534042)
		(end 41.63695 -186.182)
		(width 0.2794)
		(layer "F.Cu")
		(net "P52V_FAN_7_BUFF_EN")
	)
	(via
		(at 43.582844 -186.863482)
		(size 0.508)
		(drill 0.254)
		(layers "F.Cu" "B.Cu")
		(net "P52V_FAN_7_BUFF_EN")
	)
	(segment
		(start 19.812 -145.05305)
		(end 19.812 -145.922746)
		(width 0.2794)
		(layer "F.Cu")
		(net "PD_TCA9548_SML1_U321_A1")
	)
	(segment
		(start 19.05 -146.45005)
		(end 19.05 -146.7866)
		(width 0.2794)
		(layer "F.Cu")
		(net "PD_TCA9548_SML1_U321_A1")
	)
	(segment
		(start 19.05 -146.7866)
		(end 19.3294 -147.066)
		(width 0.2794)
		(layer "F.Cu")
		(net "PD_TCA9548_SML1_U321_A1")
	)
	(segment
		(start 19.284696 -146.45005)
		(end 19.05 -146.45005)
		(width 0.2794)
		(layer "F.Cu")
		(net "PD_TCA9548_SML1_U321_A1")
	)
	(segment
		(start 19.05 -144.29105)
		(end 19.812 -145.05305)
		(width 0.2794)
		(layer "F.Cu")
		(net "PD_TCA9548_SML1_U321_A1")
	)
	(segment
		(start 21.839936 -148.331936)
		(end 21.839936 -149.098)
		(width 0.2794)
		(layer "F.Cu")
		(net "PD_TCA9548_SML1_U321_A1")
	)
	(segment
		(start 20.30222 -147.066)
		(end 20.574 -147.066)
		(width 0.2794)
		(layer "F.Cu")
		(net "PD_TCA9548_SML1_U321_A1")
	)
	(segment
		(start 20.574 -147.066)
		(end 21.839936 -148.331936)
		(width 0.2794)
		(layer "F.Cu")
		(net "PD_TCA9548_SML1_U321_A1")
	)
	(segment
		(start 19.3294 -147.066)
		(end 20.30222 -147.066)
		(width 0.2794)
		(layer "F.Cu")
		(net "PD_TCA9548_SML1_U321_A1")
	)
	(segment
		(start 19.812 -145.922746)
		(end 19.284696 -146.45005)
		(width 0.2794)
		(layer "F.Cu")
		(net "PD_TCA9548_SML1_U321_A1")
	)
	(via
		(at 20.30222 -147.066)
		(size 0.762)
		(drill 0.381)
		(layers "F.Cu" "B.Cu")
		(net "PD_TCA9548_SML1_U321_A1")
	)
	(segment
		(start 31.242 -305.4223)
		(end 31.83636 -306.01666)
		(width 0.2794)
		(layer "F.Cu")
		(net "FAN_0_PWM_OL")
	)
	(segment
		(start 30.513274 -305.4223)
		(end 31.242 -305.4223)
		(width 0.2794)
		(layer "F.Cu")
		(net "FAN_0_PWM_OL")
	)
	(segment
		(start 31.83636 -306.01666)
		(end 35.21329 -306.01666)
		(width 0.2794)
		(layer "F.Cu")
		(net "FAN_0_PWM_OL")
	)
	(segment
		(start 35.21329 -306.01666)
		(end 37.06495 -304.165)
		(width 0.2794)
		(layer "F.Cu")
		(net "FAN_0_PWM_OL")
	)
	(segment
		(start 26.73096 -301.639986)
		(end 28.519374 -303.4284)
		(width 0.2794)
		(layer "F.Cu")
		(net "FAN_0_PWM_OL")
	)
	(segment
		(start 28.519374 -303.4284)
		(end 30.513274 -305.4223)
		(width 0.2794)
		(layer "F.Cu")
		(net "FAN_0_PWM_OL")
	)
	(via
		(at 28.519374 -303.4284)
		(size 0.762)
		(drill 0.381)
		(layers "F.Cu" "B.Cu")
		(net "FAN_0_PWM_OL")
	)
	(segment
		(start 15.22095 -172.617892)
		(end 15.742158 -173.1391)
		(width 0.2794)
		(layer "F.Cu")
		(net "FAN_6_PRESENT_N")
	)
	(segment
		(start 12.93495 -172.617892)
		(end 12.93495 -172.466)
		(width 0.2794)
		(layer "F.Cu")
		(net "FAN_6_PRESENT_N")
	)
	(segment
		(start 15.742158 -173.1391)
		(end 16.83385 -173.1391)
		(width 0.2794)
		(layer "F.Cu")
		(net "FAN_6_PRESENT_N")
	)
	(segment
		(start 13.456158 -173.1391)
		(end 12.93495 -172.617892)
		(width 0.2794)
		(layer "F.Cu")
		(net "FAN_6_PRESENT_N")
	)
	(segment
		(start 16.83385 -173.1391)
		(end 17.50695 -172.466)
		(width 0.2794)
		(layer "F.Cu")
		(net "FAN_6_PRESENT_N")
	)
	(segment
		(start 14.54785 -173.1391)
		(end 13.456158 -173.1391)
		(width 0.2794)
		(layer "F.Cu")
		(net "FAN_6_PRESENT_N")
	)
	(segment
		(start 10.967974 -172.466)
		(end 12.93495 -172.466)
		(width 0.2794)
		(layer "F.Cu")
		(net "FAN_6_PRESENT_N")
	)
	(segment
		(start 15.22095 -172.466)
		(end 15.22095 -172.617892)
		(width 0.2794)
		(layer "F.Cu")
		(net "FAN_6_PRESENT_N")
	)
	(segment
		(start 15.22095 -172.466)
		(end 14.54785 -173.1391)
		(width 0.2794)
		(layer "F.Cu")
		(net "FAN_6_PRESENT_N")
	)
	(segment
		(start 10.85596 -172.578014)
		(end 10.967974 -172.466)
		(width 0.2794)
		(layer "F.Cu")
		(net "FAN_6_PRESENT_N")
	)
	(via
		(at 13.456158 -173.1391)
		(size 0.508)
		(drill 0.254)
		(layers "F.Cu" "B.Cu")
		(net "FAN_6_PRESENT_N")
	)
	(segment
		(start 29.93644 -172.593)
		(end 30.55747 -171.97197)
		(width 0.2794)
		(layer "F.Cu")
		(net "FAN_6_FAIL_LED")
	)
	(segment
		(start 32.7152 -171.90212)
		(end 33.401 -171.90212)
		(width 0.2794)
		(layer "F.Cu")
		(net "FAN_6_FAIL_LED")
	)
	(segment
		(start 29.35605 -172.593)
		(end 29.93644 -172.593)
		(width 0.2794)
		(layer "F.Cu")
		(net "FAN_6_FAIL_LED")
	)
	(segment
		(start 30.55747 -171.97197)
		(end 30.57144 -171.958)
		(width 0.2794)
		(layer "F.Cu")
		(net "FAN_6_FAIL_LED")
	)
	(segment
		(start 32.65932 -171.958)
		(end 32.7152 -171.90212)
		(width 0.2794)
		(layer "F.Cu")
		(net "FAN_6_FAIL_LED")
	)
	(segment
		(start 30.57144 -171.958)
		(end 32.65932 -171.958)
		(width 0.2794)
		(layer "F.Cu")
		(net "FAN_6_FAIL_LED")
	)
	(via
		(at 30.55747 -171.97197)
		(size 0.762)
		(drill 0.381)
		(layers "F.Cu" "B.Cu")
		(net "FAN_6_FAIL_LED")
	)
	(segment
		(start 28.59405 -186.436)
		(end 30.226 -186.436)
		(width 0.2794)
		(layer "F.Cu")
		(net "P52V_FAN_6_BUFF_EN")
	)
	(segment
		(start 30.226 -186.436)
		(end 30.75305 -185.90895)
		(width 0.2794)
		(layer "F.Cu")
		(net "P52V_FAN_6_BUFF_EN")
	)
	(segment
		(start 30.75305 -185.674)
		(end 30.99435 -185.674)
		(width 0.2794)
		(layer "F.Cu")
		(net "P52V_FAN_6_BUFF_EN")
	)
	(segment
		(start 27.83205 -185.674)
		(end 28.59405 -186.436)
		(width 0.2794)
		(layer "F.Cu")
		(net "P52V_FAN_6_BUFF_EN")
	)
	(segment
		(start 32.736028 -188.184028)
		(end 33.401 -188.184028)
		(width 0.2794)
		(layer "F.Cu")
		(net "P52V_FAN_6_BUFF_EN")
	)
	(segment
		(start 31.24835 -185.928)
		(end 31.24835 -186.69635)
		(width 0.2794)
		(layer "F.Cu")
		(net "P52V_FAN_6_BUFF_EN")
	)
	(segment
		(start 31.24835 -186.69635)
		(end 32.736028 -188.184028)
		(width 0.2794)
		(layer "F.Cu")
		(net "P52V_FAN_6_BUFF_EN")
	)
	(segment
		(start 30.75305 -185.90895)
		(end 30.75305 -185.674)
		(width 0.2794)
		(layer "F.Cu")
		(net "P52V_FAN_6_BUFF_EN")
	)
	(segment
		(start 30.99435 -185.674)
		(end 31.24835 -185.928)
		(width 0.2794)
		(layer "F.Cu")
		(net "P52V_FAN_6_BUFF_EN")
	)
	(via
		(at 30.226 -186.436)
		(size 0.508)
		(drill 0.254)
		(layers "F.Cu" "B.Cu")
		(net "P52V_FAN_6_BUFF_EN")
	)
	(segment
		(start 20.614386 -162.449764)
		(end 20.614386 -160.485836)
		(width 0.2794)
		(layer "F.Cu")
		(net "PD_TCA9548_SML1_U321_A2")
	)
	(segment
		(start 23.139908 -156.142944)
		(end 23.139908 -154.94)
		(width 0.2794)
		(layer "F.Cu")
		(net "PD_TCA9548_SML1_U321_A2")
	)
	(segment
		(start 20.4216 -157.7848)
		(end 21.498052 -157.7848)
		(width 0.2794)
		(layer "F.Cu")
		(net "PD_TCA9548_SML1_U321_A2")
	)
	(segment
		(start 19.8628 -159.898334)
		(end 19.8628 -158.3436)
		(width 0.2794)
		(layer "F.Cu")
		(net "PD_TCA9548_SML1_U321_A2")
	)
	(segment
		(start 21.498052 -157.7848)
		(end 23.139908 -156.142944)
		(width 0.2794)
		(layer "F.Cu")
		(net "PD_TCA9548_SML1_U321_A2")
	)
	(segment
		(start 20.614386 -160.485836)
		(end 20.5486 -160.42005)
		(width 0.2794)
		(layer "F.Cu")
		(net "PD_TCA9548_SML1_U321_A2")
	)
	(segment
		(start 20.5232 -162.54095)
		(end 20.614386 -162.449764)
		(width 0.2794)
		(layer "F.Cu")
		(net "PD_TCA9548_SML1_U321_A2")
	)
	(segment
		(start 20.384516 -160.42005)
		(end 19.8628 -159.898334)
		(width 0.2794)
		(layer "F.Cu")
		(net "PD_TCA9548_SML1_U321_A2")
	)
	(segment
		(start 20.5486 -160.42005)
		(end 20.384516 -160.42005)
		(width 0.2794)
		(layer "F.Cu")
		(net "PD_TCA9548_SML1_U321_A2")
	)
	(segment
		(start 19.8628 -158.3436)
		(end 20.4216 -157.7848)
		(width 0.2794)
		(layer "F.Cu")
		(net "PD_TCA9548_SML1_U321_A2")
	)
	(via
		(at 20.4216 -157.7848)
		(size 0.762)
		(drill 0.381)
		(layers "F.Cu" "B.Cu")
		(net "PD_TCA9548_SML1_U321_A2")
	)
	(segment
		(start 22.479 -206.64805)
		(end 24.36368 -206.64805)
		(width 0.2794)
		(layer "F.Cu")
		(net "FAN_1_PWM")
	)
	(segment
		(start 22.4536 -207.81264)
		(end 22.4536 -206.67345)
		(width 0.2794)
		(layer "F.Cu")
		(net "FAN_1_PWM")
	)
	(segment
		(start 22.479 -207.83804)
		(end 22.4536 -207.81264)
		(width 0.2794)
		(layer "F.Cu")
		(net "FAN_1_PWM")
	)
	(segment
		(start 25.243282 -206.64805)
		(end 30.226 -201.665332)
		(width 0.2794)
		(layer "F.Cu")
		(net "FAN_1_PWM")
	)
	(segment
		(start 30.226 -200.279)
		(end 30.947614 -199.557386)
		(width 0.2794)
		(layer "F.Cu")
		(net "FAN_1_PWM")
	)
	(segment
		(start 24.36368 -206.64805)
		(end 25.243282 -206.64805)
		(width 0.2794)
		(layer "F.Cu")
		(net "FAN_1_PWM")
	)
	(segment
		(start 22.4536 -206.67345)
		(end 22.479 -206.64805)
		(width 0.2794)
		(layer "F.Cu")
		(net "FAN_1_PWM")
	)
	(segment
		(start 30.226 -201.665332)
		(end 30.226 -200.279)
		(width 0.2794)
		(layer "F.Cu")
		(net "FAN_1_PWM")
	)
	(segment
		(start 38.24605 -132.588)
		(end 38.24605 -133.223)
		(width 0.2794)
		(layer "F.Cu")
		(net "FAN_1_PWM")
	)
	(segment
		(start 30.947614 -199.557386)
		(end 30.947614 -197.095618)
		(width 0.2794)
		(layer "F.Cu")
		(net "FAN_1_PWM")
	)
	(via
		(at 38.24605 -133.223)
		(size 0.508)
		(drill 0.254)
		(layers "F.Cu" "B.Cu")
		(net "FAN_1_PWM")
	)
	(via
		(at 24.36368 -206.64805)
		(size 0.762)
		(drill 0.381)
		(layers "F.Cu" "B.Cu")
		(net "FAN_1_PWM")
	)
	(via
		(at 30.947614 -197.095618)
		(size 0.508)
		(drill 0.254)
		(layers "F.Cu" "B.Cu")
		(net "FAN_1_PWM")
	)
	(segment
		(start 46.4566 -143.903446)
		(end 40.582596 -138.029442)
		(width 0.2286)
		(layer "In2.Cu")
		(net "FAN_1_PWM")
	)
	(segment
		(start 40.582596 -138.029442)
		(end 40.582596 -135.559546)
		(width 0.2286)
		(layer "In2.Cu")
		(net "FAN_1_PWM")
	)
	(segment
		(start 39.243 -166.963344)
		(end 46.4566 -159.749744)
		(width 0.2286)
		(layer "In2.Cu")
		(net "FAN_1_PWM")
	)
	(segment
		(start 46.4566 -159.749744)
		(end 46.4566 -143.903446)
		(width 0.2286)
		(layer "In2.Cu")
		(net "FAN_1_PWM")
	)
	(segment
		(start 40.582596 -135.559546)
		(end 38.24605 -133.223)
		(width 0.2286)
		(layer "In2.Cu")
		(net "FAN_1_PWM")
	)
	(segment
		(start 30.947614 -197.095618)
		(end 30.947614 -196.279516)
		(width 0.2286)
		(layer "In2.Cu")
		(net "FAN_1_PWM")
	)
	(segment
		(start 39.243 -187.98413)
		(end 39.243 -166.963344)
		(width 0.2286)
		(layer "In2.Cu")
		(net "FAN_1_PWM")
	)
	(segment
		(start 30.947614 -196.279516)
		(end 39.243 -187.98413)
		(width 0.2286)
		(layer "In2.Cu")
		(net "FAN_1_PWM")
	)
	(segment
		(start 17.399254 -170.815)
		(end 17.50695 -170.815)
		(width 0.2794)
		(layer "F.Cu")
		(net "FAN_5_PRESENT_N")
	)
	(segment
		(start 12.93495 -170.815)
		(end 11.9253 -170.815)
		(width 0.2794)
		(layer "F.Cu")
		(net "FAN_5_PRESENT_N")
	)
	(segment
		(start 13.456158 -171.4881)
		(end 14.54785 -171.4881)
		(width 0.2794)
		(layer "F.Cu")
		(net "FAN_5_PRESENT_N")
	)
	(segment
		(start 15.742158 -171.4881)
		(end 16.726154 -171.4881)
		(width 0.2794)
		(layer "F.Cu")
		(net "FAN_5_PRESENT_N")
	)
	(segment
		(start 10.967974 -170.815)
		(end 10.85596 -170.702986)
		(width 0.2794)
		(layer "F.Cu")
		(net "FAN_5_PRESENT_N")
	)
	(segment
		(start 15.22095 -170.966892)
		(end 15.742158 -171.4881)
		(width 0.2794)
		(layer "F.Cu")
		(net "FAN_5_PRESENT_N")
	)
	(segment
		(start 11.9253 -170.815)
		(end 10.967974 -170.815)
		(width 0.2794)
		(layer "F.Cu")
		(net "FAN_5_PRESENT_N")
	)
	(segment
		(start 12.93495 -170.966892)
		(end 13.456158 -171.4881)
		(width 0.2794)
		(layer "F.Cu")
		(net "FAN_5_PRESENT_N")
	)
	(segment
		(start 16.726154 -171.4881)
		(end 17.399254 -170.815)
		(width 0.2794)
		(layer "F.Cu")
		(net "FAN_5_PRESENT_N")
	)
	(segment
		(start 14.54785 -171.4881)
		(end 15.22095 -170.815)
		(width 0.2794)
		(layer "F.Cu")
		(net "FAN_5_PRESENT_N")
	)
	(segment
		(start 15.22095 -170.815)
		(end 15.22095 -170.966892)
		(width 0.2794)
		(layer "F.Cu")
		(net "FAN_5_PRESENT_N")
	)
	(segment
		(start 12.93495 -170.815)
		(end 12.93495 -170.966892)
		(width 0.2794)
		(layer "F.Cu")
		(net "FAN_5_PRESENT_N")
	)
	(via
		(at 11.9253 -170.815)
		(size 0.508)
		(drill 0.254)
		(layers "F.Cu" "B.Cu")
		(net "FAN_5_PRESENT_N")
	)
	(segment
		(start 42.581068 -173.283118)
		(end 41.28516 -173.283118)
		(width 0.2794)
		(layer "F.Cu")
		(net "FAN_2_OK_LED")
	)
	(segment
		(start 41.28516 -173.283118)
		(end 40.554148 -172.552106)
		(width 0.2794)
		(layer "F.Cu")
		(net "FAN_2_OK_LED")
	)
	(segment
		(start 40.554148 -172.552106)
		(end 39.243 -172.552106)
		(width 0.2794)
		(layer "F.Cu")
		(net "FAN_2_OK_LED")
	)
	(segment
		(start 42.581068 -173.283118)
		(end 43.16095 -173.863)
		(width 0.2794)
		(layer "F.Cu")
		(net "FAN_2_OK_LED")
	)
	(via
		(at 42.581068 -173.283118)
		(size 0.508)
		(drill 0.254)
		(layers "F.Cu" "B.Cu")
		(net "FAN_2_OK_LED")
	)
	(via
		(at 39.904162 -75.641962)
		(size 0.6604)
		(drill 0.3302)
		(layers "F.Cu" "B.Cu")
		(net "FAN_2_P5V")
	)
	(segment
		(start 40.616632 -76.93152)
		(end 39.931594 -75.65009)
		(width 0.1016)
		(layer "B.Cu")
		(net "FAN_2_P5V")
	)
	(segment
		(start 40.616632 -77.45476)
		(end 40.616632 -76.93152)
		(width 0.1016)
		(layer "B.Cu")
		(net "FAN_2_P5V")
	)
	(segment
		(start 39.73068 -75.46848)
		(end 39.73068 -74.362818)
		(width 0.2794)
		(layer "B.Cu")
		(net "FAN_2_P5V")
	)
	(segment
		(start 39.904162 -75.641962)
		(end 39.73068 -75.46848)
		(width 0.2794)
		(layer "B.Cu")
		(net "FAN_2_P5V")
	)
	(segment
		(start 39.931594 -75.65009)
		(end 39.904162 -75.641962)
		(width 0.1016)
		(layer "B.Cu")
		(net "FAN_2_P5V")
	)
	(segment
		(start 29.972 -188.341)
		(end 30.75305 -187.55995)
		(width 0.2794)
		(layer "F.Cu")
		(net "P52V_FAN_5_BUFF_EN")
	)
	(segment
		(start 32.746696 -189.484)
		(end 33.401 -189.484)
		(width 0.2794)
		(layer "F.Cu")
		(net "P52V_FAN_5_BUFF_EN")
	)
	(segment
		(start 27.83205 -187.452)
		(end 28.72105 -188.341)
		(width 0.2794)
		(layer "F.Cu")
		(net "P52V_FAN_5_BUFF_EN")
	)
	(segment
		(start 30.75305 -187.55995)
		(end 30.75305 -187.490354)
		(width 0.2794)
		(layer "F.Cu")
		(net "P52V_FAN_5_BUFF_EN")
	)
	(segment
		(start 30.75305 -187.490354)
		(end 32.746696 -189.484)
		(width 0.2794)
		(layer "F.Cu")
		(net "P52V_FAN_5_BUFF_EN")
	)
	(segment
		(start 28.72105 -188.341)
		(end 29.173678 -188.341)
		(width 0.2794)
		(layer "F.Cu")
		(net "P52V_FAN_5_BUFF_EN")
	)
	(segment
		(start 29.173678 -188.341)
		(end 29.972 -188.341)
		(width 0.2794)
		(layer "F.Cu")
		(net "P52V_FAN_5_BUFF_EN")
	)
	(segment
		(start 30.75305 -187.452)
		(end 30.75305 -187.490354)
		(width 0.2794)
		(layer "F.Cu")
		(net "P52V_FAN_5_BUFF_EN")
	)
	(via
		(at 29.173678 -188.341)
		(size 0.508)
		(drill 0.254)
		(layers "F.Cu" "B.Cu")
		(net "P52V_FAN_5_BUFF_EN")
	)
	(segment
		(start 31.69285 -120.84685)
		(end 35.46475 -120.84685)
		(width 0.2794)
		(layer "F.Cu")
		(net "FAN_2_PWM_OL")
	)
	(segment
		(start 27.23896 -117.489986)
		(end 30.068774 -120.3198)
		(width 0.2794)
		(layer "F.Cu")
		(net "FAN_2_PWM_OL")
	)
	(segment
		(start 35.46475 -120.84685)
		(end 36.746688 -119.564912)
		(width 0.2794)
		(layer "F.Cu")
		(net "FAN_2_PWM_OL")
	)
	(segment
		(start 36.746688 -119.564912)
		(end 37.06495 -119.564912)
		(width 0.2794)
		(layer "F.Cu")
		(net "FAN_2_PWM_OL")
	)
	(segment
		(start 30.068774 -120.3198)
		(end 31.0642 -120.3198)
		(width 0.2794)
		(layer "F.Cu")
		(net "FAN_2_PWM_OL")
	)
	(segment
		(start 31.0642 -120.3198)
		(end 31.115 -120.269)
		(width 0.2794)
		(layer "F.Cu")
		(net "FAN_2_PWM_OL")
	)
	(segment
		(start 31.115 -120.269)
		(end 31.69285 -120.84685)
		(width 0.2794)
		(layer "F.Cu")
		(net "FAN_2_PWM_OL")
	)
	(via
		(at 31.115 -120.269)
		(size 0.762)
		(drill 0.381)
		(layers "F.Cu" "B.Cu")
		(net "FAN_2_PWM_OL")
	)
	(segment
		(start 12.93495 -169.442892)
		(end 13.456158 -169.9641)
		(width 0.2794)
		(layer "F.Cu")
		(net "FAN_4_PRESENT_N")
	)
	(segment
		(start 10.967974 -169.291)
		(end 10.85596 -169.403014)
		(width 0.2794)
		(layer "F.Cu")
		(net "FAN_4_PRESENT_N")
	)
	(segment
		(start 11.9253 -169.291)
		(end 10.967974 -169.291)
		(width 0.2794)
		(layer "F.Cu")
		(net "FAN_4_PRESENT_N")
	)
	(segment
		(start 15.742158 -169.9641)
		(end 16.83385 -169.9641)
		(width 0.2794)
		(layer "F.Cu")
		(net "FAN_4_PRESENT_N")
	)
	(segment
		(start 14.54785 -169.9641)
		(end 15.22095 -169.291)
		(width 0.2794)
		(layer "F.Cu")
		(net "FAN_4_PRESENT_N")
	)
	(segment
		(start 13.456158 -169.9641)
		(end 14.54785 -169.9641)
		(width 0.2794)
		(layer "F.Cu")
		(net "FAN_4_PRESENT_N")
	)
	(segment
		(start 15.22095 -169.291)
		(end 15.22095 -169.442892)
		(width 0.2794)
		(layer "F.Cu")
		(net "FAN_4_PRESENT_N")
	)
	(segment
		(start 15.22095 -169.442892)
		(end 15.742158 -169.9641)
		(width 0.2794)
		(layer "F.Cu")
		(net "FAN_4_PRESENT_N")
	)
	(segment
		(start 12.93495 -169.291)
		(end 12.93495 -169.442892)
		(width 0.2794)
		(layer "F.Cu")
		(net "FAN_4_PRESENT_N")
	)
	(segment
		(start 12.93495 -169.291)
		(end 11.9253 -169.291)
		(width 0.2794)
		(layer "F.Cu")
		(net "FAN_4_PRESENT_N")
	)
	(segment
		(start 16.83385 -169.9641)
		(end 17.50695 -169.291)
		(width 0.2794)
		(layer "F.Cu")
		(net "FAN_4_PRESENT_N")
	)
	(via
		(at 11.9253 -169.291)
		(size 0.508)
		(drill 0.254)
		(layers "F.Cu" "B.Cu")
		(net "FAN_4_PRESENT_N")
	)
	(segment
		(start 33.40735 -176.91989)
		(end 34.98215 -176.91989)
		(width 0.2794)
		(layer "F.Cu")
		(net "FAN_4_OK_LED")
	)
	(segment
		(start 33.12795 -176.403)
		(end 33.12795 -176.64049)
		(width 0.2794)
		(layer "F.Cu")
		(net "FAN_4_OK_LED")
	)
	(segment
		(start 34.98215 -176.91989)
		(end 35.3949 -176.50714)
		(width 0.2794)
		(layer "F.Cu")
		(net "FAN_4_OK_LED")
	)
	(segment
		(start 35.3949 -176.50714)
		(end 35.3949 -175.60036)
		(width 0.2794)
		(layer "F.Cu")
		(net "FAN_4_OK_LED")
	)
	(segment
		(start 34.94659 -175.15205)
		(end 33.401 -175.15205)
		(width 0.2794)
		(layer "F.Cu")
		(net "FAN_4_OK_LED")
	)
	(segment
		(start 35.3949 -175.60036)
		(end 34.94659 -175.15205)
		(width 0.2794)
		(layer "F.Cu")
		(net "FAN_4_OK_LED")
	)
	(segment
		(start 33.12795 -176.64049)
		(end 33.40735 -176.91989)
		(width 0.2794)
		(layer "F.Cu")
		(net "FAN_4_OK_LED")
	)
	(via
		(at 35.3949 -176.50714)
		(size 0.762)
		(drill 0.381)
		(layers "F.Cu" "B.Cu")
		(net "FAN_4_OK_LED")
	)
	(via
		(at 45.466 -75.819)
		(size 0.6604)
		(drill 0.3302)
		(layers "F.Cu" "B.Cu")
		(net "FAN_2_IMON")
	)
	(segment
		(start 46.482 -74.371962)
		(end 46.460918 -74.371962)
		(width 0.2794)
		(layer "B.Cu")
		(net "FAN_2_IMON")
	)
	(segment
		(start 44.815506 -76.088494)
		(end 44.196 -76.708)
		(width 0.2794)
		(layer "B.Cu")
		(net "FAN_2_IMON")
	)
	(segment
		(start 44.106592 -76.708)
		(end 43.816778 -76.997814)
		(width 0.1016)
		(layer "B.Cu")
		(net "FAN_2_IMON")
	)
	(segment
		(start 46.043342 -75.241658)
		(end 45.466 -75.819)
		(width 0.2794)
		(layer "B.Cu")
		(net "FAN_2_IMON")
	)
	(segment
		(start 44.196 -76.708)
		(end 44.106592 -76.708)
		(width 0.2794)
		(layer "B.Cu")
		(net "FAN_2_IMON")
	)
	(segment
		(start 46.043342 -74.789538)
		(end 46.043342 -75.241658)
		(width 0.2794)
		(layer "B.Cu")
		(net "FAN_2_IMON")
	)
	(segment
		(start 43.816778 -76.997814)
		(end 43.816778 -77.45476)
		(width 0.1016)
		(layer "B.Cu")
		(net "FAN_2_IMON")
	)
	(segment
		(start 45.466 -75.819)
		(end 44.815506 -76.088494)
		(width 0.2794)
		(layer "B.Cu")
		(net "FAN_2_IMON")
	)
	(segment
		(start 46.460918 -74.371962)
		(end 46.043342 -74.789538)
		(width 0.2794)
		(layer "B.Cu")
		(net "FAN_2_IMON")
	)
	(segment
		(start 31.839408 -190.316358)
		(end 30.75305 -189.23)
		(width 0.2794)
		(layer "F.Cu")
		(net "P52V_FAN_4_BUFF_EN")
	)
	(segment
		(start 30.75305 -189.303406)
		(end 29.937456 -190.119)
		(width 0.2794)
		(layer "F.Cu")
		(net "P52V_FAN_4_BUFF_EN")
	)
	(segment
		(start 28.955746 -190.119)
		(end 28.066746 -189.23)
		(width 0.2794)
		(layer "F.Cu")
		(net "P52V_FAN_4_BUFF_EN")
	)
	(segment
		(start 33.401 -190.783972)
		(end 32.307022 -190.783972)
		(width 0.2794)
		(layer "F.Cu")
		(net "P52V_FAN_4_BUFF_EN")
	)
	(segment
		(start 30.75305 -189.23)
		(end 30.75305 -189.303406)
		(width 0.2794)
		(layer "F.Cu")
		(net "P52V_FAN_4_BUFF_EN")
	)
	(segment
		(start 32.307022 -190.783972)
		(end 31.839408 -190.316358)
		(width 0.2794)
		(layer "F.Cu")
		(net "P52V_FAN_4_BUFF_EN")
	)
	(segment
		(start 28.066746 -189.23)
		(end 27.83205 -189.23)
		(width 0.2794)
		(layer "F.Cu")
		(net "P52V_FAN_4_BUFF_EN")
	)
	(segment
		(start 29.937456 -190.119)
		(end 28.955746 -190.119)
		(width 0.2794)
		(layer "F.Cu")
		(net "P52V_FAN_4_BUFF_EN")
	)
	(via
		(at 31.839408 -190.316358)
		(size 0.508)
		(drill 0.254)
		(layers "F.Cu" "B.Cu")
		(net "P52V_FAN_4_BUFF_EN")
	)
	(segment
		(start 29.85135 -171.577)
		(end 29.35605 -171.577)
		(width 0.2794)
		(layer "F.Cu")
		(net "FAN_7_OK_LED")
	)
	(segment
		(start 30.17647 -171.25188)
		(end 29.85135 -171.577)
		(width 0.2794)
		(layer "F.Cu")
		(net "FAN_7_OK_LED")
	)
	(segment
		(start 33.401 -171.25188)
		(end 31.70428 -171.25188)
		(width 0.2794)
		(layer "F.Cu")
		(net "FAN_7_OK_LED")
	)
	(segment
		(start 31.70428 -171.25188)
		(end 30.17647 -171.25188)
		(width 0.2794)
		(layer "F.Cu")
		(net "FAN_7_OK_LED")
	)
	(via
		(at 31.70428 -171.25188)
		(size 0.762)
		(drill 0.381)
		(layers "F.Cu" "B.Cu")
		(net "FAN_7_OK_LED")
	)
	(segment
		(start 41.348152 -71.882762)
		(end 40.926512 -71.882762)
		(width 0.2794)
		(layer "F.Cu")
		(net "FAN_2_FAULT_R")
	)
	(segment
		(start 40.926512 -72.911462)
		(end 40.926512 -71.882762)
		(width 0.2794)
		(layer "F.Cu")
		(net "FAN_2_FAULT_R")
	)
	(segment
		(start 42.418 -73.25995)
		(end 41.616122 -72.458072)
		(width 0.2794)
		(layer "F.Cu")
		(net "FAN_2_FAULT_R")
	)
	(segment
		(start 41.16705 -73.152)
		(end 40.926512 -72.911462)
		(width 0.2794)
		(layer "F.Cu")
		(net "FAN_2_FAULT_R")
	)
	(segment
		(start 41.616122 -72.458072)
		(end 41.616122 -72.150732)
		(width 0.2794)
		(layer "F.Cu")
		(net "FAN_2_FAULT_R")
	)
	(segment
		(start 41.616122 -72.150732)
		(end 41.348152 -71.882762)
		(width 0.2794)
		(layer "F.Cu")
		(net "FAN_2_FAULT_R")
	)
	(via
		(at 40.926512 -71.882762)
		(size 0.762)
		(drill 0.381)
		(layers "F.Cu" "B.Cu")
		(net "FAN_2_FAULT_R")
	)
	(segment
		(start 30.353 -251.968)
		(end 27.559 -254.762)
		(width 0.2794)
		(layer "F.Cu")
		(net "P52V_FAN_7_BUFF_EN_R")
	)
	(segment
		(start 15.4051 -254.762)
		(end 14.2621 -255.905)
		(width 0.2794)
		(layer "F.Cu")
		(net "P52V_FAN_7_BUFF_EN_R")
	)
	(segment
		(start 46.84395 -186.182)
		(end 46.84395 -187.452)
		(width 0.2794)
		(layer "F.Cu")
		(net "P52V_FAN_7_BUFF_EN_R")
	)
	(segment
		(start 27.559 -254.762)
		(end 15.4051 -254.762)
		(width 0.2794)
		(layer "F.Cu")
		(net "P52V_FAN_7_BUFF_EN_R")
	)
	(segment
		(start 45.48505 -186.182)
		(end 46.84395 -186.182)
		(width 0.2794)
		(layer "F.Cu")
		(net "P52V_FAN_7_BUFF_EN_R")
	)
	(via
		(at 14.2621 -255.905)
		(size 0.508)
		(drill 0.254)
		(layers "F.Cu" "B.Cu")
		(net "P52V_FAN_7_BUFF_EN_R")
	)
	(via
		(at 46.84395 -187.452)
		(size 0.762)
		(drill 0.254)
		(layers "F.Cu" "B.Cu")
		(net "P52V_FAN_7_BUFF_EN_R")
	)
	(via
		(at 30.353 -251.968)
		(size 0.508)
		(drill 0.254)
		(layers "F.Cu" "B.Cu")
		(net "P52V_FAN_7_BUFF_EN_R")
	)
	(segment
		(start 13.2969 -255.905)
		(end 14.2621 -255.905)
		(width 0.2794)
		(layer "B.Cu")
		(net "P52V_FAN_7_BUFF_EN_R")
	)
	(segment
		(start 33.829498 -241.688366)
		(end 33.829498 -217.705686)
		(width 0.2286)
		(layer "In2.Cu")
		(net "P52V_FAN_7_BUFF_EN_R")
	)
	(segment
		(start 30.899862 -248.76125)
		(end 33.829498 -241.688366)
		(width 0.2286)
		(layer "In2.Cu")
		(net "P52V_FAN_7_BUFF_EN_R")
	)
	(segment
		(start 40.474646 -211.060538)
		(end 40.474646 -196.395594)
		(width 0.2286)
		(layer "In2.Cu")
		(net "P52V_FAN_7_BUFF_EN_R")
	)
	(segment
		(start 33.829498 -217.705686)
		(end 40.474646 -211.060538)
		(width 0.2286)
		(layer "In2.Cu")
		(net "P52V_FAN_7_BUFF_EN_R")
	)
	(segment
		(start 30.353 -249.308112)
		(end 30.899862 -248.76125)
		(width 0.2286)
		(layer "In2.Cu")
		(net "P52V_FAN_7_BUFF_EN_R")
	)
	(segment
		(start 40.474646 -196.395594)
		(end 46.84395 -190.02629)
		(width 0.2286)
		(layer "In2.Cu")
		(net "P52V_FAN_7_BUFF_EN_R")
	)
	(segment
		(start 46.84395 -190.02629)
		(end 46.84395 -187.452)
		(width 0.2286)
		(layer "In2.Cu")
		(net "P52V_FAN_7_BUFF_EN_R")
	)
	(segment
		(start 30.353 -251.968)
		(end 30.353 -249.308112)
		(width 0.2286)
		(layer "In2.Cu")
		(net "P52V_FAN_7_BUFF_EN_R")
	)
	(segment
		(start 22.225 -21.1582)
		(end 24.428704 -21.1582)
		(width 0.2794)
		(layer "F.Cu")
		(net "P52V_FAN_EN_R")
	)
	(segment
		(start 24.428704 -21.1582)
		(end 24.87295 -20.713954)
		(width 0.2794)
		(layer "F.Cu")
		(net "P52V_FAN_EN_R")
	)
	(via
		(at 22.225 -21.1582)
		(size 0.508)
		(drill 0.254)
		(layers "F.Cu" "B.Cu")
		(net "P52V_FAN_EN_R")
	)
	(segment
		(start 20.6248 -16.3576)
		(end 20.6248 -15.5448)
		(width 0.2794)
		(layer "B.Cu")
		(net "P52V_FAN_EN_R")
	)
	(segment
		(start 20.8534 -15.3162)
		(end 21.8948 -15.3162)
		(width 0.2794)
		(layer "B.Cu")
		(net "P52V_FAN_EN_R")
	)
	(segment
		(start 22.225 -17.9578)
		(end 20.6248 -16.3576)
		(width 0.2794)
		(layer "B.Cu")
		(net "P52V_FAN_EN_R")
	)
	(segment
		(start 21.8948 -15.3162)
		(end 23.619968 -13.591032)
		(width 0.2794)
		(layer "B.Cu")
		(net "P52V_FAN_EN_R")
	)
	(segment
		(start 20.6248 -15.5448)
		(end 20.8534 -15.3162)
		(width 0.2794)
		(layer "B.Cu")
		(net "P52V_FAN_EN_R")
	)
	(segment
		(start 22.225 -21.1582)
		(end 22.225 -17.9578)
		(width 0.2794)
		(layer "B.Cu")
		(net "P52V_FAN_EN_R")
	)
	(segment
		(start 23.619968 -13.591032)
		(end 23.619968 -4.350004)
		(width 0.2794)
		(layer "B.Cu")
		(net "P52V_FAN_EN_R")
	)
	(segment
		(start 23.241 -27.79395)
		(end 23.128986 -27.681936)
		(width 0.2794)
		(layer "F.Cu")
		(net "FAN_3_PWM_BUF")
	)
	(segment
		(start 23.128986 -27.681936)
		(end 23.128986 -26.60396)
		(width 0.2794)
		(layer "F.Cu")
		(net "FAN_3_PWM_BUF")
	)
	(segment
		(start 23.75408 -26.60396)
		(end 23.98522 -26.37282)
		(width 0.2794)
		(layer "F.Cu")
		(net "FAN_3_PWM_BUF")
	)
	(segment
		(start 23.98522 -26.37282)
		(end 24.70404 -25.654)
		(width 0.2794)
		(layer "F.Cu")
		(net "FAN_3_PWM_BUF")
	)
	(segment
		(start 23.128986 -26.60396)
		(end 23.75408 -26.60396)
		(width 0.2794)
		(layer "F.Cu")
		(net "FAN_3_PWM_BUF")
	)
	(via
		(at 23.98522 -26.37282)
		(size 0.508)
		(drill 0.254)
		(layers "F.Cu" "B.Cu")
		(net "FAN_3_PWM_BUF")
	)
	(segment
		(start 42.204894 -169.799)
		(end 42.051986 -169.951908)
		(width 0.2794)
		(layer "F.Cu")
		(net "FAN_0_OK_LED")
	)
	(segment
		(start 43.16095 -169.799)
		(end 42.204894 -169.799)
		(width 0.2794)
		(layer "F.Cu")
		(net "FAN_0_OK_LED")
	)
	(segment
		(start 42.051986 -169.951908)
		(end 41.801288 -169.951908)
		(width 0.2794)
		(layer "F.Cu")
		(net "FAN_0_OK_LED")
	)
	(segment
		(start 39.243 -169.951908)
		(end 41.801288 -169.951908)
		(width 0.2794)
		(layer "F.Cu")
		(net "FAN_0_OK_LED")
	)
	(via
		(at 41.801288 -169.951908)
		(size 0.762)
		(drill 0.381)
		(layers "F.Cu" "B.Cu")
		(net "FAN_0_OK_LED")
	)
	(segment
		(start 44.45 -74.44105)
		(end 43.866816 -75.024234)
		(width 0.2794)
		(layer "B.Cu")
		(net "FAN_2_TIMER")
	)
	(segment
		(start 44.45 -74.371962)
		(end 44.45 -74.44105)
		(width 0.2794)
		(layer "B.Cu")
		(net "FAN_2_TIMER")
	)
	(segment
		(start 43.866816 -75.024234)
		(end 43.336972 -75.024234)
		(width 0.2794)
		(layer "B.Cu")
		(net "FAN_2_TIMER")
	)
	(segment
		(start 43.050206 -75.311)
		(end 42.727118 -75.634088)
		(width 0.1016)
		(layer "B.Cu")
		(net "FAN_2_TIMER")
	)
	(segment
		(start 42.616628 -76.18984)
		(end 42.616628 -77.45476)
		(width 0.1016)
		(layer "B.Cu")
		(net "FAN_2_TIMER")
	)
	(segment
		(start 43.336972 -75.024234)
		(end 43.050206 -75.311)
		(width 0.2794)
		(layer "B.Cu")
		(net "FAN_2_TIMER")
	)
	(segment
		(start 42.727118 -75.634088)
		(end 42.616628 -76.18984)
		(width 0.1016)
		(layer "B.Cu")
		(net "FAN_2_TIMER")
	)
	(segment
		(start 38.24605 -124.968)
		(end 38.24605 -125.603)
		(width 0.2794)
		(layer "F.Cu")
		(net "FAN_3_PWM")
	)
	(segment
		(start 22.4282 -23.39975)
		(end 22.45995 -23.368)
		(width 0.2794)
		(layer "F.Cu")
		(net "FAN_3_PWM")
	)
	(segment
		(start 22.479 -24.70404)
		(end 22.4282 -24.65324)
		(width 0.2794)
		(layer "F.Cu")
		(net "FAN_3_PWM")
	)
	(segment
		(start 22.45995 -23.368)
		(end 21.844 -23.368)
		(width 0.2794)
		(layer "F.Cu")
		(net "FAN_3_PWM")
	)
	(segment
		(start 22.4282 -24.65324)
		(end 22.4282 -23.39975)
		(width 0.2794)
		(layer "F.Cu")
		(net "FAN_3_PWM")
	)
	(via
		(at 21.844 -23.368)
		(size 0.508)
		(drill 0.254)
		(layers "F.Cu" "B.Cu")
		(net "FAN_3_PWM")
	)
	(via
		(at 38.24605 -125.603)
		(size 0.508)
		(drill 0.254)
		(layers "F.Cu" "B.Cu")
		(net "FAN_3_PWM")
	)
	(segment
		(start 25.554178 -112.378998)
		(end 29.63418 -116.459)
		(width 0.2286)
		(layer "In2.Cu")
		(net "FAN_3_PWM")
	)
	(segment
		(start 37.337746 -123.316746)
		(end 37.337746 -124.694696)
		(width 0.2286)
		(layer "In2.Cu")
		(net "FAN_3_PWM")
	)
	(segment
		(start 24.12238 -83.63204)
		(end 24.664416 -84.174076)
		(width 0.2286)
		(layer "In2.Cu")
		(net "FAN_3_PWM")
	)
	(segment
		(start 23.114 -27.686)
		(end 23.114 -34.417)
		(width 0.2286)
		(layer "In2.Cu")
		(net "FAN_3_PWM")
	)
	(segment
		(start 19.621754 -51.880008)
		(end 24.12238 -62.761368)
		(width 0.2286)
		(layer "In2.Cu")
		(net "FAN_3_PWM")
	)
	(segment
		(start 33.401 -119.38)
		(end 37.337746 -123.316746)
		(width 0.2286)
		(layer "In2.Cu")
		(net "FAN_3_PWM")
	)
	(segment
		(start 32.4612 -116.459)
		(end 33.401 -117.3988)
		(width 0.2286)
		(layer "In2.Cu")
		(net "FAN_3_PWM")
	)
	(segment
		(start 37.337746 -124.694696)
		(end 38.24605 -125.603)
		(width 0.2286)
		(layer "In2.Cu")
		(net "FAN_3_PWM")
	)
	(segment
		(start 23.114 -34.417)
		(end 19.621754 -37.909246)
		(width 0.2286)
		(layer "In2.Cu")
		(net "FAN_3_PWM")
	)
	(segment
		(start 25.554178 -101.22662)
		(end 25.554178 -112.378998)
		(width 0.2286)
		(layer "In2.Cu")
		(net "FAN_3_PWM")
	)
	(segment
		(start 29.63418 -116.459)
		(end 32.4612 -116.459)
		(width 0.2286)
		(layer "In2.Cu")
		(net "FAN_3_PWM")
	)
	(segment
		(start 24.12238 -62.761368)
		(end 24.12238 -83.63204)
		(width 0.2286)
		(layer "In2.Cu")
		(net "FAN_3_PWM")
	)
	(segment
		(start 19.621754 -37.909246)
		(end 19.621754 -51.880008)
		(width 0.2286)
		(layer "In2.Cu")
		(net "FAN_3_PWM")
	)
	(segment
		(start 21.844 -23.368)
		(end 21.844 -26.416)
		(width 0.2286)
		(layer "In2.Cu")
		(net "FAN_3_PWM")
	)
	(segment
		(start 33.401 -117.3988)
		(end 33.401 -119.38)
		(width 0.2286)
		(layer "In2.Cu")
		(net "FAN_3_PWM")
	)
	(segment
		(start 24.664416 -84.174076)
		(end 24.664416 -100.336858)
		(width 0.2286)
		(layer "In2.Cu")
		(net "FAN_3_PWM")
	)
	(segment
		(start 24.664416 -100.336858)
		(end 25.554178 -101.22662)
		(width 0.2286)
		(layer "In2.Cu")
		(net "FAN_3_PWM")
	)
	(segment
		(start 21.844 -26.416)
		(end 23.114 -27.686)
		(width 0.2286)
		(layer "In2.Cu")
		(net "FAN_3_PWM")
	)
	(segment
		(start 41.255188 -171.540678)
		(end 40.96639 -171.25188)
		(width 0.2794)
		(layer "F.Cu")
		(net "FAN_1_OK_LED")
	)
	(segment
		(start 40.96639 -171.25188)
		(end 39.243 -171.25188)
		(width 0.2794)
		(layer "F.Cu")
		(net "FAN_1_OK_LED")
	)
	(segment
		(start 42.590466 -171.260516)
		(end 42.310304 -171.540678)
		(width 0.2794)
		(layer "F.Cu")
		(net "FAN_1_OK_LED")
	)
	(segment
		(start 42.310304 -171.540678)
		(end 41.255188 -171.540678)
		(width 0.2794)
		(layer "F.Cu")
		(net "FAN_1_OK_LED")
	)
	(segment
		(start 42.590466 -171.260516)
		(end 43.16095 -171.831)
		(width 0.2794)
		(layer "F.Cu")
		(net "FAN_1_OK_LED")
	)
	(via
		(at 42.590466 -171.260516)
		(size 0.508)
		(drill 0.254)
		(layers "F.Cu" "B.Cu")
		(net "FAN_1_OK_LED")
	)
	(via
		(at 44.159932 -75.819)
		(size 0.762)
		(drill 0.254)
		(layers "F.Cu" "B.Cu")
		(net "FAN_2_SS")
	)
	(segment
		(start 44.159932 -75.819)
		(end 44.159932 -76.003912)
		(width 0.1016)
		(layer "B.Cu")
		(net "FAN_2_SS")
	)
	(segment
		(start 44.159932 -75.819)
		(end 45.466 -74.512932)
		(width 0.2794)
		(layer "B.Cu")
		(net "FAN_2_SS")
	)
	(segment
		(start 45.466 -74.512932)
		(end 45.466 -74.371962)
		(width 0.2794)
		(layer "B.Cu")
		(net "FAN_2_SS")
	)
	(segment
		(start 44.159932 -76.003912)
		(end 43.416728 -76.747116)
		(width 0.1016)
		(layer "B.Cu")
		(net "FAN_2_SS")
	)
	(segment
		(start 43.416728 -76.747116)
		(end 43.416728 -77.45476)
		(width 0.1016)
		(layer "B.Cu")
		(net "FAN_2_SS")
	)
	(segment
		(start 25.03805 -185.674)
		(end 27.03195 -185.674)
		(width 0.2794)
		(layer "F.Cu")
		(net "P52V_FAN_6_BUFF_EN_R")
	)
	(segment
		(start 23.692358 -186.436)
		(end 24.33574 -186.436)
		(width 0.2794)
		(layer "F.Cu")
		(net "P52V_FAN_6_BUFF_EN_R")
	)
	(segment
		(start 19.024346 -191.6684)
		(end 22.95525 -187.737496)
		(width 0.2794)
		(layer "F.Cu")
		(net "P52V_FAN_6_BUFF_EN_R")
	)
	(segment
		(start 5.03428 -191.6684)
		(end 4.043426 -191.6684)
		(width 0.2794)
		(layer "F.Cu")
		(net "P52V_FAN_6_BUFF_EN_R")
	)
	(segment
		(start 25.03805 -185.73369)
		(end 25.03805 -185.674)
		(width 0.2794)
		(layer "F.Cu")
		(net "P52V_FAN_6_BUFF_EN_R")
	)
	(segment
		(start 22.95525 -187.737496)
		(end 22.95525 -187.173108)
		(width 0.2794)
		(layer "F.Cu")
		(net "P52V_FAN_6_BUFF_EN_R")
	)
	(segment
		(start 22.95525 -187.173108)
		(end 23.692358 -186.436)
		(width 0.2794)
		(layer "F.Cu")
		(net "P52V_FAN_6_BUFF_EN_R")
	)
	(segment
		(start 5.03428 -191.6684)
		(end 19.024346 -191.6684)
		(width 0.2794)
		(layer "F.Cu")
		(net "P52V_FAN_6_BUFF_EN_R")
	)
	(segment
		(start 4.043426 -191.6684)
		(end 3.256026 -190.881)
		(width 0.2794)
		(layer "F.Cu")
		(net "P52V_FAN_6_BUFF_EN_R")
	)
	(segment
		(start 24.33574 -186.436)
		(end 25.03805 -185.73369)
		(width 0.2794)
		(layer "F.Cu")
		(net "P52V_FAN_6_BUFF_EN_R")
	)
	(via
		(at 3.256026 -190.881)
		(size 0.508)
		(drill 0.254)
		(layers "F.Cu" "B.Cu")
		(net "P52V_FAN_6_BUFF_EN_R")
	)
	(via
		(at 6.020308 -252.034294)
		(size 0.508)
		(drill 0.254)
		(layers "F.Cu" "B.Cu")
		(net "P52V_FAN_6_BUFF_EN_R")
	)
	(via
		(at 5.03428 -191.6684)
		(size 0.762)
		(drill 0.381)
		(layers "F.Cu" "B.Cu")
		(net "P52V_FAN_6_BUFF_EN_R")
	)
	(segment
		(start 6.985508 -252.095)
		(end 6.081014 -252.095)
		(width 0.2794)
		(layer "B.Cu")
		(net "P52V_FAN_6_BUFF_EN_R")
	)
	(segment
		(start 6.081014 -252.095)
		(end 6.020308 -252.034294)
		(width 0.2794)
		(layer "B.Cu")
		(net "P52V_FAN_6_BUFF_EN_R")
	)
	(segment
		(start 6.020308 -251.003308)
		(end 6.020308 -252.034294)
		(width 0.2286)
		(layer "In2.Cu")
		(net "P52V_FAN_6_BUFF_EN_R")
	)
	(segment
		(start 2.4511 -247.4341)
		(end 6.020308 -251.003308)
		(width 0.2286)
		(layer "In2.Cu")
		(net "P52V_FAN_6_BUFF_EN_R")
	)
	(segment
		(start 3.256026 -190.881)
		(end 2.4511 -191.685926)
		(width 0.2286)
		(layer "In2.Cu")
		(net "P52V_FAN_6_BUFF_EN_R")
	)
	(segment
		(start 2.4511 -191.685926)
		(end 2.4511 -247.4341)
		(width 0.2286)
		(layer "In2.Cu")
		(net "P52V_FAN_6_BUFF_EN_R")
	)
	(segment
		(start 23.128986 -118.613936)
		(end 23.128986 -117.53596)
		(width 0.2794)
		(layer "F.Cu")
		(net "FAN_2_PWM_BUF")
	)
	(segment
		(start 23.241 -118.72595)
		(end 23.128986 -118.613936)
		(width 0.2794)
		(layer "F.Cu")
		(net "FAN_2_PWM_BUF")
	)
	(segment
		(start 24.64308 -117.53596)
		(end 25.33904 -116.84)
		(width 0.2794)
		(layer "F.Cu")
		(net "FAN_2_PWM_BUF")
	)
	(segment
		(start 23.128986 -117.53596)
		(end 24.13 -117.53596)
		(width 0.2794)
		(layer "F.Cu")
		(net "FAN_2_PWM_BUF")
	)
	(segment
		(start 24.13 -117.53596)
		(end 24.64308 -117.53596)
		(width 0.2794)
		(layer "F.Cu")
		(net "FAN_2_PWM_BUF")
	)
	(via
		(at 24.13 -117.53596)
		(size 0.508)
		(drill 0.254)
		(layers "F.Cu" "B.Cu")
		(net "FAN_2_PWM_BUF")
	)
	(segment
		(start 43.063414 -177.008536)
		(end 40.973248 -177.008536)
		(width 0.2794)
		(layer "F.Cu")
		(net "FAN_3_FAIL_LED")
	)
	(segment
		(start 39.945056 -174.502064)
		(end 40.973248 -175.530256)
		(width 0.2794)
		(layer "F.Cu")
		(net "FAN_3_FAIL_LED")
	)
	(segment
		(start 39.243 -174.502064)
		(end 39.945056 -174.502064)
		(width 0.2794)
		(layer "F.Cu")
		(net "FAN_3_FAIL_LED")
	)
	(segment
		(start 40.973248 -175.530256)
		(end 40.973248 -177.008536)
		(width 0.2794)
		(layer "F.Cu")
		(net "FAN_3_FAIL_LED")
	)
	(segment
		(start 43.16095 -176.911)
		(end 43.063414 -177.008536)
		(width 0.2794)
		(layer "F.Cu")
		(net "FAN_3_FAIL_LED")
	)
	(via
		(at 40.973248 -177.008536)
		(size 0.762)
		(drill 0.381)
		(layers "F.Cu" "B.Cu")
		(net "FAN_3_FAIL_LED")
	)
	(segment
		(start 42.43324 -175.895)
		(end 42.178732 -175.895)
		(width 0.2794)
		(layer "F.Cu")
		(net "FAN_3_OK_LED")
	)
	(segment
		(start 43.16095 -175.895)
		(end 42.43324 -175.895)
		(width 0.2794)
		(layer "F.Cu")
		(net "FAN_3_OK_LED")
	)
	(segment
		(start 40.13581 -173.852078)
		(end 39.243 -173.852078)
		(width 0.2794)
		(layer "F.Cu")
		(net "FAN_3_OK_LED")
	)
	(segment
		(start 42.178732 -175.895)
		(end 40.13581 -173.852078)
		(width 0.2794)
		(layer "F.Cu")
		(net "FAN_3_OK_LED")
	)
	(via
		(at 42.43324 -175.895)
		(size 0.508)
		(drill 0.254)
		(layers "F.Cu" "B.Cu")
		(net "FAN_3_OK_LED")
	)
	(segment
		(start 24.427942 -188.214)
		(end 25.03805 -187.603892)
		(width 0.2794)
		(layer "F.Cu")
		(net "P52V_FAN_5_BUFF_EN_R")
	)
	(segment
		(start 9.398 -192.2526)
		(end 19.3294 -192.2526)
		(width 0.2794)
		(layer "F.Cu")
		(net "P52V_FAN_5_BUFF_EN_R")
	)
	(segment
		(start 23.368 -188.214)
		(end 24.427942 -188.214)
		(width 0.2794)
		(layer "F.Cu")
		(net "P52V_FAN_5_BUFF_EN_R")
	)
	(segment
		(start 27.03195 -187.452)
		(end 25.03805 -187.452)
		(width 0.2794)
		(layer "F.Cu")
		(net "P52V_FAN_5_BUFF_EN_R")
	)
	(segment
		(start 19.3294 -192.2526)
		(end 23.368 -188.214)
		(width 0.2794)
		(layer "F.Cu")
		(net "P52V_FAN_5_BUFF_EN_R")
	)
	(segment
		(start 25.03805 -187.603892)
		(end 25.03805 -187.452)
		(width 0.2794)
		(layer "F.Cu")
		(net "P52V_FAN_5_BUFF_EN_R")
	)
	(via
		(at 14.1351 -71.304912)
		(size 0.508)
		(drill 0.254)
		(layers "F.Cu" "B.Cu")
		(net "P52V_FAN_5_BUFF_EN_R")
	)
	(via
		(at 2.9972 -72.136)
		(size 0.762)
		(drill 0.254)
		(layers "F.Cu" "B.Cu")
		(net "P52V_FAN_5_BUFF_EN_R")
	)
	(via
		(at 9.398 -192.2526)
		(size 0.508)
		(drill 0.254)
		(layers "F.Cu" "B.Cu")
		(net "P52V_FAN_5_BUFF_EN_R")
	)
	(segment
		(start 13.1699 -71.304912)
		(end 14.1351 -71.304912)
		(width 0.2794)
		(layer "B.Cu")
		(net "P52V_FAN_5_BUFF_EN_R")
	)
	(segment
		(start 10.668 -181.467252)
		(end 10.668 -175.641)
		(width 0.2286)
		(layer "In2.Cu")
		(net "P52V_FAN_5_BUFF_EN_R")
	)
	(segment
		(start 10.929112 -68.699888)
		(end 11.530076 -68.699888)
		(width 0.2286)
		(layer "In2.Cu")
		(net "P52V_FAN_5_BUFF_EN_R")
	)
	(segment
		(start 3.302 -134.28472)
		(end 4.191 -133.39572)
		(width 0.2286)
		(layer "In2.Cu")
		(net "P52V_FAN_5_BUFF_EN_R")
	)
	(segment
		(start 9.3726 -167.171624)
		(end 6.825234 -164.624258)
		(width 0.2286)
		(layer "In2.Cu")
		(net "P52V_FAN_5_BUFF_EN_R")
	)
	(segment
		(start 2.9972 -72.136)
		(end 4.47929 -70.65391)
		(width 0.2286)
		(layer "In2.Cu")
		(net "P52V_FAN_5_BUFF_EN_R")
	)
	(segment
		(start 9.3726 -174.3456)
		(end 9.3726 -167.171624)
		(width 0.2286)
		(layer "In2.Cu")
		(net "P52V_FAN_5_BUFF_EN_R")
	)
	(segment
		(start 8.97509 -70.65391)
		(end 10.929112 -68.699888)
		(width 0.2286)
		(layer "In2.Cu")
		(net "P52V_FAN_5_BUFF_EN_R")
	)
	(segment
		(start 6.825234 -163.53028)
		(end 3.302 -160.007046)
		(width 0.2286)
		(layer "In2.Cu")
		(net "P52V_FAN_5_BUFF_EN_R")
	)
	(segment
		(start 2.9972 -126.02972)
		(end 2.9972 -72.136)
		(width 0.2286)
		(layer "In2.Cu")
		(net "P52V_FAN_5_BUFF_EN_R")
	)
	(segment
		(start 9.398 -182.737252)
		(end 10.668 -181.467252)
		(width 0.2286)
		(layer "In2.Cu")
		(net "P52V_FAN_5_BUFF_EN_R")
	)
	(segment
		(start 6.825234 -164.624258)
		(end 6.825234 -163.53028)
		(width 0.2286)
		(layer "In2.Cu")
		(net "P52V_FAN_5_BUFF_EN_R")
	)
	(segment
		(start 11.530076 -68.699888)
		(end 14.1351 -71.304912)
		(width 0.2286)
		(layer "In2.Cu")
		(net "P52V_FAN_5_BUFF_EN_R")
	)
	(segment
		(start 10.668 -175.641)
		(end 9.3726 -174.3456)
		(width 0.2286)
		(layer "In2.Cu")
		(net "P52V_FAN_5_BUFF_EN_R")
	)
	(segment
		(start 9.398 -192.2526)
		(end 9.398 -182.737252)
		(width 0.2286)
		(layer "In2.Cu")
		(net "P52V_FAN_5_BUFF_EN_R")
	)
	(segment
		(start 4.191 -133.39572)
		(end 4.191 -127.22352)
		(width 0.2286)
		(layer "In2.Cu")
		(net "P52V_FAN_5_BUFF_EN_R")
	)
	(segment
		(start 3.302 -160.007046)
		(end 3.302 -134.28472)
		(width 0.2286)
		(layer "In2.Cu")
		(net "P52V_FAN_5_BUFF_EN_R")
	)
	(segment
		(start 4.47929 -70.65391)
		(end 8.97509 -70.65391)
		(width 0.2286)
		(layer "In2.Cu")
		(net "P52V_FAN_5_BUFF_EN_R")
	)
	(segment
		(start 4.191 -127.22352)
		(end 2.9972 -126.02972)
		(width 0.2286)
		(layer "In2.Cu")
		(net "P52V_FAN_5_BUFF_EN_R")
	)
	(segment
		(start 32.743648 -170.601894)
		(end 32.682434 -170.54068)
		(width 0.2794)
		(layer "F.Cu")
		(net "FAN_7_FAIL_LED")
	)
	(segment
		(start 33.401 -170.601894)
		(end 32.743648 -170.601894)
		(width 0.2794)
		(layer "F.Cu")
		(net "FAN_7_FAIL_LED")
	)
	(segment
		(start 30.5816 -170.38828)
		(end 30.40888 -170.561)
		(width 0.2794)
		(layer "F.Cu")
		(net "FAN_7_FAIL_LED")
	)
	(segment
		(start 30.40888 -170.561)
		(end 29.35605 -170.561)
		(width 0.2794)
		(layer "F.Cu")
		(net "FAN_7_FAIL_LED")
	)
	(segment
		(start 30.734 -170.54068)
		(end 30.5816 -170.38828)
		(width 0.2794)
		(layer "F.Cu")
		(net "FAN_7_FAIL_LED")
	)
	(segment
		(start 32.682434 -170.54068)
		(end 30.734 -170.54068)
		(width 0.2794)
		(layer "F.Cu")
		(net "FAN_7_FAIL_LED")
	)
	(via
		(at 30.5816 -170.38828)
		(size 0.762)
		(drill 0.381)
		(layers "F.Cu" "B.Cu")
		(net "FAN_7_FAIL_LED")
	)
	(segment
		(start 34.12998 -205.399132)
		(end 30.947868 -205.399132)
		(width 0.2794)
		(layer "F.Cu")
		(net "FAN_1_PWM_IL")
	)
	(segment
		(start 29.382974 -205.486)
		(end 26.73096 -208.138014)
		(width 0.2794)
		(layer "F.Cu")
		(net "FAN_1_PWM_IL")
	)
	(segment
		(start 36.508182 -207.038956)
		(end 35.892232 -206.423006)
		(width 0.2794)
		(layer "F.Cu")
		(net "FAN_1_PWM_IL")
	)
	(segment
		(start 30.861 -205.486)
		(end 29.382974 -205.486)
		(width 0.2794)
		(layer "F.Cu")
		(net "FAN_1_PWM_IL")
	)
	(segment
		(start 35.153854 -206.423006)
		(end 34.12998 -205.399132)
		(width 0.2794)
		(layer "F.Cu")
		(net "FAN_1_PWM_IL")
	)
	(segment
		(start 35.892232 -206.423006)
		(end 35.153854 -206.423006)
		(width 0.2794)
		(layer "F.Cu")
		(net "FAN_1_PWM_IL")
	)
	(segment
		(start 36.93795 -207.038956)
		(end 36.508182 -207.038956)
		(width 0.2794)
		(layer "F.Cu")
		(net "FAN_1_PWM_IL")
	)
	(segment
		(start 30.947868 -205.399132)
		(end 30.861 -205.486)
		(width 0.2794)
		(layer "F.Cu")
		(net "FAN_1_PWM_IL")
	)
	(via
		(at 30.861 -205.486)
		(size 0.762)
		(drill 0.381)
		(layers "F.Cu" "B.Cu")
		(net "FAN_1_PWM_IL")
	)
	(segment
		(start 42.13225 -170.8531)
		(end 41.463468 -170.8531)
		(width 0.2794)
		(layer "F.Cu")
		(net "FAN_0_FAIL_LED")
	)
	(segment
		(start 41.212262 -170.601894)
		(end 40.398954 -170.601894)
		(width 0.2794)
		(layer "F.Cu")
		(net "FAN_0_FAIL_LED")
	)
	(segment
		(start 42.383456 -170.601894)
		(end 42.13225 -170.8531)
		(width 0.2794)
		(layer "F.Cu")
		(net "FAN_0_FAIL_LED")
	)
	(segment
		(start 39.243 -170.601894)
		(end 40.398954 -170.601894)
		(width 0.2794)
		(layer "F.Cu")
		(net "FAN_0_FAIL_LED")
	)
	(segment
		(start 42.947844 -170.601894)
		(end 42.383456 -170.601894)
		(width 0.2794)
		(layer "F.Cu")
		(net "FAN_0_FAIL_LED")
	)
	(segment
		(start 41.463468 -170.8531)
		(end 41.212262 -170.601894)
		(width 0.2794)
		(layer "F.Cu")
		(net "FAN_0_FAIL_LED")
	)
	(segment
		(start 43.16095 -170.815)
		(end 42.947844 -170.601894)
		(width 0.2794)
		(layer "F.Cu")
		(net "FAN_0_FAIL_LED")
	)
	(via
		(at 40.398954 -170.601894)
		(size 0.508)
		(drill 0.254)
		(layers "F.Cu" "B.Cu")
		(net "FAN_0_FAIL_LED")
	)
	(segment
		(start 25.03805 -189.381892)
		(end 25.03805 -189.23)
		(width 0.2794)
		(layer "F.Cu")
		(net "P52V_FAN_4_BUFF_EN_R")
	)
	(segment
		(start 22.352 -192.8368)
		(end 24.516842 -190.671958)
		(width 0.2794)
		(layer "F.Cu")
		(net "P52V_FAN_4_BUFF_EN_R")
	)
	(segment
		(start 8.636 -192.278)
		(end 9.1948 -192.8368)
		(width 0.2794)
		(layer "F.Cu")
		(net "P52V_FAN_4_BUFF_EN_R")
	)
	(segment
		(start 24.516842 -190.671958)
		(end 24.516842 -189.9031)
		(width 0.2794)
		(layer "F.Cu")
		(net "P52V_FAN_4_BUFF_EN_R")
	)
	(segment
		(start 27.03195 -189.23)
		(end 25.03805 -189.23)
		(width 0.2794)
		(layer "F.Cu")
		(net "P52V_FAN_4_BUFF_EN_R")
	)
	(segment
		(start 24.516842 -189.9031)
		(end 25.03805 -189.381892)
		(width 0.2794)
		(layer "F.Cu")
		(net "P52V_FAN_4_BUFF_EN_R")
	)
	(segment
		(start 9.1948 -192.8368)
		(end 22.352 -192.8368)
		(width 0.2794)
		(layer "F.Cu")
		(net "P52V_FAN_4_BUFF_EN_R")
	)
	(via
		(at 6.096 -70.104)
		(size 0.762)
		(drill 0.254)
		(layers "F.Cu" "B.Cu")
		(net "P52V_FAN_4_BUFF_EN_R")
	)
	(via
		(at 8.636 -192.278)
		(size 0.508)
		(drill 0.254)
		(layers "F.Cu" "B.Cu")
		(net "P52V_FAN_4_BUFF_EN_R")
	)
	(segment
		(start 6.096 -70.104)
		(end 6.096 -67.774312)
		(width 0.2794)
		(layer "B.Cu")
		(net "P52V_FAN_4_BUFF_EN_R")
	)
	(segment
		(start 6.096 -67.774312)
		(end 6.3754 -67.494912)
		(width 0.2794)
		(layer "B.Cu")
		(net "P52V_FAN_4_BUFF_EN_R")
	)
	(segment
		(start 6.3754 -67.494912)
		(end 6.985508 -67.494912)
		(width 0.2794)
		(layer "B.Cu")
		(net "P52V_FAN_4_BUFF_EN_R")
	)
	(segment
		(start 3.94462 -70.104)
		(end 6.096 -70.104)
		(width 0.2286)
		(layer "In2.Cu")
		(net "P52V_FAN_4_BUFF_EN_R")
	)
	(segment
		(start 2.667 -160.137094)
		(end 2.667 -134.03072)
		(width 0.2286)
		(layer "In2.Cu")
		(net "P52V_FAN_4_BUFF_EN_R")
	)
	(segment
		(start 6.223 -163.693094)
		(end 2.667 -160.137094)
		(width 0.2286)
		(layer "In2.Cu")
		(net "P52V_FAN_4_BUFF_EN_R")
	)
	(segment
		(start 8.636 -192.278)
		(end 8.636 -182.737252)
		(width 0.2286)
		(layer "In2.Cu")
		(net "P52V_FAN_4_BUFF_EN_R")
	)
	(segment
		(start 10.1346 -176.2506)
		(end 7.655306 -173.771306)
		(width 0.2286)
		(layer "In2.Cu")
		(net "P52V_FAN_4_BUFF_EN_R")
	)
	(segment
		(start 8.636 -182.737252)
		(end 10.1346 -181.238652)
		(width 0.2286)
		(layer "In2.Cu")
		(net "P52V_FAN_4_BUFF_EN_R")
	)
	(segment
		(start 3.6068 -127.50292)
		(end 2.4638 -126.35992)
		(width 0.2286)
		(layer "In2.Cu")
		(net "P52V_FAN_4_BUFF_EN_R")
	)
	(segment
		(start 2.4638 -71.58482)
		(end 3.94462 -70.104)
		(width 0.2286)
		(layer "In2.Cu")
		(net "P52V_FAN_4_BUFF_EN_R")
	)
	(segment
		(start 2.4638 -126.35992)
		(end 2.4638 -71.58482)
		(width 0.2286)
		(layer "In2.Cu")
		(net "P52V_FAN_4_BUFF_EN_R")
	)
	(segment
		(start 2.667 -134.03072)
		(end 3.6068 -133.09092)
		(width 0.2286)
		(layer "In2.Cu")
		(net "P52V_FAN_4_BUFF_EN_R")
	)
	(segment
		(start 7.655306 -166.786306)
		(end 6.223 -165.354)
		(width 0.2286)
		(layer "In2.Cu")
		(net "P52V_FAN_4_BUFF_EN_R")
	)
	(segment
		(start 3.6068 -133.09092)
		(end 3.6068 -127.50292)
		(width 0.2286)
		(layer "In2.Cu")
		(net "P52V_FAN_4_BUFF_EN_R")
	)
	(segment
		(start 6.223 -165.354)
		(end 6.223 -163.693094)
		(width 0.2286)
		(layer "In2.Cu")
		(net "P52V_FAN_4_BUFF_EN_R")
	)
	(segment
		(start 7.655306 -173.771306)
		(end 7.655306 -166.786306)
		(width 0.2286)
		(layer "In2.Cu")
		(net "P52V_FAN_4_BUFF_EN_R")
	)
	(segment
		(start 10.1346 -181.238652)
		(end 10.1346 -176.2506)
		(width 0.2286)
		(layer "In2.Cu")
		(net "P52V_FAN_4_BUFF_EN_R")
	)
	(segment
		(start 23.876 -209.73796)
		(end 23.128986 -209.73796)
		(width 0.2794)
		(layer "F.Cu")
		(net "FAN_1_PWM_BUF")
	)
	(segment
		(start 23.128986 -210.815936)
		(end 23.128986 -209.73796)
		(width 0.2794)
		(layer "F.Cu")
		(net "FAN_1_PWM_BUF")
	)
	(segment
		(start 24.55164 -209.73796)
		(end 23.876 -209.73796)
		(width 0.2794)
		(layer "F.Cu")
		(net "FAN_1_PWM_BUF")
	)
	(segment
		(start 23.241 -210.92795)
		(end 23.128986 -210.815936)
		(width 0.2794)
		(layer "F.Cu")
		(net "FAN_1_PWM_BUF")
	)
	(segment
		(start 24.83104 -209.45856)
		(end 24.55164 -209.73796)
		(width 0.2794)
		(layer "F.Cu")
		(net "FAN_1_PWM_BUF")
	)
	(segment
		(start 24.83104 -208.788)
		(end 24.83104 -209.45856)
		(width 0.2794)
		(layer "F.Cu")
		(net "FAN_1_PWM_BUF")
	)
	(via
		(at 23.876 -209.73796)
		(size 0.508)
		(drill 0.254)
		(layers "F.Cu" "B.Cu")
		(net "FAN_1_PWM_BUF")
	)
	(segment
		(start 30.225746 -173.609)
		(end 29.35605 -173.609)
		(width 0.2794)
		(layer "F.Cu")
		(net "FAN_6_OK_LED")
	)
	(segment
		(start 31.70682 -172.68698)
		(end 31.841694 -172.552106)
		(width 0.2794)
		(layer "F.Cu")
		(net "FAN_6_OK_LED")
	)
	(segment
		(start 31.70682 -172.68698)
		(end 31.147766 -172.68698)
		(width 0.2794)
		(layer "F.Cu")
		(net "FAN_6_OK_LED")
	)
	(segment
		(start 31.147766 -172.68698)
		(end 30.225746 -173.609)
		(width 0.2794)
		(layer "F.Cu")
		(net "FAN_6_OK_LED")
	)
	(segment
		(start 31.841694 -172.552106)
		(end 33.401 -172.552106)
		(width 0.2794)
		(layer "F.Cu")
		(net "FAN_6_OK_LED")
	)
	(via
		(at 31.70682 -172.68698)
		(size 0.762)
		(drill 0.381)
		(layers "F.Cu" "B.Cu")
		(net "FAN_6_OK_LED")
	)
	(segment
		(start 42.585132 -172.271182)
		(end 41.936162 -172.271182)
		(width 0.2794)
		(layer "F.Cu")
		(net "FAN_1_FAIL_LED")
	)
	(segment
		(start 41.151048 -172.271182)
		(end 41.936162 -172.271182)
		(width 0.2794)
		(layer "F.Cu")
		(net "FAN_1_FAIL_LED")
	)
	(segment
		(start 40.781986 -171.90212)
		(end 41.151048 -172.271182)
		(width 0.2794)
		(layer "F.Cu")
		(net "FAN_1_FAIL_LED")
	)
	(segment
		(start 43.16095 -172.847)
		(end 42.585132 -172.271182)
		(width 0.2794)
		(layer "F.Cu")
		(net "FAN_1_FAIL_LED")
	)
	(segment
		(start 39.243 -171.90212)
		(end 40.781986 -171.90212)
		(width 0.2794)
		(layer "F.Cu")
		(net "FAN_1_FAIL_LED")
	)
	(via
		(at 41.936162 -172.271182)
		(size 0.762)
		(drill 0.381)
		(layers "F.Cu" "B.Cu")
		(net "FAN_1_FAIL_LED")
	)
	(segment
		(start 45.48505 -179.324)
		(end 47.73295 -179.324)
		(width 0.2794)
		(layer "F.Cu")
		(net "P52V_FAN_3_BUFF_EN_R")
	)
	(segment
		(start 47.73295 -179.324)
		(end 47.73295 -178.054)
		(width 0.2794)
		(layer "F.Cu")
		(net "P52V_FAN_3_BUFF_EN_R")
	)
	(via
		(at 37.437822 -67.494912)
		(size 0.508)
		(drill 0.254)
		(layers "F.Cu" "B.Cu")
		(net "P52V_FAN_3_BUFF_EN_R")
	)
	(via
		(at 47.73295 -178.054)
		(size 0.762)
		(drill 0.254)
		(layers "F.Cu" "B.Cu")
		(net "P52V_FAN_3_BUFF_EN_R")
	)
	(segment
		(start 38.403022 -67.494912)
		(end 37.437822 -67.494912)
		(width 0.2794)
		(layer "B.Cu")
		(net "P52V_FAN_3_BUFF_EN_R")
	)
	(segment
		(start 42.922952 -66.3194)
		(end 40.577516 -68.664836)
		(width 0.2286)
		(layer "In2.Cu")
		(net "P52V_FAN_3_BUFF_EN_R")
	)
	(segment
		(start 38.607746 -68.664836)
		(end 37.437822 -67.494912)
		(width 0.2286)
		(layer "In2.Cu")
		(net "P52V_FAN_3_BUFF_EN_R")
	)
	(segment
		(start 40.577516 -68.664836)
		(end 38.607746 -68.664836)
		(width 0.2286)
		(layer "In2.Cu")
		(net "P52V_FAN_3_BUFF_EN_R")
	)
	(segment
		(start 47.73295 -178.054)
		(end 47.73295 -177.311304)
		(width 0.2286)
		(layer "In2.Cu")
		(net "P52V_FAN_3_BUFF_EN_R")
	)
	(segment
		(start 48.2092 -66.3194)
		(end 42.922952 -66.3194)
		(width 0.2286)
		(layer "In2.Cu")
		(net "P52V_FAN_3_BUFF_EN_R")
	)
	(segment
		(start 47.73295 -177.311304)
		(end 50.290476 -174.753778)
		(width 0.2286)
		(layer "In2.Cu")
		(net "P52V_FAN_3_BUFF_EN_R")
	)
	(segment
		(start 50.290476 -68.400676)
		(end 48.2092 -66.3194)
		(width 0.2286)
		(layer "In2.Cu")
		(net "P52V_FAN_3_BUFF_EN_R")
	)
	(segment
		(start 50.290476 -174.753778)
		(end 50.290476 -68.400676)
		(width 0.2286)
		(layer "In2.Cu")
		(net "P52V_FAN_3_BUFF_EN_R")
	)
	(segment
		(start 35.9283 -177.9397)
		(end 30.97276 -177.9397)
		(width 0.2794)
		(layer "F.Cu")
		(net "P52V_FAN_2_BUFF_EN_R")
	)
	(segment
		(start 39.354252 -166.385748)
		(end 37.79901 -167.94099)
		(width 0.2794)
		(layer "F.Cu")
		(net "P52V_FAN_2_BUFF_EN_R")
	)
	(segment
		(start 30.97276 -177.9397)
		(end 30.45206 -177.419)
		(width 0.2794)
		(layer "F.Cu")
		(net "P52V_FAN_2_BUFF_EN_R")
	)
	(segment
		(start 48.387254 -164.719)
		(end 43.378628 -164.719)
		(width 0.2794)
		(layer "F.Cu")
		(net "P52V_FAN_2_BUFF_EN_R")
	)
	(segment
		(start 37.79901 -167.94099)
		(end 37.79901 -176.06899)
		(width 0.2794)
		(layer "F.Cu")
		(net "P52V_FAN_2_BUFF_EN_R")
	)
	(segment
		(start 27.03195 -177.997612)
		(end 27.03195 -179.451)
		(width 0.2794)
		(layer "F.Cu")
		(net "P52V_FAN_2_BUFF_EN_R")
	)
	(segment
		(start 30.45206 -177.419)
		(end 27.610562 -177.419)
		(width 0.2794)
		(layer "F.Cu")
		(net "P52V_FAN_2_BUFF_EN_R")
	)
	(segment
		(start 49.276 -139.7)
		(end 49.276 -163.830254)
		(width 0.2794)
		(layer "F.Cu")
		(net "P52V_FAN_2_BUFF_EN_R")
	)
	(segment
		(start 49.276 -163.830254)
		(end 48.387254 -164.719)
		(width 0.2794)
		(layer "F.Cu")
		(net "P52V_FAN_2_BUFF_EN_R")
	)
	(segment
		(start 25.92705 -179.451)
		(end 27.03195 -179.451)
		(width 0.2794)
		(layer "F.Cu")
		(net "P52V_FAN_2_BUFF_EN_R")
	)
	(segment
		(start 43.378628 -164.719)
		(end 39.354252 -166.385748)
		(width 0.2794)
		(layer "F.Cu")
		(net "P52V_FAN_2_BUFF_EN_R")
	)
	(segment
		(start 37.79901 -176.06899)
		(end 35.9283 -177.9397)
		(width 0.2794)
		(layer "F.Cu")
		(net "P52V_FAN_2_BUFF_EN_R")
	)
	(segment
		(start 27.610562 -177.419)
		(end 27.03195 -177.997612)
		(width 0.2794)
		(layer "F.Cu")
		(net "P52V_FAN_2_BUFF_EN_R")
	)
	(via
		(at 41.896538 -71.304912)
		(size 0.508)
		(drill 0.254)
		(layers "F.Cu" "B.Cu")
		(net "P52V_FAN_2_BUFF_EN_R")
	)
	(via
		(at 49.276 -139.7)
		(size 0.762)
		(drill 0.254)
		(layers "F.Cu" "B.Cu")
		(net "P52V_FAN_2_BUFF_EN_R")
	)
	(segment
		(start 40.931338 -71.304912)
		(end 41.896538 -71.304912)
		(width 0.2794)
		(layer "B.Cu")
		(net "P52V_FAN_2_BUFF_EN_R")
	)
	(segment
		(start 49.197514 -134.893304)
		(end 48.2092 -135.881618)
		(width 0.2286)
		(layer "In2.Cu")
		(net "P52V_FAN_2_BUFF_EN_R")
	)
	(segment
		(start 49.1998 -68.85178)
		(end 49.1998 -72.44842)
		(width 0.2286)
		(layer "In2.Cu")
		(net "P52V_FAN_2_BUFF_EN_R")
	)
	(segment
		(start 49.197514 -129.654554)
		(end 49.197514 -134.893304)
		(width 0.2286)
		(layer "In2.Cu")
		(net "P52V_FAN_2_BUFF_EN_R")
	)
	(segment
		(start 41.896538 -71.304912)
		(end 41.6052 -71.013574)
		(width 0.2286)
		(layer "In2.Cu")
		(net "P52V_FAN_2_BUFF_EN_R")
	)
	(segment
		(start 41.6052 -71.013574)
		(end 41.6052 -70.0278)
		(width 0.2286)
		(layer "In2.Cu")
		(net "P52V_FAN_2_BUFF_EN_R")
	)
	(segment
		(start 47.93742 -67.5894)
		(end 49.1998 -68.85178)
		(width 0.2286)
		(layer "In2.Cu")
		(net "P52V_FAN_2_BUFF_EN_R")
	)
	(segment
		(start 49.1998 -72.44842)
		(end 49.223676 -72.472296)
		(width 0.2286)
		(layer "In2.Cu")
		(net "P52V_FAN_2_BUFF_EN_R")
	)
	(segment
		(start 48.2092 -123.74118)
		(end 48.2092 -128.66624)
		(width 0.2286)
		(layer "In2.Cu")
		(net "P52V_FAN_2_BUFF_EN_R")
	)
	(segment
		(start 44.0436 -67.5894)
		(end 47.93742 -67.5894)
		(width 0.2286)
		(layer "In2.Cu")
		(net "P52V_FAN_2_BUFF_EN_R")
	)
	(segment
		(start 49.223676 -122.726704)
		(end 48.2092 -123.74118)
		(width 0.2286)
		(layer "In2.Cu")
		(net "P52V_FAN_2_BUFF_EN_R")
	)
	(segment
		(start 49.223676 -72.472296)
		(end 49.223676 -122.726704)
		(width 0.2286)
		(layer "In2.Cu")
		(net "P52V_FAN_2_BUFF_EN_R")
	)
	(segment
		(start 41.6052 -70.0278)
		(end 44.0436 -67.5894)
		(width 0.2286)
		(layer "In2.Cu")
		(net "P52V_FAN_2_BUFF_EN_R")
	)
	(segment
		(start 48.2092 -128.66624)
		(end 49.197514 -129.654554)
		(width 0.2286)
		(layer "In2.Cu")
		(net "P52V_FAN_2_BUFF_EN_R")
	)
	(segment
		(start 48.768 -138.303)
		(end 49.276 -138.811)
		(width 0.2286)
		(layer "In2.Cu")
		(net "P52V_FAN_2_BUFF_EN_R")
	)
	(segment
		(start 48.2092 -136.906)
		(end 48.768 -137.4648)
		(width 0.2286)
		(layer "In2.Cu")
		(net "P52V_FAN_2_BUFF_EN_R")
	)
	(segment
		(start 48.768 -137.4648)
		(end 48.768 -138.303)
		(width 0.2286)
		(layer "In2.Cu")
		(net "P52V_FAN_2_BUFF_EN_R")
	)
	(segment
		(start 49.276 -138.811)
		(end 49.276 -139.7)
		(width 0.2286)
		(layer "In2.Cu")
		(net "P52V_FAN_2_BUFF_EN_R")
	)
	(segment
		(start 48.2092 -135.881618)
		(end 48.2092 -136.906)
		(width 0.2286)
		(layer "In2.Cu")
		(net "P52V_FAN_2_BUFF_EN_R")
	)
	(segment
		(start 40.386 -186.436)
		(end 41.402 -185.42)
		(width 0.2794)
		(layer "F.Cu")
		(net "P52V_FAN_1_BUFF_EN_R")
	)
	(segment
		(start 26.74747 -184.98947)
		(end 31.136082 -184.98947)
		(width 0.2794)
		(layer "F.Cu")
		(net "P52V_FAN_1_BUFF_EN_R")
	)
	(segment
		(start 25.92705 -181.59095)
		(end 25.685496 -181.832504)
		(width 0.2794)
		(layer "F.Cu")
		(net "P52V_FAN_1_BUFF_EN_R")
	)
	(segment
		(start 32.582612 -186.436)
		(end 40.386 -186.436)
		(width 0.2794)
		(layer "F.Cu")
		(net "P52V_FAN_1_BUFF_EN_R")
	)
	(segment
		(start 25.92705 -180.594)
		(end 25.92705 -181.59095)
		(width 0.2794)
		(layer "F.Cu")
		(net "P52V_FAN_1_BUFF_EN_R")
	)
	(segment
		(start 41.402 -185.42)
		(end 47.508414 -185.42)
		(width 0.2794)
		(layer "F.Cu")
		(net "P52V_FAN_1_BUFF_EN_R")
	)
	(segment
		(start 25.908 -182.055008)
		(end 25.908 -184.15)
		(width 0.2794)
		(layer "F.Cu")
		(net "P52V_FAN_1_BUFF_EN_R")
	)
	(segment
		(start 27.03195 -180.594)
		(end 25.92705 -180.594)
		(width 0.2794)
		(layer "F.Cu")
		(net "P52V_FAN_1_BUFF_EN_R")
	)
	(segment
		(start 25.908 -184.15)
		(end 26.74747 -184.98947)
		(width 0.2794)
		(layer "F.Cu")
		(net "P52V_FAN_1_BUFF_EN_R")
	)
	(segment
		(start 31.136082 -184.98947)
		(end 32.582612 -186.436)
		(width 0.2794)
		(layer "F.Cu")
		(net "P52V_FAN_1_BUFF_EN_R")
	)
	(segment
		(start 25.685496 -181.832504)
		(end 25.908 -182.055008)
		(width 0.2794)
		(layer "F.Cu")
		(net "P52V_FAN_1_BUFF_EN_R")
	)
	(via
		(at 25.685496 -181.832504)
		(size 0.762)
		(drill 0.381)
		(layers "F.Cu" "B.Cu")
		(net "P52V_FAN_1_BUFF_EN_R")
	)
	(via
		(at 47.508414 -185.42)
		(size 0.508)
		(drill 0.254)
		(layers "F.Cu" "B.Cu")
		(net "P52V_FAN_1_BUFF_EN_R")
	)
	(via
		(at 37.437822 -252.894846)
		(size 0.508)
		(drill 0.254)
		(layers "F.Cu" "B.Cu")
		(net "P52V_FAN_1_BUFF_EN_R")
	)
	(segment
		(start 38.403022 -252.894846)
		(end 37.437822 -252.894846)
		(width 0.2794)
		(layer "B.Cu")
		(net "P52V_FAN_1_BUFF_EN_R")
	)
	(segment
		(start 37.437822 -252.633988)
		(end 36.887912 -252.084078)
		(width 0.2286)
		(layer "In2.Cu")
		(net "P52V_FAN_1_BUFF_EN_R")
	)
	(segment
		(start 31.341822 -249.19432)
		(end 34.406332 -241.7953)
		(width 0.2286)
		(layer "In2.Cu")
		(net "P52V_FAN_1_BUFF_EN_R")
	)
	(segment
		(start 41.02862 -211.260944)
		(end 41.02862 -196.596)
		(width 0.2286)
		(layer "In2.Cu")
		(net "P52V_FAN_1_BUFF_EN_R")
	)
	(segment
		(start 47.508414 -190.116206)
		(end 47.508414 -185.42)
		(width 0.2286)
		(layer "In2.Cu")
		(net "P52V_FAN_1_BUFF_EN_R")
	)
	(segment
		(start 31.457646 -252.084078)
		(end 30.971744 -251.598176)
		(width 0.2286)
		(layer "In2.Cu")
		(net "P52V_FAN_1_BUFF_EN_R")
	)
	(segment
		(start 34.406332 -217.883232)
		(end 41.02862 -211.260944)
		(width 0.2286)
		(layer "In2.Cu")
		(net "P52V_FAN_1_BUFF_EN_R")
	)
	(segment
		(start 30.971744 -249.564398)
		(end 31.341822 -249.19432)
		(width 0.2286)
		(layer "In2.Cu")
		(net "P52V_FAN_1_BUFF_EN_R")
	)
	(segment
		(start 37.437822 -252.894846)
		(end 37.437822 -252.633988)
		(width 0.2286)
		(layer "In2.Cu")
		(net "P52V_FAN_1_BUFF_EN_R")
	)
	(segment
		(start 34.406332 -241.7953)
		(end 34.406332 -217.883232)
		(width 0.2286)
		(layer "In2.Cu")
		(net "P52V_FAN_1_BUFF_EN_R")
	)
	(segment
		(start 36.887912 -252.084078)
		(end 31.457646 -252.084078)
		(width 0.2286)
		(layer "In2.Cu")
		(net "P52V_FAN_1_BUFF_EN_R")
	)
	(segment
		(start 41.02862 -196.596)
		(end 47.508414 -190.116206)
		(width 0.2286)
		(layer "In2.Cu")
		(net "P52V_FAN_1_BUFF_EN_R")
	)
	(segment
		(start 30.971744 -251.598176)
		(end 30.971744 -249.564398)
		(width 0.2286)
		(layer "In2.Cu")
		(net "P52V_FAN_1_BUFF_EN_R")
	)
	(segment
		(start 23.114 -161.391346)
		(end 23.114 -160.42005)
		(width 0.2794)
		(layer "F.Cu")
		(net "SMB_FAN7_SDA")
	)
	(segment
		(start 15.3416 -295.656)
		(end 14.75105 -295.656)
		(width 0.2794)
		(layer "F.Cu")
		(net "SMB_FAN7_SDA")
	)
	(segment
		(start 15.621 -294.64)
		(end 15.621 -295.3766)
		(width 0.2794)
		(layer "F.Cu")
		(net "SMB_FAN7_SDA")
	)
	(segment
		(start 15.621 -295.3766)
		(end 15.3416 -295.656)
		(width 0.2794)
		(layer "F.Cu")
		(net "SMB_FAN7_SDA")
	)
	(segment
		(start 22.4282 -162.077146)
		(end 23.114 -161.391346)
		(width 0.2794)
		(layer "F.Cu")
		(net "SMB_FAN7_SDA")
	)
	(segment
		(start 22.4282 -162.5092)
		(end 22.4282 -162.077146)
		(width 0.2794)
		(layer "F.Cu")
		(net "SMB_FAN7_SDA")
	)
	(via
		(at 15.621 -294.64)
		(size 0.508)
		(drill 0.254)
		(layers "F.Cu" "B.Cu")
		(net "SMB_FAN7_SDA")
	)
	(via
		(at 22.4282 -162.5092)
		(size 0.508)
		(drill 0.254)
		(layers "F.Cu" "B.Cu")
		(net "SMB_FAN7_SDA")
	)
	(segment
		(start 21.025612 -184.841388)
		(end 18.796 -187.071)
		(width 0.2286)
		(layer "In2.Cu")
		(net "SMB_FAN7_SDA")
	)
	(segment
		(start 18.796 -191.1096)
		(end 18.2118 -191.6938)
		(width 0.2286)
		(layer "In2.Cu")
		(net "SMB_FAN7_SDA")
	)
	(segment
		(start 19.05 -204.851)
		(end 21.04136 -206.84236)
		(width 0.2286)
		(layer "In2.Cu")
		(net "SMB_FAN7_SDA")
	)
	(segment
		(start 23.0886 -279.044654)
		(end 14.412468 -287.720786)
		(width 0.2286)
		(layer "In2.Cu")
		(net "SMB_FAN7_SDA")
	)
	(segment
		(start 24.948642 -165.410642)
		(end 24.948642 -168.849294)
		(width 0.2286)
		(layer "In2.Cu")
		(net "SMB_FAN7_SDA")
	)
	(segment
		(start 18.2118 -191.6938)
		(end 18.2118 -196.9262)
		(width 0.2286)
		(layer "In2.Cu")
		(net "SMB_FAN7_SDA")
	)
	(segment
		(start 18.6944 -202.8952)
		(end 19.05 -203.2508)
		(width 0.2286)
		(layer "In2.Cu")
		(net "SMB_FAN7_SDA")
	)
	(segment
		(start 22.4282 -162.8902)
		(end 24.948642 -165.410642)
		(width 0.2286)
		(layer "In2.Cu")
		(net "SMB_FAN7_SDA")
	)
	(segment
		(start 18.6944 -197.4088)
		(end 18.6944 -202.8952)
		(width 0.2286)
		(layer "In2.Cu")
		(net "SMB_FAN7_SDA")
	)
	(segment
		(start 20.559268 -219.8116)
		(end 16.558514 -223.812354)
		(width 0.2286)
		(layer "In2.Cu")
		(net "SMB_FAN7_SDA")
	)
	(segment
		(start 21.025612 -183.00827)
		(end 21.025612 -184.841388)
		(width 0.2286)
		(layer "In2.Cu")
		(net "SMB_FAN7_SDA")
	)
	(segment
		(start 21.417026 -210.039204)
		(end 21.417026 -213.391242)
		(width 0.2286)
		(layer "In2.Cu")
		(net "SMB_FAN7_SDA")
	)
	(segment
		(start 21.04136 -209.663538)
		(end 21.417026 -210.039204)
		(width 0.2286)
		(layer "In2.Cu")
		(net "SMB_FAN7_SDA")
	)
	(segment
		(start 21.04136 -206.84236)
		(end 21.04136 -209.663538)
		(width 0.2286)
		(layer "In2.Cu")
		(net "SMB_FAN7_SDA")
	)
	(segment
		(start 23.7744 -170.023536)
		(end 23.7744 -180.259482)
		(width 0.2286)
		(layer "In2.Cu")
		(net "SMB_FAN7_SDA")
	)
	(segment
		(start 19.05 -203.2508)
		(end 19.05 -204.851)
		(width 0.2286)
		(layer "In2.Cu")
		(net "SMB_FAN7_SDA")
	)
	(segment
		(start 18.796 -187.071)
		(end 18.796 -191.1096)
		(width 0.2286)
		(layer "In2.Cu")
		(net "SMB_FAN7_SDA")
	)
	(segment
		(start 24.948642 -168.849294)
		(end 23.7744 -170.023536)
		(width 0.2286)
		(layer "In2.Cu")
		(net "SMB_FAN7_SDA")
	)
	(segment
		(start 23.0886 -252.874272)
		(end 23.0886 -279.044654)
		(width 0.2286)
		(layer "In2.Cu")
		(net "SMB_FAN7_SDA")
	)
	(segment
		(start 23.7744 -180.259482)
		(end 21.025612 -183.00827)
		(width 0.2286)
		(layer "In2.Cu")
		(net "SMB_FAN7_SDA")
	)
	(segment
		(start 14.412468 -287.720786)
		(end 14.412468 -293.431468)
		(width 0.2286)
		(layer "In2.Cu")
		(net "SMB_FAN7_SDA")
	)
	(segment
		(start 16.558514 -223.812354)
		(end 16.558514 -246.344186)
		(width 0.2286)
		(layer "In2.Cu")
		(net "SMB_FAN7_SDA")
	)
	(segment
		(start 22.4282 -162.5092)
		(end 22.4282 -162.8902)
		(width 0.2286)
		(layer "In2.Cu")
		(net "SMB_FAN7_SDA")
	)
	(segment
		(start 16.558514 -246.344186)
		(end 23.0886 -252.874272)
		(width 0.2286)
		(layer "In2.Cu")
		(net "SMB_FAN7_SDA")
	)
	(segment
		(start 20.559268 -214.249)
		(end 20.559268 -219.8116)
		(width 0.2286)
		(layer "In2.Cu")
		(net "SMB_FAN7_SDA")
	)
	(segment
		(start 18.2118 -196.9262)
		(end 18.6944 -197.4088)
		(width 0.2286)
		(layer "In2.Cu")
		(net "SMB_FAN7_SDA")
	)
	(segment
		(start 21.417026 -213.391242)
		(end 20.559268 -214.249)
		(width 0.2286)
		(layer "In2.Cu")
		(net "SMB_FAN7_SDA")
	)
	(segment
		(start 14.412468 -293.431468)
		(end 15.621 -294.64)
		(width 0.2286)
		(layer "In2.Cu")
		(net "SMB_FAN7_SDA")
	)
	(segment
		(start 31.378144 -184.40527)
		(end 28.27147 -184.40527)
		(width 0.2794)
		(layer "F.Cu")
		(net "P52V_FAN_0_BUFF_EN_R")
	)
	(segment
		(start 47.752 -184.785)
		(end 41.210738 -184.785)
		(width 0.2794)
		(layer "F.Cu")
		(net "P52V_FAN_0_BUFF_EN_R")
	)
	(segment
		(start 41.210738 -184.785)
		(end 40.143938 -185.8518)
		(width 0.2794)
		(layer "F.Cu")
		(net "P52V_FAN_0_BUFF_EN_R")
	)
	(segment
		(start 48.3362 -184.2008)
		(end 47.752 -184.785)
		(width 0.2794)
		(layer "F.Cu")
		(net "P52V_FAN_0_BUFF_EN_R")
	)
	(segment
		(start 32.824674 -185.8518)
		(end 31.378144 -184.40527)
		(width 0.2794)
		(layer "F.Cu")
		(net "P52V_FAN_0_BUFF_EN_R")
	)
	(segment
		(start 28.27147 -184.40527)
		(end 27.03195 -183.16575)
		(width 0.2794)
		(layer "F.Cu")
		(net "P52V_FAN_0_BUFF_EN_R")
	)
	(segment
		(start 27.03195 -183.16575)
		(end 27.03195 -182.372)
		(width 0.2794)
		(layer "F.Cu")
		(net "P52V_FAN_0_BUFF_EN_R")
	)
	(segment
		(start 40.143938 -185.8518)
		(end 32.824674 -185.8518)
		(width 0.2794)
		(layer "F.Cu")
		(net "P52V_FAN_0_BUFF_EN_R")
	)
	(via
		(at 41.896538 -255.905)
		(size 0.508)
		(drill 0.254)
		(layers "F.Cu" "B.Cu")
		(net "P52V_FAN_0_BUFF_EN_R")
	)
	(via
		(at 48.3362 -184.2008)
		(size 0.508)
		(drill 0.254)
		(layers "F.Cu" "B.Cu")
		(net "P52V_FAN_0_BUFF_EN_R")
	)
	(segment
		(start 40.931338 -255.905)
		(end 41.896538 -255.905)
		(width 0.2794)
		(layer "B.Cu")
		(net "P52V_FAN_0_BUFF_EN_R")
	)
	(segment
		(start 34.955988 -234.87888)
		(end 34.955988 -218.125548)
		(width 0.2286)
		(layer "In2.Cu")
		(net "P52V_FAN_0_BUFF_EN_R")
	)
	(segment
		(start 41.896538 -256.153158)
		(end 42.380662 -256.637282)
		(width 0.2286)
		(layer "In2.Cu")
		(net "P52V_FAN_0_BUFF_EN_R")
	)
	(segment
		(start 43.6626 -243.585492)
		(end 34.955988 -234.87888)
		(width 0.2286)
		(layer "In2.Cu")
		(net "P52V_FAN_0_BUFF_EN_R")
	)
	(segment
		(start 48.3362 -190.114428)
		(end 48.3362 -184.2008)
		(width 0.2286)
		(layer "In2.Cu")
		(net "P52V_FAN_0_BUFF_EN_R")
	)
	(segment
		(start 34.955988 -218.125548)
		(end 41.56202 -211.519516)
		(width 0.2286)
		(layer "In2.Cu")
		(net "P52V_FAN_0_BUFF_EN_R")
	)
	(segment
		(start 41.56202 -211.519516)
		(end 41.56202 -196.888608)
		(width 0.2286)
		(layer "In2.Cu")
		(net "P52V_FAN_0_BUFF_EN_R")
	)
	(segment
		(start 42.98061 -256.637282)
		(end 43.237912 -256.37998)
		(width 0.2286)
		(layer "In2.Cu")
		(net "P52V_FAN_0_BUFF_EN_R")
	)
	(segment
		(start 43.237912 -256.37998)
		(end 43.237912 -253.053088)
		(width 0.2286)
		(layer "In2.Cu")
		(net "P52V_FAN_0_BUFF_EN_R")
	)
	(segment
		(start 43.6626 -252.6284)
		(end 43.6626 -243.585492)
		(width 0.2286)
		(layer "In2.Cu")
		(net "P52V_FAN_0_BUFF_EN_R")
	)
	(segment
		(start 41.56202 -196.888608)
		(end 48.3362 -190.114428)
		(width 0.2286)
		(layer "In2.Cu")
		(net "P52V_FAN_0_BUFF_EN_R")
	)
	(segment
		(start 43.237912 -253.053088)
		(end 43.6626 -252.6284)
		(width 0.2286)
		(layer "In2.Cu")
		(net "P52V_FAN_0_BUFF_EN_R")
	)
	(segment
		(start 42.380662 -256.637282)
		(end 42.98061 -256.637282)
		(width 0.2286)
		(layer "In2.Cu")
		(net "P52V_FAN_0_BUFF_EN_R")
	)
	(segment
		(start 41.896538 -255.905)
		(end 41.896538 -256.153158)
		(width 0.2286)
		(layer "In2.Cu")
		(net "P52V_FAN_0_BUFF_EN_R")
	)
	(segment
		(start 14.75105 -292.608)
		(end 15.36065 -292.608)
		(width 0.2794)
		(layer "F.Cu")
		(net "SMB_FAN7_SCL")
	)
	(segment
		(start 22.225 -160.54705)
		(end 22.225 -161.2138)
		(width 0.2794)
		(layer "F.Cu")
		(net "SMB_FAN7_SCL")
	)
	(segment
		(start 22.098 -160.42005)
		(end 22.225 -160.54705)
		(width 0.2794)
		(layer "F.Cu")
		(net "SMB_FAN7_SCL")
	)
	(via
		(at 22.225 -161.2138)
		(size 0.508)
		(drill 0.254)
		(layers "F.Cu" "B.Cu")
		(net "SMB_FAN7_SCL")
	)
	(via
		(at 15.36065 -292.608)
		(size 0.508)
		(drill 0.254)
		(layers "F.Cu" "B.Cu")
		(net "SMB_FAN7_SCL")
	)
	(segment
		(start 25.659842 -169.10812)
		(end 24.4602 -170.307762)
		(width 0.2286)
		(layer "In2.Cu")
		(net "SMB_FAN7_SCL")
	)
	(segment
		(start 21.72716 -199.93864)
		(end 21.72716 -206.883)
		(width 0.2286)
		(layer "In2.Cu")
		(net "SMB_FAN7_SCL")
	)
	(segment
		(start 22.225 -161.49447)
		(end 25.659842 -164.929312)
		(width 0.2286)
		(layer "In2.Cu")
		(net "SMB_FAN7_SCL")
	)
	(segment
		(start 22.225 -161.2138)
		(end 22.225 -161.49447)
		(width 0.2286)
		(layer "In2.Cu")
		(net "SMB_FAN7_SCL")
	)
	(segment
		(start 17.244314 -224.211896)
		(end 17.244314 -246.05996)
		(width 0.2286)
		(layer "In2.Cu")
		(net "SMB_FAN7_SCL")
	)
	(segment
		(start 21.72716 -206.883)
		(end 21.7932 -206.94904)
		(width 0.2286)
		(layer "In2.Cu")
		(net "SMB_FAN7_SCL")
	)
	(segment
		(start 23.7744 -279.5016)
		(end 19.36242 -283.91358)
		(width 0.2286)
		(layer "In2.Cu")
		(net "SMB_FAN7_SCL")
	)
	(segment
		(start 21.72716 -190.35014)
		(end 21.92782 -190.5508)
		(width 0.2286)
		(layer "In2.Cu")
		(net "SMB_FAN7_SCL")
	)
	(segment
		(start 21.7932 -206.94904)
		(end 21.7932 -209.445352)
		(width 0.2286)
		(layer "In2.Cu")
		(net "SMB_FAN7_SCL")
	)
	(segment
		(start 18.38452 -286.24784)
		(end 17.85366 -285.71698)
		(width 0.2286)
		(layer "In2.Cu")
		(net "SMB_FAN7_SCL")
	)
	(segment
		(start 19.89328 -285.03372)
		(end 19.685 -285.242)
		(width 0.2286)
		(layer "In2.Cu")
		(net "SMB_FAN7_SCL")
	)
	(segment
		(start 15.137892 -292.385242)
		(end 15.36065 -292.608)
		(width 0.2286)
		(layer "In2.Cu")
		(net "SMB_FAN7_SCL")
	)
	(segment
		(start 22.102826 -213.456012)
		(end 22.4028 -213.755986)
		(width 0.2286)
		(layer "In2.Cu")
		(net "SMB_FAN7_SCL")
	)
	(segment
		(start 18.88744 -285.74492)
		(end 18.88744 -286.03956)
		(width 0.2286)
		(layer "In2.Cu")
		(net "SMB_FAN7_SCL")
	)
	(segment
		(start 23.7744 -252.590046)
		(end 23.7744 -279.5016)
		(width 0.2286)
		(layer "In2.Cu")
		(net "SMB_FAN7_SCL")
	)
	(segment
		(start 21.72716 -183.276748)
		(end 21.72716 -190.35014)
		(width 0.2286)
		(layer "In2.Cu")
		(net "SMB_FAN7_SCL")
	)
	(segment
		(start 19.89328 -284.73908)
		(end 19.89328 -285.03372)
		(width 0.2286)
		(layer "In2.Cu")
		(net "SMB_FAN7_SCL")
	)
	(segment
		(start 18.8595 -284.71114)
		(end 18.56486 -284.71114)
		(width 0.2286)
		(layer "In2.Cu")
		(net "SMB_FAN7_SCL")
	)
	(segment
		(start 22.4028 -219.05341)
		(end 17.244314 -224.211896)
		(width 0.2286)
		(layer "In2.Cu")
		(net "SMB_FAN7_SCL")
	)
	(segment
		(start 21.92782 -190.5508)
		(end 21.92782 -199.73798)
		(width 0.2286)
		(layer "In2.Cu")
		(net "SMB_FAN7_SCL")
	)
	(segment
		(start 24.4602 -180.543708)
		(end 21.72716 -183.276748)
		(width 0.2286)
		(layer "In2.Cu")
		(net "SMB_FAN7_SCL")
	)
	(segment
		(start 17.244314 -246.05996)
		(end 23.7744 -252.590046)
		(width 0.2286)
		(layer "In2.Cu")
		(net "SMB_FAN7_SCL")
	)
	(segment
		(start 17.55902 -285.71698)
		(end 15.137892 -288.138108)
		(width 0.2286)
		(layer "In2.Cu")
		(net "SMB_FAN7_SCL")
	)
	(segment
		(start 21.7932 -209.445352)
		(end 22.102826 -209.754978)
		(width 0.2286)
		(layer "In2.Cu")
		(net "SMB_FAN7_SCL")
	)
	(segment
		(start 18.35658 -284.91942)
		(end 18.35658 -285.21406)
		(width 0.2286)
		(layer "In2.Cu")
		(net "SMB_FAN7_SCL")
	)
	(segment
		(start 18.88744 -286.03956)
		(end 18.67916 -286.24784)
		(width 0.2286)
		(layer "In2.Cu")
		(net "SMB_FAN7_SCL")
	)
	(segment
		(start 22.102826 -209.754978)
		(end 22.102826 -213.456012)
		(width 0.2286)
		(layer "In2.Cu")
		(net "SMB_FAN7_SCL")
	)
	(segment
		(start 19.39036 -285.242)
		(end 18.8595 -284.71114)
		(width 0.2286)
		(layer "In2.Cu")
		(net "SMB_FAN7_SCL")
	)
	(segment
		(start 18.67916 -286.24784)
		(end 18.38452 -286.24784)
		(width 0.2286)
		(layer "In2.Cu")
		(net "SMB_FAN7_SCL")
	)
	(segment
		(start 22.4028 -213.755986)
		(end 22.4028 -219.05341)
		(width 0.2286)
		(layer "In2.Cu")
		(net "SMB_FAN7_SCL")
	)
	(segment
		(start 19.685 -285.242)
		(end 19.39036 -285.242)
		(width 0.2286)
		(layer "In2.Cu")
		(net "SMB_FAN7_SCL")
	)
	(segment
		(start 24.4602 -170.307762)
		(end 24.4602 -180.543708)
		(width 0.2286)
		(layer "In2.Cu")
		(net "SMB_FAN7_SCL")
	)
	(segment
		(start 17.85366 -285.71698)
		(end 17.55902 -285.71698)
		(width 0.2286)
		(layer "In2.Cu")
		(net "SMB_FAN7_SCL")
	)
	(segment
		(start 15.137892 -288.138108)
		(end 15.137892 -292.385242)
		(width 0.2286)
		(layer "In2.Cu")
		(net "SMB_FAN7_SCL")
	)
	(segment
		(start 18.35658 -285.21406)
		(end 18.88744 -285.74492)
		(width 0.2286)
		(layer "In2.Cu")
		(net "SMB_FAN7_SCL")
	)
	(segment
		(start 19.36242 -283.91358)
		(end 19.36242 -284.20822)
		(width 0.2286)
		(layer "In2.Cu")
		(net "SMB_FAN7_SCL")
	)
	(segment
		(start 25.659842 -164.929312)
		(end 25.659842 -169.10812)
		(width 0.2286)
		(layer "In2.Cu")
		(net "SMB_FAN7_SCL")
	)
	(segment
		(start 18.56486 -284.71114)
		(end 18.35658 -284.91942)
		(width 0.2286)
		(layer "In2.Cu")
		(net "SMB_FAN7_SCL")
	)
	(segment
		(start 21.92782 -199.73798)
		(end 21.72716 -199.93864)
		(width 0.2286)
		(layer "In2.Cu")
		(net "SMB_FAN7_SCL")
	)
	(segment
		(start 19.36242 -284.20822)
		(end 19.89328 -284.73908)
		(width 0.2286)
		(layer "In2.Cu")
		(net "SMB_FAN7_SCL")
	)
	(via
		(at 12.35964 -260.5151)
		(size 0.6604)
		(drill 0.3302)
		(layers "F.Cu" "B.Cu")
		(net "FAN_7_P5V")
	)
	(segment
		(start 11.715242 -259.730748)
		(end 11.811 -259.826506)
		(width 0.2794)
		(layer "B.Cu")
		(net "FAN_7_P5V")
	)
	(segment
		(start 12.513818 -260.798818)
		(end 12.982194 -261.675372)
		(width 0.1016)
		(layer "B.Cu")
		(net "FAN_7_P5V")
	)
	(segment
		(start 11.811 -259.826506)
		(end 11.811 -259.96646)
		(width 0.2794)
		(layer "B.Cu")
		(net "FAN_7_P5V")
	)
	(segment
		(start 12.35964 -260.5151)
		(end 12.35964 -260.64464)
		(width 0.1016)
		(layer "B.Cu")
		(net "FAN_7_P5V")
	)
	(segment
		(start 12.35964 -260.64464)
		(end 12.513818 -260.798818)
		(width 0.1016)
		(layer "B.Cu")
		(net "FAN_7_P5V")
	)
	(segment
		(start 11.715242 -258.962906)
		(end 11.715242 -259.730748)
		(width 0.2794)
		(layer "B.Cu")
		(net "FAN_7_P5V")
	)
	(segment
		(start 11.811 -259.96646)
		(end 12.35964 -260.5151)
		(width 0.2794)
		(layer "B.Cu")
		(net "FAN_7_P5V")
	)
	(segment
		(start 12.982194 -261.675372)
		(end 12.982194 -262.054848)
		(width 0.1016)
		(layer "B.Cu")
		(net "FAN_7_P5V")
	)
	(segment
		(start 14.98219 -260.718554)
		(end 14.98219 -262.054848)
		(width 0.1016)
		(layer "B.Cu")
		(net "FAN_7_TIMER")
	)
	(segment
		(start 15.226792 -260.128258)
		(end 14.98219 -260.718554)
		(width 0.2794)
		(layer "B.Cu")
		(net "FAN_7_TIMER")
	)
	(segment
		(start 16.383 -258.97205)
		(end 15.226792 -260.128258)
		(width 0.2794)
		(layer "B.Cu")
		(net "FAN_7_TIMER")
	)
	(segment
		(start 30.23235 -139.192)
		(end 30.734 -139.69365)
		(width 0.2794)
		(layer "F.Cu")
		(net "FAN_3_PRSNT_BUF_N")
	)
	(segment
		(start 44.5516 -140.081)
		(end 48.403256 -136.229344)
		(width 0.2794)
		(layer "F.Cu")
		(net "FAN_3_PRSNT_BUF_N")
	)
	(segment
		(start 3.567938 -139.192)
		(end 30.23235 -139.192)
		(width 0.2794)
		(layer "F.Cu")
		(net "FAN_3_PRSNT_BUF_N")
	)
	(segment
		(start 36.767262 -140.081)
		(end 44.5516 -140.081)
		(width 0.2794)
		(layer "F.Cu")
		(net "FAN_3_PRSNT_BUF_N")
	)
	(segment
		(start 2.742946 -139.827)
		(end 2.932938 -139.827)
		(width 0.2794)
		(layer "F.Cu")
		(net "FAN_3_PRSNT_BUF_N")
	)
	(segment
		(start 3.79095 -167.64)
		(end 3.79095 -167.551862)
		(width 0.2794)
		(layer "F.Cu")
		(net "FAN_3_PRSNT_BUF_N")
	)
	(segment
		(start 3.79095 -167.64)
		(end 2.93116 -167.64)
		(width 0.2794)
		(layer "F.Cu")
		(net "FAN_3_PRSNT_BUF_N")
	)
	(segment
		(start 2.93116 -167.64)
		(end 1.409446 -169.161714)
		(width 0.2794)
		(layer "F.Cu")
		(net "FAN_3_PRSNT_BUF_N")
	)
	(segment
		(start 36.379912 -139.69365)
		(end 36.767262 -140.081)
		(width 0.2794)
		(layer "F.Cu")
		(net "FAN_3_PRSNT_BUF_N")
	)
	(segment
		(start 1.50495 -141.064996)
		(end 2.742946 -139.827)
		(width 0.2794)
		(layer "F.Cu")
		(net "FAN_3_PRSNT_BUF_N")
	)
	(segment
		(start 2.932938 -139.827)
		(end 3.567938 -139.192)
		(width 0.2794)
		(layer "F.Cu")
		(net "FAN_3_PRSNT_BUF_N")
	)
	(segment
		(start 5.437124 -179.259738)
		(end 5.811266 -179.63388)
		(width 0.2794)
		(layer "F.Cu")
		(net "FAN_3_PRSNT_BUF_N")
	)
	(segment
		(start 30.734 -139.69365)
		(end 36.379912 -139.69365)
		(width 0.2794)
		(layer "F.Cu")
		(net "FAN_3_PRSNT_BUF_N")
	)
	(segment
		(start 1.409446 -169.161714)
		(end 1.409446 -177.00117)
		(width 0.2794)
		(layer "F.Cu")
		(net "FAN_3_PRSNT_BUF_N")
	)
	(segment
		(start 1.50495 -165.265862)
		(end 1.50495 -141.064996)
		(width 0.2794)
		(layer "F.Cu")
		(net "FAN_3_PRSNT_BUF_N")
	)
	(segment
		(start 1.409446 -177.00117)
		(end 3.668014 -179.259738)
		(width 0.2794)
		(layer "F.Cu")
		(net "FAN_3_PRSNT_BUF_N")
	)
	(segment
		(start 3.79095 -167.551862)
		(end 1.50495 -165.265862)
		(width 0.2794)
		(layer "F.Cu")
		(net "FAN_3_PRSNT_BUF_N")
	)
	(segment
		(start 3.668014 -179.259738)
		(end 5.437124 -179.259738)
		(width 0.2794)
		(layer "F.Cu")
		(net "FAN_3_PRSNT_BUF_N")
	)
	(segment
		(start 5.811266 -179.63388)
		(end 7.366 -179.63388)
		(width 0.2794)
		(layer "F.Cu")
		(net "FAN_3_PRSNT_BUF_N")
	)
	(segment
		(start 48.403256 -136.229344)
		(end 48.765714 -136.229344)
		(width 0.2794)
		(layer "F.Cu")
		(net "FAN_3_PRSNT_BUF_N")
	)
	(via
		(at 34.666428 -69.207634)
		(size 0.508)
		(drill 0.254)
		(layers "F.Cu" "B.Cu")
		(net "FAN_3_PRSNT_BUF_N")
	)
	(via
		(at 48.765714 -136.229344)
		(size 0.508)
		(drill 0.254)
		(layers "F.Cu" "B.Cu")
		(net "FAN_3_PRSNT_BUF_N")
	)
	(segment
		(start 34.666428 -68.521834)
		(end 34.666428 -69.207634)
		(width 0.2794)
		(layer "B.Cu")
		(net "FAN_3_PRSNT_BUF_N")
	)
	(segment
		(start 48.765714 -128.45669)
		(end 48.765714 -123.939046)
		(width 0.2286)
		(layer "In2.Cu")
		(net "FAN_3_PRSNT_BUF_N")
	)
	(segment
		(start 49.7332 -72.22744)
		(end 49.7332 -68.6308)
		(width 0.2286)
		(layer "In2.Cu")
		(net "FAN_3_PRSNT_BUF_N")
	)
	(segment
		(start 41.612566 -69.207634)
		(end 34.666428 -69.207634)
		(width 0.2286)
		(layer "In2.Cu")
		(net "FAN_3_PRSNT_BUF_N")
	)
	(segment
		(start 43.7642 -67.056)
		(end 41.612566 -69.207634)
		(width 0.2286)
		(layer "In2.Cu")
		(net "FAN_3_PRSNT_BUF_N")
	)
	(segment
		(start 48.765714 -123.939046)
		(end 49.757076 -122.947684)
		(width 0.2286)
		(layer "In2.Cu")
		(net "FAN_3_PRSNT_BUF_N")
	)
	(segment
		(start 49.74082 -135.254238)
		(end 49.74082 -129.431796)
		(width 0.2286)
		(layer "In2.Cu")
		(net "FAN_3_PRSNT_BUF_N")
	)
	(segment
		(start 49.757076 -122.947684)
		(end 49.757076 -72.251316)
		(width 0.2286)
		(layer "In2.Cu")
		(net "FAN_3_PRSNT_BUF_N")
	)
	(segment
		(start 49.74082 -129.431796)
		(end 48.765714 -128.45669)
		(width 0.2286)
		(layer "In2.Cu")
		(net "FAN_3_PRSNT_BUF_N")
	)
	(segment
		(start 49.757076 -72.251316)
		(end 49.7332 -72.22744)
		(width 0.2286)
		(layer "In2.Cu")
		(net "FAN_3_PRSNT_BUF_N")
	)
	(segment
		(start 48.765714 -136.229344)
		(end 49.74082 -135.254238)
		(width 0.2286)
		(layer "In2.Cu")
		(net "FAN_3_PRSNT_BUF_N")
	)
	(segment
		(start 48.1584 -67.056)
		(end 43.7642 -67.056)
		(width 0.2286)
		(layer "In2.Cu")
		(net "FAN_3_PRSNT_BUF_N")
	)
	(segment
		(start 49.7332 -68.6308)
		(end 48.1584 -67.056)
		(width 0.2286)
		(layer "In2.Cu")
		(net "FAN_3_PRSNT_BUF_N")
	)
	(via
		(at 18.08734 -260.16966)
		(size 0.6604)
		(drill 0.3302)
		(layers "F.Cu" "B.Cu")
		(net "FAN_7_IMON")
	)
	(segment
		(start 16.54937 -261.230872)
		(end 16.18234 -261.597902)
		(width 0.1016)
		(layer "B.Cu")
		(net "FAN_7_IMON")
	)
	(segment
		(start 18.08734 -260.16966)
		(end 17.363948 -260.893306)
		(width 0.2794)
		(layer "B.Cu")
		(net "FAN_7_IMON")
	)
	(segment
		(start 18.430494 -259.826506)
		(end 18.08734 -260.16966)
		(width 0.2794)
		(layer "B.Cu")
		(net "FAN_7_IMON")
	)
	(segment
		(start 18.430494 -258.97205)
		(end 18.430494 -259.826506)
		(width 0.2794)
		(layer "B.Cu")
		(net "FAN_7_IMON")
	)
	(segment
		(start 17.363948 -260.893306)
		(end 16.54937 -261.230872)
		(width 0.2794)
		(layer "B.Cu")
		(net "FAN_7_IMON")
	)
	(segment
		(start 16.18234 -261.597902)
		(end 16.18234 -262.054848)
		(width 0.1016)
		(layer "B.Cu")
		(net "FAN_7_IMON")
	)
	(segment
		(start 37.3888 -216.4588)
		(end 37.846 -216.916)
		(width 0.2794)
		(layer "F.Cu")
		(net "FAN_1_PRSNT_BUF_N")
	)
	(segment
		(start 5.163058 -180.638196)
		(end 5.458968 -180.934106)
		(width 0.2794)
		(layer "F.Cu")
		(net "FAN_1_PRSNT_BUF_N")
	)
	(segment
		(start 4.470146 -213.36)
		(end 19.558 -213.36)
		(width 0.2794)
		(layer "F.Cu")
		(net "FAN_1_PRSNT_BUF_N")
	)
	(segment
		(start 29.4894 -216.4588)
		(end 37.3888 -216.4588)
		(width 0.2794)
		(layer "F.Cu")
		(net "FAN_1_PRSNT_BUF_N")
	)
	(segment
		(start 3.76682 -212.656674)
		(end 4.470146 -213.36)
		(width 0.2794)
		(layer "F.Cu")
		(net "FAN_1_PRSNT_BUF_N")
	)
	(segment
		(start 3.79095 -163.957)
		(end 3.40995 -164.338)
		(width 0.2794)
		(layer "F.Cu")
		(net "FAN_1_PRSNT_BUF_N")
	)
	(segment
		(start 3.40995 -164.338)
		(end 3.18135 -164.338)
		(width 0.2794)
		(layer "F.Cu")
		(net "FAN_1_PRSNT_BUF_N")
	)
	(segment
		(start 3.18135 -164.338)
		(end 3.178048 -164.341302)
		(width 0.2794)
		(layer "F.Cu")
		(net "FAN_1_PRSNT_BUF_N")
	)
	(segment
		(start 5.458968 -180.934106)
		(end 7.366 -180.934106)
		(width 0.2794)
		(layer "F.Cu")
		(net "FAN_1_PRSNT_BUF_N")
	)
	(segment
		(start 19.558 -213.36)
		(end 20.447 -212.471)
		(width 0.2794)
		(layer "F.Cu")
		(net "FAN_1_PRSNT_BUF_N")
	)
	(segment
		(start 20.447 -212.471)
		(end 25.5016 -212.471)
		(width 0.2794)
		(layer "F.Cu")
		(net "FAN_1_PRSNT_BUF_N")
	)
	(segment
		(start 3.76682 -193.957956)
		(end 3.76682 -212.656674)
		(width 0.2794)
		(layer "F.Cu")
		(net "FAN_1_PRSNT_BUF_N")
	)
	(segment
		(start 25.5016 -212.471)
		(end 29.4894 -216.4588)
		(width 0.2794)
		(layer "F.Cu")
		(net "FAN_1_PRSNT_BUF_N")
	)
	(segment
		(start 37.846 -216.916)
		(end 37.846 -217.043)
		(width 0.2794)
		(layer "F.Cu")
		(net "FAN_1_PRSNT_BUF_N")
	)
	(via
		(at 5.163058 -180.638196)
		(size 0.508)
		(drill 0.254)
		(layers "F.Cu" "B.Cu")
		(net "FAN_1_PRSNT_BUF_N")
	)
	(via
		(at 37.846 -217.043)
		(size 0.508)
		(drill 0.254)
		(layers "F.Cu" "B.Cu")
		(net "FAN_1_PRSNT_BUF_N")
	)
	(via
		(at 34.666428 -254.607568)
		(size 0.508)
		(drill 0.254)
		(layers "F.Cu" "B.Cu")
		(net "FAN_1_PRSNT_BUF_N")
	)
	(via
		(at 3.178048 -164.341302)
		(size 0.508)
		(drill 0.254)
		(layers "F.Cu" "B.Cu")
		(net "FAN_1_PRSNT_BUF_N")
	)
	(via
		(at 3.76682 -193.957956)
		(size 0.508)
		(drill 0.254)
		(layers "F.Cu" "B.Cu")
		(net "FAN_1_PRSNT_BUF_N")
	)
	(segment
		(start 34.666428 -253.921768)
		(end 34.666428 -254.607568)
		(width 0.2794)
		(layer "B.Cu")
		(net "FAN_1_PRSNT_BUF_N")
	)
	(segment
		(start 3.178048 -164.341302)
		(end 2.032 -165.48735)
		(width 0.2286)
		(layer "In2.Cu")
		(net "FAN_1_PRSNT_BUF_N")
	)
	(segment
		(start 4.653788 -180.128926)
		(end 5.163058 -180.638196)
		(width 0.2286)
		(layer "In2.Cu")
		(net "FAN_1_PRSNT_BUF_N")
	)
	(segment
		(start 43.071034 -258.538218)
		(end 40.338248 -258.538218)
		(width 0.2286)
		(layer "In2.Cu")
		(net "FAN_1_PRSNT_BUF_N")
	)
	(segment
		(start 4.953 -172.719746)
		(end 4.953 -176.276)
		(width 0.2286)
		(layer "In2.Cu")
		(net "FAN_1_PRSNT_BUF_N")
	)
	(segment
		(start 37.846 -217.043)
		(end 36.022788 -218.866212)
		(width 0.2286)
		(layer "In2.Cu")
		(net "FAN_1_PRSNT_BUF_N")
	)
	(segment
		(start 36.022788 -234.388914)
		(end 44.777152 -243.143278)
		(width 0.2286)
		(layer "In2.Cu")
		(net "FAN_1_PRSNT_BUF_N")
	)
	(segment
		(start 3.76682 -192.336928)
		(end 5.629656 -190.474092)
		(width 0.2286)
		(layer "In2.Cu")
		(net "FAN_1_PRSNT_BUF_N")
	)
	(segment
		(start 2.032 -169.798746)
		(end 4.953 -172.719746)
		(width 0.2286)
		(layer "In2.Cu")
		(net "FAN_1_PRSNT_BUF_N")
	)
	(segment
		(start 5.629656 -190.474092)
		(end 5.629656 -181.104794)
		(width 0.2286)
		(layer "In2.Cu")
		(net "FAN_1_PRSNT_BUF_N")
	)
	(segment
		(start 44.777152 -243.143278)
		(end 44.777152 -253.184406)
		(width 0.2286)
		(layer "In2.Cu")
		(net "FAN_1_PRSNT_BUF_N")
	)
	(segment
		(start 43.591988 -258.017264)
		(end 43.071034 -258.538218)
		(width 0.2286)
		(layer "In2.Cu")
		(net "FAN_1_PRSNT_BUF_N")
	)
	(segment
		(start 4.661662 -176.567338)
		(end 4.661662 -179.79771)
		(width 0.2286)
		(layer "In2.Cu")
		(net "FAN_1_PRSNT_BUF_N")
	)
	(segment
		(start 45.310806 -255.194562)
		(end 43.591988 -256.91338)
		(width 0.2286)
		(layer "In2.Cu")
		(net "FAN_1_PRSNT_BUF_N")
	)
	(segment
		(start 40.338248 -258.538218)
		(end 39.852346 -258.052316)
		(width 0.2286)
		(layer "In2.Cu")
		(net "FAN_1_PRSNT_BUF_N")
	)
	(segment
		(start 2.032 -165.48735)
		(end 2.032 -169.798746)
		(width 0.2286)
		(layer "In2.Cu")
		(net "FAN_1_PRSNT_BUF_N")
	)
	(segment
		(start 4.953 -176.276)
		(end 4.661662 -176.567338)
		(width 0.2286)
		(layer "In2.Cu")
		(net "FAN_1_PRSNT_BUF_N")
	)
	(segment
		(start 37.805106 -254.43815)
		(end 34.835846 -254.43815)
		(width 0.2286)
		(layer "In2.Cu")
		(net "FAN_1_PRSNT_BUF_N")
	)
	(segment
		(start 3.76682 -193.957956)
		(end 3.76682 -192.336928)
		(width 0.2286)
		(layer "In2.Cu")
		(net "FAN_1_PRSNT_BUF_N")
	)
	(segment
		(start 4.661662 -179.79771)
		(end 4.653788 -179.805584)
		(width 0.2286)
		(layer "In2.Cu")
		(net "FAN_1_PRSNT_BUF_N")
	)
	(segment
		(start 4.653788 -179.805584)
		(end 4.653788 -180.128926)
		(width 0.2286)
		(layer "In2.Cu")
		(net "FAN_1_PRSNT_BUF_N")
	)
	(segment
		(start 39.36111 -255.994154)
		(end 37.805106 -254.43815)
		(width 0.2286)
		(layer "In2.Cu")
		(net "FAN_1_PRSNT_BUF_N")
	)
	(segment
		(start 5.629656 -181.104794)
		(end 5.163058 -180.638196)
		(width 0.2286)
		(layer "In2.Cu")
		(net "FAN_1_PRSNT_BUF_N")
	)
	(segment
		(start 39.36111 -256.47269)
		(end 39.36111 -255.994154)
		(width 0.2286)
		(layer "In2.Cu")
		(net "FAN_1_PRSNT_BUF_N")
	)
	(segment
		(start 39.852346 -258.052316)
		(end 39.852346 -256.963926)
		(width 0.2286)
		(layer "In2.Cu")
		(net "FAN_1_PRSNT_BUF_N")
	)
	(segment
		(start 34.835846 -254.43815)
		(end 34.666428 -254.607568)
		(width 0.2286)
		(layer "In2.Cu")
		(net "FAN_1_PRSNT_BUF_N")
	)
	(segment
		(start 45.310806 -253.71806)
		(end 45.310806 -255.194562)
		(width 0.2286)
		(layer "In2.Cu")
		(net "FAN_1_PRSNT_BUF_N")
	)
	(segment
		(start 43.591988 -256.91338)
		(end 43.591988 -258.017264)
		(width 0.2286)
		(layer "In2.Cu")
		(net "FAN_1_PRSNT_BUF_N")
	)
	(segment
		(start 44.777152 -253.184406)
		(end 45.310806 -253.71806)
		(width 0.2286)
		(layer "In2.Cu")
		(net "FAN_1_PRSNT_BUF_N")
	)
	(segment
		(start 39.852346 -256.963926)
		(end 39.36111 -256.47269)
		(width 0.2286)
		(layer "In2.Cu")
		(net "FAN_1_PRSNT_BUF_N")
	)
	(segment
		(start 36.022788 -218.866212)
		(end 36.022788 -234.388914)
		(width 0.2286)
		(layer "In2.Cu")
		(net "FAN_1_PRSNT_BUF_N")
	)
	(segment
		(start 23.07209 -203.169266)
		(end 21.051266 -203.169266)
		(width 0.2794)
		(layer "F.Cu")
		(net "SMB_FAN6_SDA")
	)
	(segment
		(start 19.431 -201.549)
		(end 15.1384 -201.549)
		(width 0.2794)
		(layer "F.Cu")
		(net "SMB_FAN6_SDA")
	)
	(segment
		(start 26.67 -160.42005)
		(end 26.67 -160.909)
		(width 0.2794)
		(layer "F.Cu")
		(net "SMB_FAN6_SDA")
	)
	(segment
		(start 24.765 -201.476356)
		(end 23.07209 -203.169266)
		(width 0.2794)
		(layer "F.Cu")
		(net "SMB_FAN6_SDA")
	)
	(segment
		(start 24.765 -200.406)
		(end 24.765 -201.476356)
		(width 0.2794)
		(layer "F.Cu")
		(net "SMB_FAN6_SDA")
	)
	(segment
		(start 26.67 -160.909)
		(end 26.924 -161.163)
		(width 0.2794)
		(layer "F.Cu")
		(net "SMB_FAN6_SDA")
	)
	(segment
		(start 21.051266 -203.169266)
		(end 19.431 -201.549)
		(width 0.2794)
		(layer "F.Cu")
		(net "SMB_FAN6_SDA")
	)
	(segment
		(start 14.913356 -201.323956)
		(end 14.75105 -201.323956)
		(width 0.2794)
		(layer "F.Cu")
		(net "SMB_FAN6_SDA")
	)
	(segment
		(start 25.273 -199.898)
		(end 24.765 -200.406)
		(width 0.2794)
		(layer "F.Cu")
		(net "SMB_FAN6_SDA")
	)
	(segment
		(start 15.1384 -201.549)
		(end 14.913356 -201.323956)
		(width 0.2794)
		(layer "F.Cu")
		(net "SMB_FAN6_SDA")
	)
	(via
		(at 25.273 -199.898)
		(size 0.508)
		(drill 0.254)
		(layers "F.Cu" "B.Cu")
		(net "SMB_FAN6_SDA")
	)
	(via
		(at 26.924 -161.163)
		(size 0.508)
		(drill 0.254)
		(layers "F.Cu" "B.Cu")
		(net "SMB_FAN6_SDA")
	)
	(segment
		(start 26.4414 -195.95846)
		(end 26.4414 -184.563258)
		(width 0.2286)
		(layer "In2.Cu")
		(net "SMB_FAN6_SDA")
	)
	(segment
		(start 25.941782 -196.458078)
		(end 26.4414 -195.95846)
		(width 0.2286)
		(layer "In2.Cu")
		(net "SMB_FAN6_SDA")
	)
	(segment
		(start 26.4414 -184.563258)
		(end 28.546552 -182.458106)
		(width 0.2286)
		(layer "In2.Cu")
		(net "SMB_FAN6_SDA")
	)
	(segment
		(start 25.273 -199.898)
		(end 25.941782 -199.229218)
		(width 0.2286)
		(layer "In2.Cu")
		(net "SMB_FAN6_SDA")
	)
	(segment
		(start 28.546552 -163.701984)
		(end 26.924 -162.079432)
		(width 0.2286)
		(layer "In2.Cu")
		(net "SMB_FAN6_SDA")
	)
	(segment
		(start 28.546552 -182.458106)
		(end 28.546552 -163.701984)
		(width 0.2286)
		(layer "In2.Cu")
		(net "SMB_FAN6_SDA")
	)
	(segment
		(start 26.924 -162.079432)
		(end 26.924 -161.163)
		(width 0.2286)
		(layer "In2.Cu")
		(net "SMB_FAN6_SDA")
	)
	(segment
		(start 25.941782 -199.229218)
		(end 25.941782 -196.458078)
		(width 0.2286)
		(layer "In2.Cu")
		(net "SMB_FAN6_SDA")
	)
	(segment
		(start 12.7 -259.842)
		(end 12.7 -258.699)
		(width 0.2794)
		(layer "F.Cu")
		(net "FAN_7_P3V_R")
	)
	(segment
		(start 14.33195 -258.064)
		(end 14.33195 -259.08)
		(width 0.2794)
		(layer "F.Cu")
		(net "FAN_7_P3V_R")
	)
	(segment
		(start 12.7 -258.699)
		(end 13.335 -258.064)
		(width 0.2794)
		(layer "F.Cu")
		(net "FAN_7_P3V_R")
	)
	(segment
		(start 13.335 -258.064)
		(end 14.33195 -258.064)
		(width 0.2794)
		(layer "F.Cu")
		(net "FAN_7_P3V_R")
	)
	(via
		(at 12.7 -259.842)
		(size 0.762)
		(drill 0.254)
		(layers "F.Cu" "B.Cu")
		(net "FAN_7_P3V_R")
	)
	(segment
		(start 13.382244 -262.054848)
		(end 13.382244 -261.72287)
		(width 0.1016)
		(layer "B.Cu")
		(net "FAN_7_P3V_R")
	)
	(segment
		(start 12.7 -259.842)
		(end 12.7 -258.97205)
		(width 0.2794)
		(layer "B.Cu")
		(net "FAN_7_P3V_R")
	)
	(segment
		(start 13.382244 -261.72287)
		(end 12.93749 -260.64845)
		(width 0.1016)
		(layer "B.Cu")
		(net "FAN_7_P3V_R")
	)
	(segment
		(start 12.848336 -260.199886)
		(end 12.7 -259.842)
		(width 0.1016)
		(layer "B.Cu")
		(net "FAN_7_P3V_R")
	)
	(segment
		(start 12.93749 -260.64845)
		(end 12.848336 -260.199886)
		(width 0.1016)
		(layer "B.Cu")
		(net "FAN_7_P3V_R")
	)
	(segment
		(start 4.228084 -213.9442)
		(end 19.800062 -213.9442)
		(width 0.2794)
		(layer "F.Cu")
		(net "FAN_0_PRSNT_BUF_N")
	)
	(segment
		(start 3.994658 -180.524658)
		(end 3.994658 -180.342286)
		(width 0.2794)
		(layer "F.Cu")
		(net "FAN_0_PRSNT_BUF_N")
	)
	(segment
		(start 3.154426 -212.870542)
		(end 4.228084 -213.9442)
		(width 0.2794)
		(layer "F.Cu")
		(net "FAN_0_PRSNT_BUF_N")
	)
	(segment
		(start 29.247338 -217.043)
		(end 37.084 -217.043)
		(width 0.2794)
		(layer "F.Cu")
		(net "FAN_0_PRSNT_BUF_N")
	)
	(segment
		(start 3.048 -162.814)
		(end 3.79095 -162.814)
		(width 0.2794)
		(layer "F.Cu")
		(net "FAN_0_PRSNT_BUF_N")
	)
	(segment
		(start 20.689062 -213.0552)
		(end 25.259538 -213.0552)
		(width 0.2794)
		(layer "F.Cu")
		(net "FAN_0_PRSNT_BUF_N")
	)
	(segment
		(start 3.154426 -194.376294)
		(end 3.154426 -212.870542)
		(width 0.2794)
		(layer "F.Cu")
		(net "FAN_0_PRSNT_BUF_N")
	)
	(segment
		(start 7.366 -181.584092)
		(end 5.054092 -181.584092)
		(width 0.2794)
		(layer "F.Cu")
		(net "FAN_0_PRSNT_BUF_N")
	)
	(segment
		(start 3.994658 -180.342286)
		(end 3.991102 -180.342286)
		(width 0.2794)
		(layer "F.Cu")
		(net "FAN_0_PRSNT_BUF_N")
	)
	(segment
		(start 19.800062 -213.9442)
		(end 20.689062 -213.0552)
		(width 0.2794)
		(layer "F.Cu")
		(net "FAN_0_PRSNT_BUF_N")
	)
	(segment
		(start 25.259538 -213.0552)
		(end 29.247338 -217.043)
		(width 0.2794)
		(layer "F.Cu")
		(net "FAN_0_PRSNT_BUF_N")
	)
	(segment
		(start 5.054092 -181.584092)
		(end 3.994658 -180.524658)
		(width 0.2794)
		(layer "F.Cu")
		(net "FAN_0_PRSNT_BUF_N")
	)
	(via
		(at 3.154426 -194.376294)
		(size 0.508)
		(drill 0.254)
		(layers "F.Cu" "B.Cu")
		(net "FAN_0_PRSNT_BUF_N")
	)
	(via
		(at 3.991102 -180.342286)
		(size 0.508)
		(drill 0.254)
		(layers "F.Cu" "B.Cu")
		(net "FAN_0_PRSNT_BUF_N")
	)
	(via
		(at 3.048 -162.814)
		(size 0.508)
		(drill 0.254)
		(layers "F.Cu" "B.Cu")
		(net "FAN_0_PRSNT_BUF_N")
	)
	(via
		(at 44.667932 -254.192278)
		(size 0.508)
		(drill 0.254)
		(layers "F.Cu" "B.Cu")
		(net "FAN_0_PRSNT_BUF_N")
	)
	(via
		(at 37.084 -217.043)
		(size 0.508)
		(drill 0.254)
		(layers "F.Cu" "B.Cu")
		(net "FAN_0_PRSNT_BUF_N")
	)
	(segment
		(start 44.667932 -254.192278)
		(end 44.667932 -254.878078)
		(width 0.2794)
		(layer "B.Cu")
		(net "FAN_0_PRSNT_BUF_N")
	)
	(segment
		(start 3.994658 -180.342286)
		(end 3.994658 -176.091342)
		(width 0.2286)
		(layer "In2.Cu")
		(net "FAN_0_PRSNT_BUF_N")
	)
	(segment
		(start 35.489388 -218.637612)
		(end 37.084 -217.043)
		(width 0.2286)
		(layer "In2.Cu")
		(net "FAN_0_PRSNT_BUF_N")
	)
	(segment
		(start 44.20489 -243.373402)
		(end 35.489388 -234.6579)
		(width 0.2286)
		(layer "In2.Cu")
		(net "FAN_0_PRSNT_BUF_N")
	)
	(segment
		(start 4.318 -172.847254)
		(end 1.4986 -170.027854)
		(width 0.2286)
		(layer "In2.Cu")
		(net "FAN_0_PRSNT_BUF_N")
	)
	(segment
		(start 1.4986 -170.027854)
		(end 1.4986 -164.3634)
		(width 0.2286)
		(layer "In2.Cu")
		(net "FAN_0_PRSNT_BUF_N")
	)
	(segment
		(start 35.489388 -234.6579)
		(end 35.489388 -218.637612)
		(width 0.2286)
		(layer "In2.Cu")
		(net "FAN_0_PRSNT_BUF_N")
	)
	(segment
		(start 3.154426 -194.376294)
		(end 3.154426 -192.194942)
		(width 0.2286)
		(layer "In2.Cu")
		(net "FAN_0_PRSNT_BUF_N")
	)
	(segment
		(start 5.096256 -190.253112)
		(end 5.096256 -181.44744)
		(width 0.2286)
		(layer "In2.Cu")
		(net "FAN_0_PRSNT_BUF_N")
	)
	(segment
		(start 44.20489 -253.729236)
		(end 44.20489 -243.373402)
		(width 0.2286)
		(layer "In2.Cu")
		(net "FAN_0_PRSNT_BUF_N")
	)
	(segment
		(start 3.154426 -192.194942)
		(end 5.096256 -190.253112)
		(width 0.2286)
		(layer "In2.Cu")
		(net "FAN_0_PRSNT_BUF_N")
	)
	(segment
		(start 3.991102 -180.342286)
		(end 3.994658 -180.342286)
		(width 0.2286)
		(layer "In2.Cu")
		(net "FAN_0_PRSNT_BUF_N")
	)
	(segment
		(start 3.994658 -176.091342)
		(end 4.318 -175.768)
		(width 0.2286)
		(layer "In2.Cu")
		(net "FAN_0_PRSNT_BUF_N")
	)
	(segment
		(start 4.318 -175.768)
		(end 4.318 -172.847254)
		(width 0.2286)
		(layer "In2.Cu")
		(net "FAN_0_PRSNT_BUF_N")
	)
	(segment
		(start 5.096256 -181.44744)
		(end 3.991102 -180.342286)
		(width 0.2286)
		(layer "In2.Cu")
		(net "FAN_0_PRSNT_BUF_N")
	)
	(segment
		(start 1.4986 -164.3634)
		(end 3.048 -162.814)
		(width 0.2286)
		(layer "In2.Cu")
		(net "FAN_0_PRSNT_BUF_N")
	)
	(segment
		(start 44.667932 -254.192278)
		(end 44.20489 -253.729236)
		(width 0.2286)
		(layer "In2.Cu")
		(net "FAN_0_PRSNT_BUF_N")
	)
	(segment
		(start 16.129 -258.97205)
		(end 16.129 -259.863336)
		(width 0.2794)
		(layer "F.Cu")
		(net "FAN_7_FAULT")
	)
	(segment
		(start 16.129 -259.863336)
		(end 15.875 -260.477)
		(width 0.2794)
		(layer "F.Cu")
		(net "FAN_7_FAULT")
	)
	(via
		(at 15.875 -260.477)
		(size 0.508)
		(drill 0.254)
		(layers "F.Cu" "B.Cu")
		(net "FAN_7_FAULT")
	)
	(segment
		(start 15.621 -260.89483)
		(end 15.38224 -261.471664)
		(width 0.1016)
		(layer "B.Cu")
		(net "FAN_7_FAULT")
	)
	(segment
		(start 15.38224 -261.471664)
		(end 15.38224 -262.054848)
		(width 0.1016)
		(layer "B.Cu")
		(net "FAN_7_FAULT")
	)
	(segment
		(start 15.621 -260.731)
		(end 15.621 -260.89483)
		(width 0.2794)
		(layer "B.Cu")
		(net "FAN_7_FAULT")
	)
	(segment
		(start 15.875 -260.477)
		(end 15.621 -260.731)
		(width 0.2794)
		(layer "B.Cu")
		(net "FAN_7_FAULT")
	)
	(segment
		(start 3.146806 -165.991286)
		(end 2.08915 -164.93363)
		(width 0.2794)
		(layer "F.Cu")
		(net "FAN_2_PRSNT_BUF_N")
	)
	(segment
		(start 3.79095 -166.116)
		(end 3.27152 -166.116)
		(width 0.2794)
		(layer "F.Cu")
		(net "FAN_2_PRSNT_BUF_N")
	)
	(segment
		(start 29.242004 -140.452602)
		(end 29.416756 -140.27785)
		(width 0.2794)
		(layer "F.Cu")
		(net "FAN_2_PRSNT_BUF_N")
	)
	(segment
		(start 35.692842 -140.27785)
		(end 36.130992 -140.716)
		(width 0.2794)
		(layer "F.Cu")
		(net "FAN_2_PRSNT_BUF_N")
	)
	(segment
		(start 5.635244 -180.28412)
		(end 7.366 -180.28412)
		(width 0.2794)
		(layer "F.Cu")
		(net "FAN_2_PRSNT_BUF_N")
	)
	(segment
		(start 5.195062 -179.843938)
		(end 5.635244 -180.28412)
		(width 0.2794)
		(layer "F.Cu")
		(net "FAN_2_PRSNT_BUF_N")
	)
	(segment
		(start 3.5814 -140.0048)
		(end 23.927054 -140.0048)
		(width 0.2794)
		(layer "F.Cu")
		(net "FAN_2_PRSNT_BUF_N")
	)
	(segment
		(start 2.08915 -141.49705)
		(end 3.5814 -140.0048)
		(width 0.2794)
		(layer "F.Cu")
		(net "FAN_2_PRSNT_BUF_N")
	)
	(segment
		(start 2.08915 -164.93363)
		(end 2.08915 -141.49705)
		(width 0.2794)
		(layer "F.Cu")
		(net "FAN_2_PRSNT_BUF_N")
	)
	(segment
		(start 23.927054 -140.0048)
		(end 24.374856 -140.452602)
		(width 0.2794)
		(layer "F.Cu")
		(net "FAN_2_PRSNT_BUF_N")
	)
	(segment
		(start 44.958 -140.716)
		(end 48.0695 -137.6045)
		(width 0.2794)
		(layer "F.Cu")
		(net "FAN_2_PRSNT_BUF_N")
	)
	(segment
		(start 29.416756 -140.27785)
		(end 35.692842 -140.27785)
		(width 0.2794)
		(layer "F.Cu")
		(net "FAN_2_PRSNT_BUF_N")
	)
	(segment
		(start 3.27152 -166.116)
		(end 3.146806 -165.991286)
		(width 0.2794)
		(layer "F.Cu")
		(net "FAN_2_PRSNT_BUF_N")
	)
	(segment
		(start 36.130992 -140.716)
		(end 44.958 -140.716)
		(width 0.2794)
		(layer "F.Cu")
		(net "FAN_2_PRSNT_BUF_N")
	)
	(segment
		(start 24.374856 -140.452602)
		(end 29.242004 -140.452602)
		(width 0.2794)
		(layer "F.Cu")
		(net "FAN_2_PRSNT_BUF_N")
	)
	(via
		(at 3.146806 -165.991286)
		(size 0.508)
		(drill 0.254)
		(layers "F.Cu" "B.Cu")
		(net "FAN_2_PRSNT_BUF_N")
	)
	(via
		(at 48.0695 -137.6045)
		(size 0.508)
		(drill 0.254)
		(layers "F.Cu" "B.Cu")
		(net "FAN_2_PRSNT_BUF_N")
	)
	(via
		(at 44.667932 -69.59219)
		(size 0.508)
		(drill 0.254)
		(layers "F.Cu" "B.Cu")
		(net "FAN_2_PRSNT_BUF_N")
	)
	(via
		(at 5.195062 -179.843938)
		(size 0.508)
		(drill 0.254)
		(layers "F.Cu" "B.Cu")
		(net "FAN_2_PRSNT_BUF_N")
	)
	(segment
		(start 44.667932 -70.27799)
		(end 44.667932 -69.59219)
		(width 0.2794)
		(layer "B.Cu")
		(net "FAN_2_PRSNT_BUF_N")
	)
	(segment
		(start 46.7106 -70.7136)
		(end 45.789342 -70.7136)
		(width 0.2286)
		(layer "In2.Cu")
		(net "FAN_2_PRSNT_BUF_N")
	)
	(segment
		(start 47.27448 -133.83768)
		(end 47.27448 -123.92152)
		(width 0.2286)
		(layer "In2.Cu")
		(net "FAN_2_PRSNT_BUF_N")
	)
	(segment
		(start 47.5996 -134.1628)
		(end 47.27448 -133.83768)
		(width 0.2286)
		(layer "In2.Cu")
		(net "FAN_2_PRSNT_BUF_N")
	)
	(segment
		(start 47.5996 -137.1346)
		(end 47.5996 -134.1628)
		(width 0.2286)
		(layer "In2.Cu")
		(net "FAN_2_PRSNT_BUF_N")
	)
	(segment
		(start 5.588 -172.465746)
		(end 5.588 -179.451)
		(width 0.2286)
		(layer "In2.Cu")
		(net "FAN_2_PRSNT_BUF_N")
	)
	(segment
		(start 2.667 -166.471092)
		(end 2.667 -169.544746)
		(width 0.2286)
		(layer "In2.Cu")
		(net "FAN_2_PRSNT_BUF_N")
	)
	(segment
		(start 48.0695 -137.6045)
		(end 47.5996 -137.1346)
		(width 0.2286)
		(layer "In2.Cu")
		(net "FAN_2_PRSNT_BUF_N")
	)
	(segment
		(start 48.690276 -72.693276)
		(end 46.7106 -70.7136)
		(width 0.2286)
		(layer "In2.Cu")
		(net "FAN_2_PRSNT_BUF_N")
	)
	(segment
		(start 2.667 -169.544746)
		(end 5.588 -172.465746)
		(width 0.2286)
		(layer "In2.Cu")
		(net "FAN_2_PRSNT_BUF_N")
	)
	(segment
		(start 47.27448 -123.92152)
		(end 48.690276 -122.505724)
		(width 0.2286)
		(layer "In2.Cu")
		(net "FAN_2_PRSNT_BUF_N")
	)
	(segment
		(start 3.146806 -165.991286)
		(end 2.667 -166.471092)
		(width 0.2286)
		(layer "In2.Cu")
		(net "FAN_2_PRSNT_BUF_N")
	)
	(segment
		(start 5.588 -179.451)
		(end 5.195062 -179.843938)
		(width 0.2286)
		(layer "In2.Cu")
		(net "FAN_2_PRSNT_BUF_N")
	)
	(segment
		(start 45.789342 -70.7136)
		(end 44.667932 -69.59219)
		(width 0.2286)
		(layer "In2.Cu")
		(net "FAN_2_PRSNT_BUF_N")
	)
	(segment
		(start 48.690276 -122.505724)
		(end 48.690276 -72.693276)
		(width 0.2286)
		(layer "In2.Cu")
		(net "FAN_2_PRSNT_BUF_N")
	)
	(segment
		(start 28.68295 -21.5138)
		(end 29.14015 -21.971)
		(width 0.4572)
		(layer "F.Cu")
		(net "P3V3_AUX")
	)
	(segment
		(start 29.21 -107.58805)
		(end 30.74035 -107.58805)
		(width 0.4572)
		(layer "F.Cu")
		(net "P3V3_AUX")
	)
	(segment
		(start 31.122366 -21.24075)
		(end 31.122366 -19.714718)
		(width 0.4572)
		(layer "F.Cu")
		(net "P3V3_AUX")
	)
	(segment
		(start 15.804134 -185.222134)
		(end 17.958816 -185.222134)
		(width 0.4572)
		(layer "F.Cu")
		(net "P3V3_AUX")
	)
	(segment
		(start 22.225 -126.492)
		(end 22.154896 -126.562104)
		(width 0.1778)
		(layer "F.Cu")
		(net "P3V3_AUX")
	)
	(segment
		(start 22.87905 -28.59405)
		(end 22.07895 -27.79395)
		(width 0.4572)
		(layer "F.Cu")
		(net "P3V3_AUX")
	)
	(segment
		(start 7.97814 -173.5709)
		(end 8.32104 -173.228)
		(width 0.4572)
		(layer "F.Cu")
		(net "P3V3_AUX")
	)
	(segment
		(start 30.113986 -17.348454)
		(end 30.113986 -18.10004)
		(width 0.4572)
		(layer "F.Cu")
		(net "P3V3_AUX")
	)
	(segment
		(start 5.17525 -131.79425)
		(end 4.889754 -132.08)
		(width 0.4572)
		(layer "F.Cu")
		(net "P3V3_AUX")
	)
	(segment
		(start 27.813 -101.70795)
		(end 27.178 -101.70795)
		(width 0.4572)
		(layer "F.Cu")
		(net "P3V3_AUX")
	)
	(segment
		(start 32.131 -163.34105)
		(end 30.734 -163.34105)
		(width 0.4572)
		(layer "F.Cu")
		(net "P3V3_AUX")
	)
	(segment
		(start 19.431 -298.85005)
		(end 20.092924 -298.85005)
		(width 0.4572)
		(layer "F.Cu")
		(net "P3V3_AUX")
	)
	(segment
		(start 29.95295 -179.05095)
		(end 30.353 -179.451)
		(width 0.4572)
		(layer "F.Cu")
		(net "P3V3_AUX")
	)
	(segment
		(start 44.009056 -167.561006)
		(end 44.655994 -167.561006)
		(width 0.4572)
		(layer "F.Cu")
		(net "P3V3_AUX")
	)
	(segment
		(start 22.479 -205.84795)
		(end 25.09139 -205.84795)
		(width 0.4572)
		(layer "F.Cu")
		(net "P3V3_AUX")
	)
	(segment
		(start 34.229294 -252.494796)
		(end 33.916366 -252.807724)
		(width 0.4572)
		(layer "F.Cu")
		(net "P3V3_AUX")
	)
	(segment
		(start 28.1432 -104.775)
		(end 29.493972 -104.775)
		(width 0.4572)
		(layer "F.Cu")
		(net "P3V3_AUX")
	)
	(segment
		(start 29.95295 -182.372)
		(end 29.95295 -182.13705)
		(width 0.4572)
		(layer "F.Cu")
		(net "P3V3_AUX")
	)
	(segment
		(start 3.40995 -182.626)
		(end 2.8702 -182.626)
		(width 0.4572)
		(layer "F.Cu")
		(net "P3V3_AUX")
	)
	(segment
		(start 27.31008 -113.03)
		(end 28.067 -113.03)
		(width 0.4572)
		(layer "F.Cu")
		(net "P3V3_AUX")
	)
	(segment
		(start 10.548874 -256.413)
		(end 10.406888 -256.554986)
		(width 0.4572)
		(layer "F.Cu")
		(net "P3V3_AUX")
	)
	(segment
		(start 19.05 -145.64995)
		(end 19.05 -145.279872)
		(width 0.4572)
		(layer "F.Cu")
		(net "P3V3_AUX")
	)
	(segment
		(start 19.939 -154.53995)
		(end 19.939 -154.2796)
		(width 0.4572)
		(layer "F.Cu")
		(net "P3V3_AUX")
	)
	(segment
		(start 21.829014 -26.60396)
		(end 21.216112 -26.60396)
		(width 0.4572)
		(layer "F.Cu")
		(net "P3V3_AUX")
	)
	(segment
		(start 6.07695 -169.291)
		(end 5.46735 -169.291)
		(width 0.4572)
		(layer "F.Cu")
		(net "P3V3_AUX")
	)
	(segment
		(start 13.73505 -164.338)
		(end 14.34465 -164.338)
		(width 0.4572)
		(layer "F.Cu")
		(net "P3V3_AUX")
	)
	(segment
		(start 26.6446 -107.5944)
		(end 26.6446 -106.8324)
		(width 0.4572)
		(layer "F.Cu")
		(net "P3V3_AUX")
	)
	(segment
		(start 21.717 -117.647974)
		(end 21.829014 -117.53596)
		(width 0.4572)
		(layer "F.Cu")
		(net "P3V3_AUX")
	)
	(segment
		(start 41.63695 -191.516)
		(end 41.554908 -191.433958)
		(width 0.3556)
		(layer "F.Cu")
		(net "P3V3_AUX")
	)
	(segment
		(start 6.477 -171.5389)
		(end 9.6139 -171.5389)
		(width 0.4572)
		(layer "F.Cu")
		(net "P3V3_AUX")
	)
	(segment
		(start 34.666428 -67.094862)
		(end 34.229294 -67.094862)
		(width 0.4572)
		(layer "F.Cu")
		(net "P3V3_AUX")
	)
	(segment
		(start 45.105066 -256.30505)
		(end 45.417994 -255.992122)
		(width 0.4572)
		(layer "F.Cu")
		(net "P3V3_AUX")
	)
	(segment
		(start 21.822918 -14.29385)
		(end 23.241 -14.29385)
		(width 0.254)
		(layer "F.Cu")
		(net "P3V3_AUX")
	)
	(segment
		(start 23.26005 -23.368)
		(end 23.537418 -23.368)
		(width 0.4572)
		(layer "F.Cu")
		(net "P3V3_AUX")
	)
	(segment
		(start 44.191936 -134.361936)
		(end 44.191936 -133.622034)
		(width 0.2794)
		(layer "F.Cu")
		(net "P3V3_AUX")
	)
	(segment
		(start 30.296104 -131.501896)
		(end 30.296104 -131.158996)
		(width 0.1778)
		(layer "F.Cu")
		(net "P3V3_AUX")
	)
	(segment
		(start 32.258 -198.35495)
		(end 32.616394 -198.35495)
		(width 0.4572)
		(layer "F.Cu")
		(net "P3V3_AUX")
	)
	(segment
		(start 21.95195 -303.12995)
		(end 22.75205 -303.93005)
		(width 0.4572)
		(layer "F.Cu")
		(net "P3V3_AUX")
	)
	(segment
		(start 19.05 -145.279872)
		(end 18.731738 -144.96161)
		(width 0.4572)
		(layer "F.Cu")
		(net "P3V3_AUX")
	)
	(segment
		(start 43.96105 -165.481)
		(end 44.577 -165.481)
		(width 0.4572)
		(layer "F.Cu")
		(net "P3V3_AUX")
	)
	(segment
		(start 34.417 -140.95095)
		(end 35.41395 -140.95095)
		(width 0.4572)
		(layer "F.Cu")
		(net "P3V3_AUX")
	)
	(segment
		(start 21.3487 -141.20495)
		(end 20.32 -141.20495)
		(width 0.4572)
		(layer "F.Cu")
		(net "P3V3_AUX")
	)
	(segment
		(start 39.116 -183.559958)
		(end 40.176958 -183.559958)
		(width 0.3556)
		(layer "F.Cu")
		(net "P3V3_AUX")
	)
	(segment
		(start 42.926 -135.90905)
		(end 42.291 -135.90905)
		(width 0.4572)
		(layer "F.Cu")
		(net "P3V3_AUX")
	)
	(segment
		(start 28.829 -102.50805)
		(end 29.0068 -102.50805)
		(width 0.4572)
		(layer "F.Cu")
		(net "P3V3_AUX")
	)
	(segment
		(start 48.133 -130.048)
		(end 48.66005 -130.57505)
		(width 0.4572)
		(layer "F.Cu")
		(net "P3V3_AUX")
	)
	(segment
		(start 22.479 -167.0812)
		(end 22.479 -169.291)
		(width 0.4572)
		(layer "F.Cu")
		(net "P3V3_AUX")
	)
	(segment
		(start 8.95604 -170.053)
		(end 8.32104 -170.053)
		(width 0.4572)
		(layer "F.Cu")
		(net "P3V3_AUX")
	)
	(segment
		(start 18.796 -154.53995)
		(end 19.939 -154.53995)
		(width 0.4572)
		(layer "F.Cu")
		(net "P3V3_AUX")
	)
	(segment
		(start 39.497254 -185.166)
		(end 38.62705 -185.166)
		(width 0.4572)
		(layer "F.Cu")
		(net "P3V3_AUX")
	)
	(segment
		(start 32.258 -290.93795)
		(end 32.258 -290.322)
		(width 0.4572)
		(layer "F.Cu")
		(net "P3V3_AUX")
	)
	(segment
		(start 29.688536 -141.228064)
		(end 29.942536 -140.974064)
		(width 0.4572)
		(layer "F.Cu")
		(net "P3V3_AUX")
	)
	(segment
		(start 18.542 -256.667)
		(end 17.395444 -256.667)
		(width 0.4572)
		(layer "F.Cu")
		(net "P3V3_AUX")
	)
	(segment
		(start 31.322518 -104.855518)
		(end 30.306518 -104.855518)
		(width 0.4572)
		(layer "F.Cu")
		(net "P3V3_AUX")
	)
	(segment
		(start 36.16706 -159.275018)
		(end 36.16706 -162.64382)
		(width 0.4572)
		(layer "F.Cu")
		(net "P3V3_AUX")
	)
	(segment
		(start 30.74035 -107.58805)
		(end 32.04845 -106.27995)
		(width 0.4572)
		(layer "F.Cu")
		(net "P3V3_AUX")
	)
	(segment
		(start 30.099 -287.42005)
		(end 29.986986 -287.532064)
		(width 0.4572)
		(layer "F.Cu")
		(net "P3V3_AUX")
	)
	(segment
		(start 29.567378 -195.21805)
		(end 29.845 -195.21805)
		(width 0.4572)
		(layer "F.Cu")
		(net "P3V3_AUX")
	)
	(segment
		(start 15.621 -185.039)
		(end 15.804134 -185.222134)
		(width 0.4572)
		(layer "F.Cu")
		(net "P3V3_AUX")
	)
	(segment
		(start 23.956264 -23.786846)
		(end 26.409904 -23.786846)
		(width 0.4572)
		(layer "F.Cu")
		(net "P3V3_AUX")
	)
	(segment
		(start 31.60395 -110.49)
		(end 31.067502 -110.49)
		(width 0.4572)
		(layer "F.Cu")
		(net "P3V3_AUX")
	)
	(segment
		(start 32.616394 -198.35495)
		(end 32.83839 -198.576946)
		(width 0.4572)
		(layer "F.Cu")
		(net "P3V3_AUX")
	)
	(segment
		(start 21.829014 -117.53596)
		(end 22.966934 -116.39804)
		(width 0.4572)
		(layer "F.Cu")
		(net "P3V3_AUX")
	)
	(segment
		(start 20.512024 -118.171976)
		(end 20.2692 -117.929152)
		(width 0.4572)
		(layer "F.Cu")
		(net "P3V3_AUX")
	)
	(segment
		(start 19.558 -110.63605)
		(end 20.486878 -110.63605)
		(width 0.4572)
		(layer "F.Cu")
		(net "P3V3_AUX")
	)
	(segment
		(start 3.40995 -183.642)
		(end 3.40995 -182.626)
		(width 0.4572)
		(layer "F.Cu")
		(net "P3V3_AUX")
	)
	(segment
		(start 22.225 -123.71705)
		(end 21.48205 -123.71705)
		(width 0.4572)
		(layer "F.Cu")
		(net "P3V3_AUX")
	)
	(segment
		(start 26.162 -106.807)
		(end 26.6192 -106.807)
		(width 0.4572)
		(layer "F.Cu")
		(net "P3V3_AUX")
	)
	(segment
		(start 22.07895 -27.79395)
		(end 21.717 -27.79395)
		(width 0.4572)
		(layer "F.Cu")
		(net "P3V3_AUX")
	)
	(segment
		(start 5.715 -163.957)
		(end 5.334 -163.576)
		(width 0.4572)
		(layer "F.Cu")
		(net "P3V3_AUX")
	)
	(segment
		(start 25.790652 -16.373602)
		(end 27.051 -15.113254)
		(width 0.4572)
		(layer "F.Cu")
		(net "P3V3_AUX")
	)
	(segment
		(start 27.686 -106.172)
		(end 27.686 -105.2322)
		(width 0.4572)
		(layer "F.Cu")
		(net "P3V3_AUX")
	)
	(segment
		(start 42.43705 -179.324)
		(end 43.04665 -179.324)
		(width 0.4572)
		(layer "F.Cu")
		(net "P3V3_AUX")
	)
	(segment
		(start 38.806882 -256.413)
		(end 38.183312 -256.413)
		(width 0.4572)
		(layer "F.Cu")
		(net "P3V3_AUX")
	)
	(segment
		(start 23.495 -163.34105)
		(end 25.019 -163.34105)
		(width 0.4572)
		(layer "F.Cu")
		(net "P3V3_AUX")
	)
	(segment
		(start 41.63695 -192.151)
		(end 41.63695 -191.516)
		(width 0.4572)
		(layer "F.Cu")
		(net "P3V3_AUX")
	)
	(segment
		(start 4.21005 -132.62483)
		(end 4.21005 -132.08)
		(width 0.4572)
		(layer "F.Cu")
		(net "P3V3_AUX")
	)
	(segment
		(start 44.831 -135.10895)
		(end 44.649136 -135.10895)
		(width 0.4572)
		(layer "F.Cu")
		(net "P3V3_AUX")
	)
	(segment
		(start 40.386 -183.769)
		(end 40.386 -184.277)
		(width 0.3556)
		(layer "F.Cu")
		(net "P3V3_AUX")
	)
	(segment
		(start 6.07695 -163.957)
		(end 5.715 -163.957)
		(width 0.4572)
		(layer "F.Cu")
		(net "P3V3_AUX")
	)
	(segment
		(start 11.95705 -183.53405)
		(end 13.208 -183.53405)
		(width 0.3556)
		(layer "F.Cu")
		(net "P3V3_AUX")
	)
	(segment
		(start 36.16706 -162.64382)
		(end 35.46983 -163.34105)
		(width 0.4572)
		(layer "F.Cu")
		(net "P3V3_AUX")
	)
	(segment
		(start 9.733534 -251.587)
		(end 9.87552 -251.445014)
		(width 0.4572)
		(layer "F.Cu")
		(net "P3V3_AUX")
	)
	(segment
		(start 35.58794 -157.877256)
		(end 36.16706 -159.275018)
		(width 0.4572)
		(layer "F.Cu")
		(net "P3V3_AUX")
	)
	(segment
		(start 13.73505 -162.814)
		(end 14.34465 -162.814)
		(width 0.4572)
		(layer "F.Cu")
		(net "P3V3_AUX")
	)
	(segment
		(start 25.12695 -130.81)
		(end 25.12695 -131.445)
		(width 0.4572)
		(layer "F.Cu")
		(net "P3V3_AUX")
	)
	(segment
		(start 8.95604 -164.084)
		(end 8.193532 -164.084)
		(width 0.4572)
		(layer "F.Cu")
		(net "P3V3_AUX")
	)
	(segment
		(start 3.40995 -129.794)
		(end 2.794 -129.794)
		(width 0.4572)
		(layer "F.Cu")
		(net "P3V3_AUX")
	)
	(segment
		(start 21.18995 -154.13355)
		(end 21.18995 -154.94)
		(width 0.3556)
		(layer "F.Cu")
		(net "P3V3_AUX")
	)
	(segment
		(start 22.479 -169.291)
		(end 22.987 -169.799)
		(width 0.4572)
		(layer "F.Cu")
		(net "P3V3_AUX")
	)
	(segment
		(start 19.558 -24.945848)
		(end 19.558 -22.87905)
		(width 0.4572)
		(layer "F.Cu")
		(net "P3V3_AUX")
	)
	(segment
		(start 28.522676 -191.590676)
		(end 28.522676 -193.101468)
		(width 0.4572)
		(layer "F.Cu")
		(net "P3V3_AUX")
	)
	(segment
		(start 13.73505 -166.116)
		(end 14.34465 -166.116)
		(width 0.4572)
		(layer "F.Cu")
		(net "P3V3_AUX")
	)
	(segment
		(start 26.89225 -101.70795)
		(end 25.527 -103.0732)
		(width 0.4572)
		(layer "F.Cu")
		(net "P3V3_AUX")
	)
	(segment
		(start 21.717 -210.92795)
		(end 21.829014 -210.815936)
		(width 0.4572)
		(layer "F.Cu")
		(net "P3V3_AUX")
	)
	(segment
		(start 27.686 -121.51995)
		(end 25.6921 -119.52605)
		(width 0.4572)
		(layer "F.Cu")
		(net "P3V3_AUX")
	)
	(segment
		(start 21.95195 -118.72595)
		(end 22.75205 -119.52605)
		(width 0.4572)
		(layer "F.Cu")
		(net "P3V3_AUX")
	)
	(segment
		(start 14.065504 -183.53405)
		(end 15.570454 -185.039)
		(width 0.4572)
		(layer "F.Cu")
		(net "P3V3_AUX")
	)
	(segment
		(start 23.241 -28.59405)
		(end 22.87905 -28.59405)
		(width 0.4572)
		(layer "F.Cu")
		(net "P3V3_AUX")
	)
	(segment
		(start 41.041574 -252.900942)
		(end 44.443396 -252.900942)
		(width 0.4572)
		(layer "F.Cu")
		(net "P3V3_AUX")
	)
	(segment
		(start 13.73505 -167.64)
		(end 14.34465 -167.64)
		(width 0.4572)
		(layer "F.Cu")
		(net "P3V3_AUX")
	)
	(segment
		(start 30.392116 -21.971)
		(end 31.122366 -21.24075)
		(width 0.4572)
		(layer "F.Cu")
		(net "P3V3_AUX")
	)
	(segment
		(start 9.109964 -66.986912)
		(end 9.733534 -66.986912)
		(width 0.4572)
		(layer "F.Cu")
		(net "P3V3_AUX")
	)
	(segment
		(start 20.483068 -115.057682)
		(end 19.581368 -115.057682)
		(width 0.4572)
		(layer "F.Cu")
		(net "P3V3_AUX")
	)
	(segment
		(start 30.353 -179.451)
		(end 30.353 -179.705)
		(width 0.4572)
		(layer "F.Cu")
		(net "P3V3_AUX")
	)
	(segment
		(start 32.258 -18.14195)
		(end 31.73095 -18.14195)
		(width 0.4572)
		(layer "F.Cu")
		(net "P3V3_AUX")
	)
	(segment
		(start 18.01495 -185.928)
		(end 18.01495 -185.166)
		(width 0.4572)
		(layer "F.Cu")
		(net "P3V3_AUX")
	)
	(segment
		(start 2.413 -182.1688)
		(end 2.413 -180.721)
		(width 0.4572)
		(layer "F.Cu")
		(net "P3V3_AUX")
	)
	(segment
		(start 36.322 -141.859)
		(end 36.322 -143.369284)
		(width 0.4572)
		(layer "F.Cu")
		(net "P3V3_AUX")
	)
	(segment
		(start 21.34235 -114.7826)
		(end 20.75815 -114.7826)
		(width 0.4572)
		(layer "F.Cu")
		(net "P3V3_AUX")
	)
	(segment
		(start 43.96105 -167.513)
		(end 44.009056 -167.561006)
		(width 0.4572)
		(layer "F.Cu")
		(net "P3V3_AUX")
	)
	(segment
		(start 9.54405 -184.785)
		(end 9.54405 -184.33415)
		(width 0.4572)
		(layer "F.Cu")
		(net "P3V3_AUX")
	)
	(segment
		(start 33.25495 -166.624)
		(end 22.9362 -166.624)
		(width 0.4572)
		(layer "F.Cu")
		(net "P3V3_AUX")
	)
	(segment
		(start 44.667932 -256.30505)
		(end 45.105066 -256.30505)
		(width 0.4572)
		(layer "F.Cu")
		(net "P3V3_AUX")
	)
	(segment
		(start 44.667932 -71.704962)
		(end 45.105066 -71.704962)
		(width 0.4572)
		(layer "F.Cu")
		(net "P3V3_AUX")
	)
	(segment
		(start 30.113986 -18.706338)
		(end 30.113986 -18.10004)
		(width 0.4572)
		(layer "F.Cu")
		(net "P3V3_AUX")
	)
	(segment
		(start 32.258 -201.422)
		(end 32.639 -201.041)
		(width 0.4572)
		(layer "F.Cu")
		(net "P3V3_AUX")
	)
	(segment
		(start 3.248914 -66.294)
		(end 3.248914 -67.094862)
		(width 0.4572)
		(layer "F.Cu")
		(net "P3V3_AUX")
	)
	(segment
		(start 26.6446 -106.8324)
		(end 26.6192 -106.807)
		(width 0.4572)
		(layer "F.Cu")
		(net "P3V3_AUX")
	)
	(segment
		(start 29.0068 -102.50805)
		(end 29.464 -102.96525)
		(width 0.4572)
		(layer "F.Cu")
		(net "P3V3_AUX")
	)
	(segment
		(start 6.07695 -172.847)
		(end 6.07695 -173.609)
		(width 0.4572)
		(layer "F.Cu")
		(net "P3V3_AUX")
	)
	(segment
		(start 3.886708 -132.948172)
		(end 4.21005 -132.62483)
		(width 0.4572)
		(layer "F.Cu")
		(net "P3V3_AUX")
	)
	(segment
		(start 9.906 -172.847)
		(end 9.525 -173.228)
		(width 0.4572)
		(layer "F.Cu")
		(net "P3V3_AUX")
	)
	(segment
		(start 5.528564 -131.440936)
		(end 5.17525 -131.79425)
		(width 0.2794)
		(layer "F.Cu")
		(net "P3V3_AUX")
	)
	(segment
		(start 21.22805 -173.736)
		(end 21.844 -173.736)
		(width 0.4572)
		(layer "F.Cu")
		(net "P3V3_AUX")
	)
	(segment
		(start 8.95604 -173.228)
		(end 8.32104 -173.228)
		(width 0.4572)
		(layer "F.Cu")
		(net "P3V3_AUX")
	)
	(segment
		(start 28.321 -193.303144)
		(end 28.321 -194.41795)
		(width 0.4572)
		(layer "F.Cu")
		(net "P3V3_AUX")
	)
	(segment
		(start 34.666428 -252.494796)
		(end 34.229294 -252.494796)
		(width 0.4572)
		(layer "F.Cu")
		(net "P3V3_AUX")
	)
	(segment
		(start 25.7048 -108.5342)
		(end 26.6446 -107.5944)
		(width 0.4572)
		(layer "F.Cu")
		(net "P3V3_AUX")
	)
	(segment
		(start 3.40995 -127.508)
		(end 2.794 -127.508)
		(width 0.4572)
		(layer "F.Cu")
		(net "P3V3_AUX")
	)
	(segment
		(start 29.95295 -182.13705)
		(end 30.353 -181.737)
		(width 0.4572)
		(layer "F.Cu")
		(net "P3V3_AUX")
	)
	(segment
		(start 25.019 -163.34105)
		(end 27.178 -163.34105)
		(width 0.4572)
		(layer "F.Cu")
		(net "P3V3_AUX")
	)
	(segment
		(start 33.02 -123.80595)
		(end 33.02 -123.19635)
		(width 0.4572)
		(layer "F.Cu")
		(net "P3V3_AUX")
	)
	(segment
		(start 21.22805 -171.704)
		(end 21.844 -171.704)
		(width 0.4572)
		(layer "F.Cu")
		(net "P3V3_AUX")
	)
	(segment
		(start 22.479 -205.84795)
		(end 22.200362 -205.84795)
		(width 0.4572)
		(layer "F.Cu")
		(net "P3V3_AUX")
	)
	(segment
		(start 17.04975 -190.627)
		(end 12.9286 -190.627)
		(width 0.4572)
		(layer "F.Cu")
		(net "P3V3_AUX")
	)
	(segment
		(start 32.04845 -106.27995)
		(end 32.385 -106.27995)
		(width 0.4572)
		(layer "F.Cu")
		(net "P3V3_AUX")
	)
	(segment
		(start 20.022312 -208.026)
		(end 19.558 -208.026)
		(width 0.4572)
		(layer "F.Cu")
		(net "P3V3_AUX")
	)
	(segment
		(start 38.62705 -185.166)
		(end 38.62705 -184.80405)
		(width 0.4572)
		(layer "F.Cu")
		(net "P3V3_AUX")
	)
	(segment
		(start 24.257 -141.20495)
		(end 25.654 -141.20495)
		(width 0.381)
		(layer "F.Cu")
		(net "P3V3_AUX")
	)
	(segment
		(start 30.992318 -17.403318)
		(end 30.992318 -16.914368)
		(width 0.4572)
		(layer "F.Cu")
		(net "P3V3_AUX")
	)
	(segment
		(start 24.557228 -16.373602)
		(end 25.790652 -16.373602)
		(width 0.4572)
		(layer "F.Cu")
		(net "P3V3_AUX")
	)
	(segment
		(start 21.717 -118.72595)
		(end 21.065998 -118.72595)
		(width 0.4572)
		(layer "F.Cu")
		(net "P3V3_AUX")
	)
	(segment
		(start 23.94204 -116.39804)
		(end 27.31008 -113.03)
		(width 0.4572)
		(layer "F.Cu")
		(net "P3V3_AUX")
	)
	(segment
		(start 21.717 -27.79395)
		(end 21.829014 -27.681936)
		(width 0.4572)
		(layer "F.Cu")
		(net "P3V3_AUX")
	)
	(segment
		(start 43.96105 -168.529)
		(end 43.96105 -167.513)
		(width 0.4572)
		(layer "F.Cu")
		(net "P3V3_AUX")
	)
	(segment
		(start 19.558 -115.9256)
		(end 19.558 -115.08105)
		(width 0.4572)
		(layer "F.Cu")
		(net "P3V3_AUX")
	)
	(segment
		(start 22.154896 -126.562104)
		(end 22.154896 -127.159004)
		(width 0.1778)
		(layer "F.Cu")
		(net "P3V3_AUX")
	)
	(segment
		(start 40.527478 -66.986912)
		(end 40.92067 -67.380104)
		(width 0.4572)
		(layer "F.Cu")
		(net "P3V3_AUX")
	)
	(segment
		(start 21.065998 -118.72595)
		(end 20.512024 -118.171976)
		(width 0.4572)
		(layer "F.Cu")
		(net "P3V3_AUX")
	)
	(segment
		(start 21.07565 -13.546582)
		(end 21.822918 -14.29385)
		(width 0.254)
		(layer "F.Cu")
		(net "P3V3_AUX")
	)
	(segment
		(start 33.401 -140.95095)
		(end 34.417 -140.95095)
		(width 0.4572)
		(layer "F.Cu")
		(net "P3V3_AUX")
	)
	(segment
		(start 9.109964 -251.587)
		(end 9.733534 -251.587)
		(width 0.4572)
		(layer "F.Cu")
		(net "P3V3_AUX")
	)
	(segment
		(start 44.649136 -135.10895)
		(end 44.191936 -134.65175)
		(width 0.4572)
		(layer "F.Cu")
		(net "P3V3_AUX")
	)
	(segment
		(start 36.129468 -144.271746)
		(end 35.58794 -145.579084)
		(width 0.4572)
		(layer "F.Cu")
		(net "P3V3_AUX")
	)
	(segment
		(start 45.105066 -71.704962)
		(end 45.417994 -71.392034)
		(width 0.4572)
		(layer "F.Cu")
		(net "P3V3_AUX")
	)
	(segment
		(start 22.225 -124.714)
		(end 22.225 -126.492)
		(width 0.1778)
		(layer "F.Cu")
		(net "P3V3_AUX")
	)
	(segment
		(start 17.272 -145.64995)
		(end 19.05 -145.64995)
		(width 0.4572)
		(layer "F.Cu")
		(net "P3V3_AUX")
	)
	(segment
		(start 22.987 -169.799)
		(end 23.241 -169.545)
		(width 0.4572)
		(layer "F.Cu")
		(net "P3V3_AUX")
	)
	(segment
		(start 29.06395 -133.07695)
		(end 28.829 -132.842)
		(width 0.4572)
		(layer "F.Cu")
		(net "P3V3_AUX")
	)
	(segment
		(start 25.527 -103.0732)
		(end 25.527 -106.172)
		(width 0.4572)
		(layer "F.Cu")
		(net "P3V3_AUX")
	)
	(segment
		(start 36.322 -143.369284)
		(end 36.322 -143.806926)
		(width 0.381)
		(layer "F.Cu")
		(net "P3V3_AUX")
	)
	(segment
		(start 22.75205 -119.52605)
		(end 23.241 -119.52605)
		(width 0.4572)
		(layer "F.Cu")
		(net "P3V3_AUX")
	)
	(segment
		(start 19.431 -294.78605)
		(end 19.431 -295.39565)
		(width 0.4572)
		(layer "F.Cu")
		(net "P3V3_AUX")
	)
	(segment
		(start 22.200362 -205.84795)
		(end 20.022312 -208.026)
		(width 0.4572)
		(layer "F.Cu")
		(net "P3V3_AUX")
	)
	(segment
		(start 22.588728 -108.5342)
		(end 25.7048 -108.5342)
		(width 0.4572)
		(layer "F.Cu")
		(net "P3V3_AUX")
	)
	(segment
		(start 30.734 -287.42005)
		(end 30.099 -287.42005)
		(width 0.4572)
		(layer "F.Cu")
		(net "P3V3_AUX")
	)
	(segment
		(start 38.1 -184.277)
		(end 36.449 -184.277)
		(width 0.4572)
		(layer "F.Cu")
		(net "P3V3_AUX")
	)
	(segment
		(start 29.083 -141.20495)
		(end 28.194 -141.20495)
		(width 0.4572)
		(layer "F.Cu")
		(net "P3V3_AUX")
	)
	(segment
		(start 5.06095 -186.436)
		(end 4.445 -186.436)
		(width 0.4572)
		(layer "F.Cu")
		(net "P3V3_AUX")
	)
	(segment
		(start 21.717 -210.92795)
		(end 21.994622 -210.92795)
		(width 0.4572)
		(layer "F.Cu")
		(net "P3V3_AUX")
	)
	(segment
		(start 24.27605 -211.328)
		(end 26.924254 -211.328)
		(width 0.4572)
		(layer "F.Cu")
		(net "P3V3_AUX")
	)
	(segment
		(start 6.07695 -166.116)
		(end 5.46735 -166.116)
		(width 0.4572)
		(layer "F.Cu")
		(net "P3V3_AUX")
	)
	(segment
		(start 23.956264 -23.786846)
		(end 23.956264 -24.993092)
		(width 0.4572)
		(layer "F.Cu")
		(net "P3V3_AUX")
	)
	(segment
		(start 19.431 -134.38505)
		(end 19.431 -134.994904)
		(width 0.4572)
		(layer "F.Cu")
		(net "P3V3_AUX")
	)
	(segment
		(start 29.464 -102.96525)
		(end 29.464 -103.302054)
		(width 0.4572)
		(layer "F.Cu")
		(net "P3V3_AUX")
	)
	(segment
		(start 21.717 -118.72595)
		(end 21.717 -117.647974)
		(width 0.4572)
		(layer "F.Cu")
		(net "P3V3_AUX")
	)
	(segment
		(start 40.386 -184.277)
		(end 40.386 -184.277254)
		(width 0.4572)
		(layer "F.Cu")
		(net "P3V3_AUX")
	)
	(segment
		(start 30.306518 -104.855518)
		(end 29.859986 -104.408986)
		(width 0.4572)
		(layer "F.Cu")
		(net "P3V3_AUX")
	)
	(segment
		(start 25.92705 -125.349)
		(end 26.86304 -125.349)
		(width 0.4572)
		(layer "F.Cu")
		(net "P3V3_AUX")
	)
	(segment
		(start 28.187904 -20.713954)
		(end 28.68295 -21.209)
		(width 0.4572)
		(layer "F.Cu")
		(net "P3V3_AUX")
	)
	(segment
		(start 27.051 -106.807)
		(end 27.686 -106.172)
		(width 0.4572)
		(layer "F.Cu")
		(net "P3V3_AUX")
	)
	(segment
		(start 21.717 -27.79395)
		(end 20.828 -27.79395)
		(width 0.4572)
		(layer "F.Cu")
		(net "P3V3_AUX")
	)
	(segment
		(start 28.767278 -194.41795)
		(end 29.567378 -195.21805)
		(width 0.4572)
		(layer "F.Cu")
		(net "P3V3_AUX")
	)
	(segment
		(start 32.639 -140.95095)
		(end 33.401 -140.95095)
		(width 0.4572)
		(layer "F.Cu")
		(net "P3V3_AUX")
	)
	(segment
		(start 22.794722 -211.72805)
		(end 23.241 -211.72805)
		(width 0.4572)
		(layer "F.Cu")
		(net "P3V3_AUX")
	)
	(segment
		(start 22.966934 -116.39804)
		(end 23.94204 -116.39804)
		(width 0.4572)
		(layer "F.Cu")
		(net "P3V3_AUX")
	)
	(segment
		(start 45.395896 -253.853442)
		(end 45.395896 -255.970024)
		(width 0.4572)
		(layer "F.Cu")
		(net "P3V3_AUX")
	)
	(segment
		(start 21.717 -118.72595)
		(end 21.95195 -118.72595)
		(width 0.4572)
		(layer "F.Cu")
		(net "P3V3_AUX")
	)
	(segment
		(start 38.183312 -71.812912)
		(end 38.041326 -71.954898)
		(width 0.4572)
		(layer "F.Cu")
		(net "P3V3_AUX")
	)
	(segment
		(start 13.73505 -169.291)
		(end 14.34465 -169.291)
		(width 0.4572)
		(layer "F.Cu")
		(net "P3V3_AUX")
	)
	(segment
		(start 31.73095 -18.14195)
		(end 30.992318 -17.403318)
		(width 0.4572)
		(layer "F.Cu")
		(net "P3V3_AUX")
	)
	(segment
		(start 23.956264 -24.993092)
		(end 23.499064 -25.450292)
		(width 0.4572)
		(layer "F.Cu")
		(net "P3V3_AUX")
	)
	(segment
		(start 26.6192 -106.807)
		(end 27.051 -106.807)
		(width 0.4572)
		(layer "F.Cu")
		(net "P3V3_AUX")
	)
	(segment
		(start 20.2692 -117.104922)
		(end 19.7231 -116.558822)
		(width 0.4572)
		(layer "F.Cu")
		(net "P3V3_AUX")
	)
	(segment
		(start 23.876 -211.72805)
		(end 24.27605 -211.328)
		(width 0.4572)
		(layer "F.Cu")
		(net "P3V3_AUX")
	)
	(segment
		(start 18.415 -72.077834)
		(end 17.279366 -72.077834)
		(width 0.4572)
		(layer "F.Cu")
		(net "P3V3_AUX")
	)
	(segment
		(start 36.449 -184.277)
		(end 35.3441 -183.1721)
		(width 0.4572)
		(layer "F.Cu")
		(net "P3V3_AUX")
	)
	(segment
		(start 42.43705 -181.102)
		(end 43.04665 -181.102)
		(width 0.4572)
		(layer "F.Cu")
		(net "P3V3_AUX")
	)
	(segment
		(start 31.623 -123.80595)
		(end 31.623 -123.19)
		(width 0.4572)
		(layer "F.Cu")
		(net "P3V3_AUX")
	)
	(segment
		(start 21.994622 -210.92795)
		(end 22.794722 -211.72805)
		(width 0.4572)
		(layer "F.Cu")
		(net "P3V3_AUX")
	)
	(segment
		(start 23.114 -141.20495)
		(end 24.257 -141.20495)
		(width 0.381)
		(layer "F.Cu")
		(net "P3V3_AUX")
	)
	(segment
		(start 35.41395 -140.95095)
		(end 36.322 -141.859)
		(width 0.4572)
		(layer "F.Cu")
		(net "P3V3_AUX")
	)
	(segment
		(start 32.258 -294.49395)
		(end 32.258 -293.88435)
		(width 0.4572)
		(layer "F.Cu")
		(net "P3V3_AUX")
	)
	(segment
		(start 17.30375 -190.881)
		(end 17.04975 -190.627)
		(width 0.4572)
		(layer "F.Cu")
		(net "P3V3_AUX")
	)
	(segment
		(start 27.051 -127.10795)
		(end 27.15895 -127)
		(width 0.4572)
		(layer "F.Cu")
		(net "P3V3_AUX")
	)
	(segment
		(start 48.66005 -130.57505)
		(end 48.66005 -130.937)
		(width 0.4572)
		(layer "F.Cu")
		(net "P3V3_AUX")
	)
	(segment
		(start 29.95295 -178.816)
		(end 29.95295 -179.05095)
		(width 0.4572)
		(layer "F.Cu")
		(net "P3V3_AUX")
	)
	(segment
		(start 29.95295 -180.594)
		(end 29.95295 -180.35905)
		(width 0.4572)
		(layer "F.Cu")
		(net "P3V3_AUX")
	)
	(segment
		(start 31.579566 -21.69795)
		(end 31.122366 -21.24075)
		(width 0.4572)
		(layer "F.Cu")
		(net "P3V3_AUX")
	)
	(segment
		(start 23.495 -163.34105)
		(end 21.5138 -163.34105)
		(width 0.4572)
		(layer "F.Cu")
		(net "P3V3_AUX")
	)
	(segment
		(start 23.622 -134.38505)
		(end 23.622 -134.994904)
		(width 0.4572)
		(layer "F.Cu")
		(net "P3V3_AUX")
	)
	(segment
		(start 6.07695 -170.815)
		(end 6.07695 -171.13885)
		(width 0.4572)
		(layer "F.Cu")
		(net "P3V3_AUX")
	)
	(segment
		(start 9.906 -171.831)
		(end 9.906 -172.847)
		(width 0.4572)
		(layer "F.Cu")
		(net "P3V3_AUX")
	)
	(segment
		(start 21.216112 -26.60396)
		(end 19.558 -24.945848)
		(width 0.4572)
		(layer "F.Cu")
		(net "P3V3_AUX")
	)
	(segment
		(start 29.95295 -187.452)
		(end 29.34335 -187.452)
		(width 0.4572)
		(layer "F.Cu")
		(net "P3V3_AUX")
	)
	(segment
		(start 13.208 -183.53405)
		(end 14.065504 -183.53405)
		(width 0.3556)
		(layer "F.Cu")
		(net "P3V3_AUX")
	)
	(segment
		(start 20.512024 -118.171976)
		(end 20.512024 -122.747024)
		(width 0.4572)
		(layer "F.Cu")
		(net "P3V3_AUX")
	)
	(segment
		(start 22.9362 -166.624)
		(end 22.479 -167.0812)
		(width 0.4572)
		(layer "F.Cu")
		(net "P3V3_AUX")
	)
	(segment
		(start 9.906 -173.609)
		(end 9.525 -173.228)
		(width 0.4572)
		(layer "F.Cu")
		(net "P3V3_AUX")
	)
	(segment
		(start 33.38195 -167.3606)
		(end 33.401 -167.37965)
		(width 0.4572)
		(layer "F.Cu")
		(net "P3V3_AUX")
	)
	(segment
		(start 23.537418 -23.368)
		(end 23.956264 -23.786846)
		(width 0.4572)
		(layer "F.Cu")
		(net "P3V3_AUX")
	)
	(segment
		(start 4.445 -189.992)
		(end 5.06095 -189.992)
		(width 0.4572)
		(layer "F.Cu")
		(net "P3V3_AUX")
	)
	(segment
		(start 29.986986 -287.532064)
		(end 29.986986 -288.61004)
		(width 0.4572)
		(layer "F.Cu")
		(net "P3V3_AUX")
	)
	(segment
		(start 42.43705 -189.738)
		(end 43.04665 -189.738)
		(width 0.4572)
		(layer "F.Cu")
		(net "P3V3_AUX")
	)
	(segment
		(start 40.176958 -183.559958)
		(end 40.386 -183.769)
		(width 0.3556)
		(layer "F.Cu")
		(net "P3V3_AUX")
	)
	(segment
		(start 26.924254 -211.328)
		(end 29.553154 -213.9569)
		(width 0.4572)
		(layer "F.Cu")
		(net "P3V3_AUX")
	)
	(segment
		(start 21.717 -303.12995)
		(end 21.829014 -303.017936)
		(width 0.4572)
		(layer "F.Cu")
		(net "P3V3_AUX")
	)
	(segment
		(start 6.11505 -173.5709)
		(end 7.97814 -173.5709)
		(width 0.4572)
		(layer "F.Cu")
		(net "P3V3_AUX")
	)
	(segment
		(start 21.829014 -303.017936)
		(end 21.829014 -301.93996)
		(width 0.4572)
		(layer "F.Cu")
		(net "P3V3_AUX")
	)
	(segment
		(start 17.958816 -185.222134)
		(end 18.01495 -185.166)
		(width 0.4572)
		(layer "F.Cu")
		(net "P3V3_AUX")
	)
	(segment
		(start 35.179 -163.34105)
		(end 32.131 -163.34105)
		(width 0.4572)
		(layer "F.Cu")
		(net "P3V3_AUX")
	)
	(segment
		(start 6.07695 -171.13885)
		(end 6.477 -171.5389)
		(width 0.4572)
		(layer "F.Cu")
		(net "P3V3_AUX")
	)
	(segment
		(start 23.241 -211.72805)
		(end 23.876 -211.72805)
		(width 0.4572)
		(layer "F.Cu")
		(net "P3V3_AUX")
	)
	(segment
		(start 22.479 -298.04995)
		(end 23.114 -298.04995)
		(width 0.4572)
		(layer "F.Cu")
		(net "P3V3_AUX")
	)
	(segment
		(start 20.512024 -122.747024)
		(end 21.48205 -123.71705)
		(width 0.4572)
		(layer "F.Cu")
		(net "P3V3_AUX")
	)
	(segment
		(start 27.345386 -20.713954)
		(end 28.187904 -20.713954)
		(width 0.4572)
		(layer "F.Cu")
		(net "P3V3_AUX")
	)
	(segment
		(start 25.09139 -205.84795)
		(end 29.083 -201.85634)
		(width 0.4572)
		(layer "F.Cu")
		(net "P3V3_AUX")
	)
	(segment
		(start 18.01495 -190.881)
		(end 17.30375 -190.881)
		(width 0.4572)
		(layer "F.Cu")
		(net "P3V3_AUX")
	)
	(segment
		(start 44.443396 -252.900942)
		(end 45.395896 -253.853442)
		(width 0.4572)
		(layer "F.Cu")
		(net "P3V3_AUX")
	)
	(segment
		(start 22.352 -175.768)
		(end 21.22805 -175.768)
		(width 0.4572)
		(layer "F.Cu")
		(net "P3V3_AUX")
	)
	(segment
		(start 23.495 -170.307)
		(end 22.987 -169.799)
		(width 0.4572)
		(layer "F.Cu")
		(net "P3V3_AUX")
	)
	(segment
		(start 2.790698 -132.948172)
		(end 3.886708 -132.948172)
		(width 0.4572)
		(layer "F.Cu")
		(net "P3V3_AUX")
	)
	(segment
		(start 13.73505 -170.815)
		(end 14.34465 -170.815)
		(width 0.4572)
		(layer "F.Cu")
		(net "P3V3_AUX")
	)
	(segment
		(start 21.829014 -26.60396)
		(end 21.829014 -26.176986)
		(width 0.4572)
		(layer "F.Cu")
		(net "P3V3_AUX")
	)
	(segment
		(start 29.732986 -195.330064)
		(end 29.732986 -196.40804)
		(width 0.4572)
		(layer "F.Cu")
		(net "P3V3_AUX")
	)
	(segment
		(start 10.3632 -183.515)
		(end 11.938 -183.515)
		(width 0.4572)
		(layer "F.Cu")
		(net "P3V3_AUX")
	)
	(segment
		(start 27.051 -15.113254)
		(end 27.051 -14.29385)
		(width 0.4572)
		(layer "F.Cu")
		(net "P3V3_AUX")
	)
	(segment
		(start 28.575 -286.61995)
		(end 27.94 -286.61995)
		(width 0.4572)
		(layer "F.Cu")
		(net "P3V3_AUX")
	)
	(segment
		(start 38.183312 -256.413)
		(end 38.041326 -256.554986)
		(width 0.4572)
		(layer "F.Cu")
		(net "P3V3_AUX")
	)
	(segment
		(start 35.3441 -183.1721)
		(end 35.3441 -180.975)
		(width 0.4572)
		(layer "F.Cu")
		(net "P3V3_AUX")
	)
	(segment
		(start 21.829014 -27.681936)
		(end 21.829014 -26.60396)
		(width 0.4572)
		(layer "F.Cu")
		(net "P3V3_AUX")
	)
	(segment
		(start 41.554908 -191.433958)
		(end 39.243 -191.433958)
		(width 0.3556)
		(layer "F.Cu")
		(net "P3V3_AUX")
	)
	(segment
		(start 6.07695 -167.64)
		(end 5.46735 -167.64)
		(width 0.4572)
		(layer "F.Cu")
		(net "P3V3_AUX")
	)
	(segment
		(start 29.083 -201.85634)
		(end 29.083 -200.29805)
		(width 0.4572)
		(layer "F.Cu")
		(net "P3V3_AUX")
	)
	(segment
		(start 8.509 -177.673)
		(end 9.906 -176.276)
		(width 0.4572)
		(layer "F.Cu")
		(net "P3V3_AUX")
	)
	(segment
		(start 22.210522 -173.736)
		(end 21.844 -173.736)
		(width 0.4572)
		(layer "F.Cu")
		(net "P3V3_AUX")
	)
	(segment
		(start 2.988056 -251.69495)
		(end 2.498852 -252.184154)
		(width 0.4572)
		(layer "F.Cu")
		(net "P3V3_AUX")
	)
	(segment
		(start 26.7081 -127.10795)
		(end 27.051 -127.10795)
		(width 0.4572)
		(layer "F.Cu")
		(net "P3V3_AUX")
	)
	(segment
		(start 13.73505 -173.99)
		(end 14.34465 -173.99)
		(width 0.4572)
		(layer "F.Cu")
		(net "P3V3_AUX")
	)
	(segment
		(start 41.041574 -252.900942)
		(end 40.527478 -252.386846)
		(width 0.4572)
		(layer "F.Cu")
		(net "P3V3_AUX")
	)
	(segment
		(start 5.46735 -170.815)
		(end 6.07695 -170.815)
		(width 0.4572)
		(layer "F.Cu")
		(net "P3V3_AUX")
	)
	(segment
		(start 33.38195 -166.751)
		(end 33.38195 -167.3606)
		(width 0.4572)
		(layer "F.Cu")
		(net "P3V3_AUX")
	)
	(segment
		(start 19.7231 -116.0907)
		(end 19.558 -115.9256)
		(width 0.4572)
		(layer "F.Cu")
		(net "P3V3_AUX")
	)
	(segment
		(start 18.81505 -188.595)
		(end 19.42465 -188.595)
		(width 0.4572)
		(layer "F.Cu")
		(net "P3V3_AUX")
	)
	(segment
		(start 20.486878 -110.63605)
		(end 22.588728 -108.5342)
		(width 0.4572)
		(layer "F.Cu")
		(net "P3V3_AUX")
	)
	(segment
		(start 30.992318 -16.914368)
		(end 30.96895 -16.891)
		(width 0.4572)
		(layer "F.Cu")
		(net "P3V3_AUX")
	)
	(segment
		(start 29.464 -133.07695)
		(end 29.06395 -133.07695)
		(width 0.4572)
		(layer "F.Cu")
		(net "P3V3_AUX")
	)
	(segment
		(start 9.906 -176.276)
		(end 9.906 -173.609)
		(width 0.4572)
		(layer "F.Cu")
		(net "P3V3_AUX")
	)
	(segment
		(start 29.95295 -180.35905)
		(end 30.353 -179.959)
		(width 0.4572)
		(layer "F.Cu")
		(net "P3V3_AUX")
	)
	(segment
		(start 44.191936 -134.65175)
		(end 44.191936 -134.361936)
		(width 0.4572)
		(layer "F.Cu")
		(net "P3V3_AUX")
	)
	(segment
		(start 18.81505 -181.61)
		(end 19.42465 -181.61)
		(width 0.4572)
		(layer "F.Cu")
		(net "P3V3_AUX")
	)
	(segment
		(start 29.464 -132.334)
		(end 29.972 -131.826)
		(width 0.4572)
		(layer "F.Cu")
		(net "P3V3_AUX")
	)
	(segment
		(start 11.045444 -71.812912)
		(end 10.421874 -71.812912)
		(width 0.4572)
		(layer "F.Cu")
		(net "P3V3_AUX")
	)
	(segment
		(start 42.43705 -187.96)
		(end 43.04665 -187.96)
		(width 0.4572)
		(layer "F.Cu")
		(net "P3V3_AUX")
	)
	(segment
		(start 29.083 -141.20495)
		(end 29.106114 -141.228064)
		(width 0.4572)
		(layer "F.Cu")
		(net "P3V3_AUX")
	)
	(segment
		(start 28.829 -123.80595)
		(end 28.829 -123.19)
		(width 0.4572)
		(layer "F.Cu")
		(net "P3V3_AUX")
	)
	(segment
		(start 5.06095 -188.214)
		(end 4.445 -188.214)
		(width 0.4572)
		(layer "F.Cu")
		(net "P3V3_AUX")
	)
	(segment
		(start 29.95295 -189.23)
		(end 29.34335 -189.23)
		(width 0.4572)
		(layer "F.Cu")
		(net "P3V3_AUX")
	)
	(segment
		(start 29.14015 -23.26005)
		(end 29.14015 -21.971)
		(width 0.4572)
		(layer "F.Cu")
		(net "P3V3_AUX")
	)
	(segment
		(start 6.458966 -131.440936)
		(end 5.528564 -131.440936)
		(width 0.2794)
		(layer "F.Cu")
		(net "P3V3_AUX")
	)
	(segment
		(start 20.828 -134.38505)
		(end 20.828 -134.994904)
		(width 0.4572)
		(layer "F.Cu")
		(net "P3V3_AUX")
	)
	(segment
		(start 44.831 -135.10895)
		(end 45.466 -135.10895)
		(width 0.4572)
		(layer "F.Cu")
		(net "P3V3_AUX")
	)
	(segment
		(start 30.226 -123.80595)
		(end 30.226 -123.19)
		(width 0.4572)
		(layer "F.Cu")
		(net "P3V3_AUX")
	)
	(segment
		(start 40.92067 -67.380104)
		(end 40.92067 -67.584574)
		(width 0.4572)
		(layer "F.Cu")
		(net "P3V3_AUX")
	)
	(segment
		(start 31.067502 -110.49)
		(end 29.21 -108.632498)
		(width 0.4572)
		(layer "F.Cu")
		(net "P3V3_AUX")
	)
	(segment
		(start 38.806882 -71.812912)
		(end 38.183312 -71.812912)
		(width 0.4572)
		(layer "F.Cu")
		(net "P3V3_AUX")
	)
	(segment
		(start 3.048 -180.086)
		(end 3.302 -180.086)
		(width 0.4572)
		(layer "F.Cu")
		(net "P3V3_AUX")
	)
	(segment
		(start 21.717 -303.12995)
		(end 20.574 -303.12995)
		(width 0.4572)
		(layer "F.Cu")
		(net "P3V3_AUX")
	)
	(segment
		(start 23.241 -169.545)
		(end 28.55595 -169.545)
		(width 0.4572)
		(layer "F.Cu")
		(net "P3V3_AUX")
	)
	(segment
		(start 27.686 -105.2322)
		(end 28.1432 -104.775)
		(width 0.4572)
		(layer "F.Cu")
		(net "P3V3_AUX")
	)
	(segment
		(start 29.553154 -213.9569)
		(end 36.321746 -213.9569)
		(width 0.4572)
		(layer "F.Cu")
		(net "P3V3_AUX")
	)
	(segment
		(start 19.06905 -204.597)
		(end 19.558 -204.10805)
		(width 0.4572)
		(layer "F.Cu")
		(net "P3V3_AUX")
	)
	(segment
		(start 32.258 -201.65695)
		(end 32.258 -201.422)
		(width 0.4572)
		(layer "F.Cu")
		(net "P3V3_AUX")
	)
	(segment
		(start 21.829014 -26.176986)
		(end 22.555708 -25.450292)
		(width 0.4572)
		(layer "F.Cu")
		(net "P3V3_AUX")
	)
	(segment
		(start 11.938 -183.515)
		(end 11.95705 -183.53405)
		(width 0.3556)
		(layer "F.Cu")
		(net "P3V3_AUX")
	)
	(segment
		(start 28.68295 -21.209)
		(end 28.68295 -21.5138)
		(width 0.4572)
		(layer "F.Cu")
		(net "P3V3_AUX")
	)
	(segment
		(start 42.43705 -186.182)
		(end 43.04665 -186.182)
		(width 0.4572)
		(layer "F.Cu")
		(net "P3V3_AUX")
	)
	(segment
		(start 19.939 -154.2796)
		(end 20.32 -153.8986)
		(width 0.4572)
		(layer "F.Cu")
		(net "P3V3_AUX")
	)
	(segment
		(start 22.210522 -173.736)
		(end 23.495 -172.451522)
		(width 0.4572)
		(layer "F.Cu")
		(net "P3V3_AUX")
	)
	(segment
		(start 35.46983 -163.34105)
		(end 35.179 -163.34105)
		(width 0.4572)
		(layer "F.Cu")
		(net "P3V3_AUX")
	)
	(segment
		(start 22.225 -134.38505)
		(end 22.225 -134.994904)
		(width 0.4572)
		(layer "F.Cu")
		(net "P3V3_AUX")
	)
	(segment
		(start 20.75815 -114.7826)
		(end 20.483068 -115.057682)
		(width 0.4572)
		(layer "F.Cu")
		(net "P3V3_AUX")
	)
	(segment
		(start 44.655994 -167.561006)
		(end 44.704 -167.513)
		(width 0.4572)
		(layer "F.Cu")
		(net "P3V3_AUX")
	)
	(segment
		(start 18.034 -134.38505)
		(end 19.431 -134.38505)
		(width 0.4572)
		(layer "F.Cu")
		(net "P3V3_AUX")
	)
	(segment
		(start 29.464 -103.302054)
		(end 29.859986 -103.69804)
		(width 0.4572)
		(layer "F.Cu")
		(net "P3V3_AUX")
	)
	(segment
		(start 21.22805 -177.8)
		(end 21.844 -177.8)
		(width 0.4572)
		(layer "F.Cu")
		(net "P3V3_AUX")
	)
	(segment
		(start 23.241 -14.29385)
		(end 23.241 -15.057374)
		(width 0.4572)
		(layer "F.Cu")
		(net "P3V3_AUX")
	)
	(segment
		(start 2.413 -180.721)
		(end 3.048 -180.086)
		(width 0.4572)
		(layer "F.Cu")
		(net "P3V3_AUX")
	)
	(segment
		(start 28.522676 -193.101468)
		(end 28.321 -193.303144)
		(width 0.4572)
		(layer "F.Cu")
		(net "P3V3_AUX")
	)
	(segment
		(start 34.417 -123.80595)
		(end 34.417 -123.196096)
		(width 0.4572)
		(layer "F.Cu")
		(net "P3V3_AUX")
	)
	(segment
		(start 2.498852 -252.184154)
		(end 2.498852 -252.661166)
		(width 0.4572)
		(layer "F.Cu")
		(net "P3V3_AUX")
	)
	(segment
		(start 29.14015 -21.971)
		(end 30.392116 -21.971)
		(width 0.4572)
		(layer "F.Cu")
		(net "P3V3_AUX")
	)
	(segment
		(start 19.581368 -115.057682)
		(end 19.558 -115.08105)
		(width 0.4572)
		(layer "F.Cu")
		(net "P3V3_AUX")
	)
	(segment
		(start 18.81505 -180.213)
		(end 19.431 -180.213)
		(width 0.4572)
		(layer "F.Cu")
		(net "P3V3_AUX")
	)
	(segment
		(start 22.225 -123.71705)
		(end 22.225 -124.714)
		(width 0.4572)
		(layer "F.Cu")
		(net "P3V3_AUX")
	)
	(segment
		(start 19.7231 -116.558822)
		(end 19.7231 -116.0907)
		(width 0.4572)
		(layer "F.Cu")
		(net "P3V3_AUX")
	)
	(segment
		(start 20.828 -27.79395)
		(end 20.3581 -27.32405)
		(width 0.4572)
		(layer "F.Cu")
		(net "P3V3_AUX")
	)
	(segment
		(start 20.2692 -117.929152)
		(end 20.2692 -117.104922)
		(width 0.4572)
		(layer "F.Cu")
		(net "P3V3_AUX")
	)
	(segment
		(start 25.92705 -127.889)
		(end 26.7081 -127.10795)
		(width 0.4572)
		(layer "F.Cu")
		(net "P3V3_AUX")
	)
	(segment
		(start 29.972 -131.826)
		(end 30.296104 -131.501896)
		(width 0.1778)
		(layer "F.Cu")
		(net "P3V3_AUX")
	)
	(segment
		(start 21.829014 -210.815936)
		(end 21.829014 -209.73796)
		(width 0.4572)
		(layer "F.Cu")
		(net "P3V3_AUX")
	)
	(segment
		(start 35.58794 -145.579084)
		(end 35.58794 -157.877256)
		(width 0.4572)
		(layer "F.Cu")
		(net "P3V3_AUX")
	)
	(segment
		(start 43.561 -135.90905)
		(end 42.926 -135.90905)
		(width 0.4572)
		(layer "F.Cu")
		(net "P3V3_AUX")
	)
	(segment
		(start 31.623 -140.95095)
		(end 32.639 -140.95095)
		(width 0.4572)
		(layer "F.Cu")
		(net "P3V3_AUX")
	)
	(segment
		(start 20.32 -153.8986)
		(end 20.955 -153.8986)
		(width 0.4572)
		(layer "F.Cu")
		(net "P3V3_AUX")
	)
	(segment
		(start 22.210522 -173.736)
		(end 22.675342 -174.20082)
		(width 0.4572)
		(layer "F.Cu")
		(net "P3V3_AUX")
	)
	(segment
		(start 20.3581 -27.32405)
		(end 19.558 -27.32405)
		(width 0.4572)
		(layer "F.Cu")
		(net "P3V3_AUX")
	)
	(segment
		(start 30.57144 -16.891)
		(end 30.113986 -17.348454)
		(width 0.4572)
		(layer "F.Cu")
		(net "P3V3_AUX")
	)
	(segment
		(start 26.448258 -23.8252)
		(end 28.575 -23.8252)
		(width 0.4572)
		(layer "F.Cu")
		(net "P3V3_AUX")
	)
	(segment
		(start 28.956 -163.34105)
		(end 27.178 -163.34105)
		(width 0.4572)
		(layer "F.Cu")
		(net "P3V3_AUX")
	)
	(segment
		(start 6.858 -135.65505)
		(end 7.493 -135.65505)
		(width 0.4572)
		(layer "F.Cu")
		(net "P3V3_AUX")
	)
	(segment
		(start 4.889754 -132.08)
		(end 4.21005 -132.08)
		(width 0.4572)
		(layer "F.Cu")
		(net "P3V3_AUX")
	)
	(segment
		(start 6.07695 -173.609)
		(end 6.07695 -174.244)
		(width 0.4572)
		(layer "F.Cu")
		(net "P3V3_AUX")
	)
	(segment
		(start 9.54405 -184.33415)
		(end 10.3632 -183.515)
		(width 0.4572)
		(layer "F.Cu")
		(net "P3V3_AUX")
	)
	(segment
		(start 31.122366 -19.714718)
		(end 30.113986 -18.706338)
		(width 0.4572)
		(layer "F.Cu")
		(net "P3V3_AUX")
	)
	(segment
		(start 10.421874 -71.812912)
		(end 10.279888 -71.954898)
		(width 0.4572)
		(layer "F.Cu")
		(net "P3V3_AUX")
	)
	(segment
		(start 30.96895 -16.891)
		(end 30.57144 -16.891)
		(width 0.4572)
		(layer "F.Cu")
		(net "P3V3_AUX")
	)
	(segment
		(start 30.353 -179.959)
		(end 30.353 -179.705)
		(width 0.4572)
		(layer "F.Cu")
		(net "P3V3_AUX")
	)
	(segment
		(start 29.942536 -140.974064)
		(end 31.599886 -140.974064)
		(width 0.381)
		(layer "F.Cu")
		(net "P3V3_AUX")
	)
	(segment
		(start 27.15895 -127)
		(end 27.686 -127)
		(width 0.4572)
		(layer "F.Cu")
		(net "P3V3_AUX")
	)
	(segment
		(start 20.5232 -163.34105)
		(end 21.5138 -163.34105)
		(width 0.4572)
		(layer "F.Cu")
		(net "P3V3_AUX")
	)
	(segment
		(start 23.241 -15.057374)
		(end 24.557228 -16.373602)
		(width 0.4572)
		(layer "F.Cu")
		(net "P3V3_AUX")
	)
	(segment
		(start 40.386 -184.277254)
		(end 39.497254 -185.166)
		(width 0.4572)
		(layer "F.Cu")
		(net "P3V3_AUX")
	)
	(segment
		(start 29.21 -108.632498)
		(end 29.21 -107.58805)
		(width 0.4572)
		(layer "F.Cu")
		(net "P3V3_AUX")
	)
	(segment
		(start 3.248914 -251.69495)
		(end 2.988056 -251.69495)
		(width 0.4572)
		(layer "F.Cu")
		(net "P3V3_AUX")
	)
	(segment
		(start 23.495 -172.451522)
		(end 23.495 -170.307)
		(width 0.4572)
		(layer "F.Cu")
		(net "P3V3_AUX")
	)
	(segment
		(start 29.493972 -104.775)
		(end 29.859986 -104.408986)
		(width 0.4572)
		(layer "F.Cu")
		(net "P3V3_AUX")
	)
	(segment
		(start 33.38195 -166.751)
		(end 33.25495 -166.624)
		(width 0.4572)
		(layer "F.Cu")
		(net "P3V3_AUX")
	)
	(segment
		(start 13.73505 -172.466)
		(end 14.34465 -172.466)
		(width 0.4572)
		(layer "F.Cu")
		(net "P3V3_AUX")
	)
	(segment
		(start 21.3487 -141.20495)
		(end 23.114 -141.20495)
		(width 0.381)
		(layer "F.Cu")
		(net "P3V3_AUX")
	)
	(segment
		(start 17.395444 -256.667)
		(end 17.033494 -256.30505)
		(width 0.4572)
		(layer "F.Cu")
		(net "P3V3_AUX")
	)
	(segment
		(start 42.43705 -182.88)
		(end 43.04665 -182.88)
		(width 0.4572)
		(layer "F.Cu")
		(net "P3V3_AUX")
	)
	(segment
		(start 45.395896 -255.970024)
		(end 45.417994 -255.992122)
		(width 0.4572)
		(layer "F.Cu")
		(net "P3V3_AUX")
	)
	(segment
		(start 19.558 -207.41005)
		(end 19.558 -208.026)
		(width 0.4572)
		(layer "F.Cu")
		(net "P3V3_AUX")
	)
	(segment
		(start 2.8702 -182.626)
		(end 2.413 -182.1688)
		(width 0.4572)
		(layer "F.Cu")
		(net "P3V3_AUX")
	)
	(segment
		(start 28.321 -194.41795)
		(end 28.767278 -194.41795)
		(width 0.4572)
		(layer "F.Cu")
		(net "P3V3_AUX")
	)
	(segment
		(start 29.337 -292.50005)
		(end 29.972 -292.50005)
		(width 0.4572)
		(layer "F.Cu")
		(net "P3V3_AUX")
	)
	(segment
		(start 20.955 -153.8986)
		(end 21.18995 -154.13355)
		(width 0.3556)
		(layer "F.Cu")
		(net "P3V3_AUX")
	)
	(segment
		(start 9.6139 -171.5389)
		(end 9.906 -171.831)
		(width 0.4572)
		(layer "F.Cu")
		(net "P3V3_AUX")
	)
	(segment
		(start 30.734 -163.34105)
		(end 28.956 -163.34105)
		(width 0.4572)
		(layer "F.Cu")
		(net "P3V3_AUX")
	)
	(segment
		(start 32.385 -105.918)
		(end 31.322518 -104.855518)
		(width 0.4572)
		(layer "F.Cu")
		(net "P3V3_AUX")
	)
	(segment
		(start 31.599886 -140.974064)
		(end 31.623 -140.95095)
		(width 0.4572)
		(layer "F.Cu")
		(net "P3V3_AUX")
	)
	(segment
		(start 9.525 -173.228)
		(end 8.95604 -173.228)
		(width 0.4572)
		(layer "F.Cu")
		(net "P3V3_AUX")
	)
	(segment
		(start 10.3632 -183.515)
		(end 8.509 -181.6608)
		(width 0.4572)
		(layer "F.Cu")
		(net "P3V3_AUX")
	)
	(segment
		(start 21.717 -303.12995)
		(end 21.95195 -303.12995)
		(width 0.4572)
		(layer "F.Cu")
		(net "P3V3_AUX")
	)
	(segment
		(start 9.733534 -66.986912)
		(end 9.87552 -66.844926)
		(width 0.4572)
		(layer "F.Cu")
		(net "P3V3_AUX")
	)
	(segment
		(start 22.675342 -175.444658)
		(end 22.352 -175.768)
		(width 0.4572)
		(layer "F.Cu")
		(net "P3V3_AUX")
	)
	(segment
		(start 23.499064 -25.450292)
		(end 22.555708 -25.450292)
		(width 0.4572)
		(layer "F.Cu")
		(net "P3V3_AUX")
	)
	(segment
		(start 17.279366 -72.077834)
		(end 16.906494 -71.704962)
		(width 0.4572)
		(layer "F.Cu")
		(net "P3V3_AUX")
	)
	(segment
		(start 8.95604 -166.878)
		(end 8.32104 -166.878)
		(width 0.4572)
		(layer "F.Cu")
		(net "P3V3_AUX")
	)
	(segment
		(start 28.575 -23.8252)
		(end 29.14015 -23.26005)
		(width 0.4572)
		(layer "F.Cu")
		(net "P3V3_AUX")
	)
	(segment
		(start 25.6921 -119.52605)
		(end 23.241 -119.52605)
		(width 0.4572)
		(layer "F.Cu")
		(net "P3V3_AUX")
	)
	(segment
		(start 27.178 -101.70795)
		(end 26.89225 -101.70795)
		(width 0.4572)
		(layer "F.Cu")
		(net "P3V3_AUX")
	)
	(segment
		(start 29.95295 -185.674)
		(end 29.34335 -185.674)
		(width 0.4572)
		(layer "F.Cu")
		(net "P3V3_AUX")
	)
	(segment
		(start 32.258 -21.69795)
		(end 31.579566 -21.69795)
		(width 0.4572)
		(layer "F.Cu")
		(net "P3V3_AUX")
	)
	(segment
		(start 11.172444 -256.413)
		(end 10.548874 -256.413)
		(width 0.4572)
		(layer "F.Cu")
		(net "P3V3_AUX")
	)
	(segment
		(start 21.69795 -114.427)
		(end 21.34235 -114.7826)
		(width 0.4572)
		(layer "F.Cu")
		(net "P3V3_AUX")
	)
	(segment
		(start 18.81505 -178.816)
		(end 19.431 -178.816)
		(width 0.4572)
		(layer "F.Cu")
		(net "P3V3_AUX")
	)
	(segment
		(start 26.409904 -23.786846)
		(end 26.448258 -23.8252)
		(width 0.4572)
		(layer "F.Cu")
		(net "P3V3_AUX")
	)
	(segment
		(start 29.106114 -141.228064)
		(end 29.688536 -141.228064)
		(width 0.381)
		(layer "F.Cu")
		(net "P3V3_AUX")
	)
	(segment
		(start 36.322 -143.806926)
		(end 36.129468 -144.271746)
		(width 0.381)
		(layer "F.Cu")
		(net "P3V3_AUX")
	)
	(segment
		(start 8.509 -181.6608)
		(end 8.509 -177.673)
		(width 0.4572)
		(layer "F.Cu")
		(net "P3V3_AUX")
	)
	(segment
		(start 18.01495 -190.246)
		(end 18.01495 -190.881)
		(width 0.4572)
		(layer "F.Cu")
		(net "P3V3_AUX")
	)
	(segment
		(start 22.75205 -303.93005)
		(end 23.241 -303.93005)
		(width 0.4572)
		(layer "F.Cu")
		(net "P3V3_AUX")
	)
	(segment
		(start 25.654 -141.20495)
		(end 27.305 -141.20495)
		(width 0.381)
		(layer "F.Cu")
		(net "P3V3_AUX")
	)
	(segment
		(start 15.570454 -185.039)
		(end 15.621 -185.039)
		(width 0.4572)
		(layer "F.Cu")
		(net "P3V3_AUX")
	)
	(segment
		(start 29.845 -195.21805)
		(end 29.732986 -195.330064)
		(width 0.4572)
		(layer "F.Cu")
		(net "P3V3_AUX")
	)
	(segment
		(start 28.194 -141.20495)
		(end 27.305 -141.20495)
		(width 0.381)
		(layer "F.Cu")
		(net "P3V3_AUX")
	)
	(segment
		(start 6.07695 -173.609)
		(end 6.11505 -173.5709)
		(width 0.4572)
		(layer "F.Cu")
		(net "P3V3_AUX")
	)
	(segment
		(start 32.385 -106.27995)
		(end 32.385 -105.918)
		(width 0.4572)
		(layer "F.Cu")
		(net "P3V3_AUX")
	)
	(segment
		(start 25.12695 -135.001)
		(end 25.12695 -135.636)
		(width 0.4572)
		(layer "F.Cu")
		(net "P3V3_AUX")
	)
	(segment
		(start 29.859986 -104.408986)
		(end 29.859986 -103.69804)
		(width 0.4572)
		(layer "F.Cu")
		(net "P3V3_AUX")
	)
	(segment
		(start 38.62705 -184.80405)
		(end 38.1 -184.277)
		(width 0.4572)
		(layer "F.Cu")
		(net "P3V3_AUX")
	)
	(segment
		(start 18.161 -204.597)
		(end 19.06905 -204.597)
		(width 0.4572)
		(layer "F.Cu")
		(net "P3V3_AUX")
	)
	(segment
		(start 22.675342 -174.20082)
		(end 22.675342 -175.444658)
		(width 0.4572)
		(layer "F.Cu")
		(net "P3V3_AUX")
	)
	(segment
		(start 25.527 -106.172)
		(end 26.162 -106.807)
		(width 0.4572)
		(layer "F.Cu")
		(net "P3V3_AUX")
	)
	(segment
		(start 33.401 -167.37965)
		(end 33.401 -168.00195)
		(width 0.3556)
		(layer "F.Cu")
		(net "P3V3_AUX")
	)
	(segment
		(start 29.464 -133.07695)
		(end 29.464 -132.334)
		(width 0.4572)
		(layer "F.Cu")
		(net "P3V3_AUX")
	)
	(segment
		(start 34.229294 -67.094862)
		(end 33.916366 -67.40779)
		(width 0.4572)
		(layer "F.Cu")
		(net "P3V3_AUX")
	)
	(segment
		(start 6.07695 -162.814)
		(end 6.07695 -163.957)
		(width 0.4572)
		(layer "F.Cu")
		(net "P3V3_AUX")
	)
	(via
		(at 19.42465 -188.595)
		(size 0.508)
		(drill 0.254)
		(layers "F.Cu" "B.Cu")
		(net "P3V3_AUX")
	)
	(via
		(at 9.87552 -251.445014)
		(size 0.508)
		(drill 0.254)
		(layers "F.Cu" "B.Cu")
		(net "P3V3_AUX")
	)
	(via
		(at 25.12695 -130.81)
		(size 0.508)
		(drill 0.254)
		(layers "F.Cu" "B.Cu")
		(net "P3V3_AUX")
	)
	(via
		(at 23.622 -134.994904)
		(size 0.508)
		(drill 0.254)
		(layers "F.Cu" "B.Cu")
		(net "P3V3_AUX")
	)
	(via
		(at 33.916366 -252.807724)
		(size 0.508)
		(drill 0.254)
		(layers "F.Cu" "B.Cu")
		(net "P3V3_AUX")
	)
	(via
		(at 21.844 -171.704)
		(size 0.508)
		(drill 0.254)
		(layers "F.Cu" "B.Cu")
		(net "P3V3_AUX")
	)
	(via
		(at 38.041326 -256.554986)
		(size 0.508)
		(drill 0.254)
		(layers "F.Cu" "B.Cu")
		(net "P3V3_AUX")
	)
	(via
		(at 48.514 -192.151)
		(size 0.508)
		(drill 0.254)
		(layers "F.Cu" "B.Cu")
		(net "P3V3_AUX")
	)
	(via
		(at 48.006 -192.659)
		(size 0.508)
		(drill 0.254)
		(layers "F.Cu" "B.Cu")
		(net "P3V3_AUX")
	)
	(via
		(at 26.86304 -125.349)
		(size 0.508)
		(drill 0.254)
		(layers "F.Cu" "B.Cu")
		(net "P3V3_AUX")
	)
	(via
		(at 41.041574 -252.900942)
		(size 0.508)
		(drill 0.254)
		(layers "F.Cu" "B.Cu")
		(net "P3V3_AUX")
	)
	(via
		(at 29.34335 -189.23)
		(size 0.508)
		(drill 0.254)
		(layers "F.Cu" "B.Cu")
		(net "P3V3_AUX")
	)
	(via
		(at 22.555708 -25.450292)
		(size 0.508)
		(drill 0.254)
		(layers "F.Cu" "B.Cu")
		(net "P3V3_AUX")
	)
	(via
		(at 14.34465 -169.291)
		(size 0.508)
		(drill 0.254)
		(layers "F.Cu" "B.Cu")
		(net "P3V3_AUX")
	)
	(via
		(at 2.498852 -252.661166)
		(size 0.508)
		(drill 0.254)
		(layers "F.Cu" "B.Cu")
		(net "P3V3_AUX")
	)
	(via
		(at 19.431 -295.39565)
		(size 0.508)
		(drill 0.254)
		(layers "F.Cu" "B.Cu")
		(net "P3V3_AUX")
	)
	(via
		(at 19.431 -178.816)
		(size 0.508)
		(drill 0.254)
		(layers "F.Cu" "B.Cu")
		(net "P3V3_AUX")
	)
	(via
		(at 36.321746 -213.9569)
		(size 0.508)
		(drill 0.254)
		(layers "F.Cu" "B.Cu")
		(net "P3V3_AUX")
	)
	(via
		(at 14.34465 -167.64)
		(size 0.508)
		(drill 0.254)
		(layers "F.Cu" "B.Cu")
		(net "P3V3_AUX")
	)
	(via
		(at 29.972 -292.50005)
		(size 0.508)
		(drill 0.254)
		(layers "F.Cu" "B.Cu")
		(net "P3V3_AUX")
	)
	(via
		(at 33.02 -123.19635)
		(size 0.508)
		(drill 0.254)
		(layers "F.Cu" "B.Cu")
		(net "P3V3_AUX")
	)
	(via
		(at 28.194 -141.20495)
		(size 0.508)
		(drill 0.254)
		(layers "F.Cu" "B.Cu")
		(net "P3V3_AUX")
	)
	(via
		(at 5.334 -163.576)
		(size 0.508)
		(drill 0.254)
		(layers "F.Cu" "B.Cu")
		(net "P3V3_AUX")
	)
	(via
		(at 8.32104 -170.053)
		(size 0.508)
		(drill 0.254)
		(layers "F.Cu" "B.Cu")
		(net "P3V3_AUX")
	)
	(via
		(at 14.34465 -162.814)
		(size 0.508)
		(drill 0.254)
		(layers "F.Cu" "B.Cu")
		(net "P3V3_AUX")
	)
	(via
		(at 32.639 -201.041)
		(size 0.508)
		(drill 0.254)
		(layers "F.Cu" "B.Cu")
		(net "P3V3_AUX")
	)
	(via
		(at 19.558 -208.026)
		(size 0.508)
		(drill 0.254)
		(layers "F.Cu" "B.Cu")
		(net "P3V3_AUX")
	)
	(via
		(at 3.248914 -66.294)
		(size 0.508)
		(drill 0.254)
		(layers "F.Cu" "B.Cu")
		(net "P3V3_AUX")
	)
	(via
		(at 18.542 -256.667)
		(size 0.508)
		(drill 0.254)
		(layers "F.Cu" "B.Cu")
		(net "P3V3_AUX")
	)
	(via
		(at 5.46735 -170.815)
		(size 0.508)
		(drill 0.254)
		(layers "F.Cu" "B.Cu")
		(net "P3V3_AUX")
	)
	(via
		(at 14.34465 -170.815)
		(size 0.508)
		(drill 0.254)
		(layers "F.Cu" "B.Cu")
		(net "P3V3_AUX")
	)
	(via
		(at 27.94 -286.61995)
		(size 0.508)
		(drill 0.254)
		(layers "F.Cu" "B.Cu")
		(net "P3V3_AUX")
	)
	(via
		(at 5.46735 -169.291)
		(size 0.508)
		(drill 0.254)
		(layers "F.Cu" "B.Cu")
		(net "P3V3_AUX")
	)
	(via
		(at 43.04665 -179.324)
		(size 0.508)
		(drill 0.254)
		(layers "F.Cu" "B.Cu")
		(net "P3V3_AUX")
	)
	(via
		(at 20.828 -134.994904)
		(size 0.508)
		(drill 0.254)
		(layers "F.Cu" "B.Cu")
		(net "P3V3_AUX")
	)
	(via
		(at 28.067 -113.03)
		(size 0.508)
		(drill 0.254)
		(layers "F.Cu" "B.Cu")
		(net "P3V3_AUX")
	)
	(via
		(at 30.734 -287.42005)
		(size 0.508)
		(drill 0.254)
		(layers "F.Cu" "B.Cu")
		(net "P3V3_AUX")
	)
	(via
		(at 3.302 -180.086)
		(size 0.508)
		(drill 0.254)
		(layers "F.Cu" "B.Cu")
		(net "P3V3_AUX")
	)
	(via
		(at 14.34465 -164.338)
		(size 0.508)
		(drill 0.254)
		(layers "F.Cu" "B.Cu")
		(net "P3V3_AUX")
	)
	(via
		(at 21.07565 -13.546582)
		(size 0.508)
		(drill 0.254)
		(layers "F.Cu" "B.Cu")
		(net "P3V3_AUX")
	)
	(via
		(at 33.916366 -67.40779)
		(size 0.508)
		(drill 0.254)
		(layers "F.Cu" "B.Cu")
		(net "P3V3_AUX")
	)
	(via
		(at 2.794 -127.508)
		(size 0.508)
		(drill 0.254)
		(layers "F.Cu" "B.Cu")
		(net "P3V3_AUX")
	)
	(via
		(at 27.686 -127)
		(size 0.508)
		(drill 0.254)
		(layers "F.Cu" "B.Cu")
		(net "P3V3_AUX")
	)
	(via
		(at 18.01495 -185.928)
		(size 0.508)
		(drill 0.254)
		(layers "F.Cu" "B.Cu")
		(net "P3V3_AUX")
	)
	(via
		(at 44.704 -167.513)
		(size 0.508)
		(drill 0.254)
		(layers "F.Cu" "B.Cu")
		(net "P3V3_AUX")
	)
	(via
		(at 2.790698 -132.948172)
		(size 0.508)
		(drill 0.254)
		(layers "F.Cu" "B.Cu")
		(net "P3V3_AUX")
	)
	(via
		(at 14.34465 -166.116)
		(size 0.508)
		(drill 0.254)
		(layers "F.Cu" "B.Cu")
		(net "P3V3_AUX")
	)
	(via
		(at 35.3441 -180.975)
		(size 0.508)
		(drill 0.254)
		(layers "F.Cu" "B.Cu")
		(net "P3V3_AUX")
	)
	(via
		(at 21.844 -173.736)
		(size 0.508)
		(drill 0.254)
		(layers "F.Cu" "B.Cu")
		(net "P3V3_AUX")
	)
	(via
		(at 43.04665 -186.182)
		(size 0.508)
		(drill 0.254)
		(layers "F.Cu" "B.Cu")
		(net "P3V3_AUX")
	)
	(via
		(at 31.623 -123.19)
		(size 0.508)
		(drill 0.254)
		(layers "F.Cu" "B.Cu")
		(net "P3V3_AUX")
	)
	(via
		(at 43.04665 -181.102)
		(size 0.508)
		(drill 0.254)
		(layers "F.Cu" "B.Cu")
		(net "P3V3_AUX")
	)
	(via
		(at 32.258 -293.88435)
		(size 0.508)
		(drill 0.254)
		(layers "F.Cu" "B.Cu")
		(net "P3V3_AUX")
	)
	(via
		(at 30.353 -181.737)
		(size 0.508)
		(drill 0.254)
		(layers "F.Cu" "B.Cu")
		(net "P3V3_AUX")
	)
	(via
		(at 8.32104 -173.228)
		(size 0.508)
		(drill 0.254)
		(layers "F.Cu" "B.Cu")
		(net "P3V3_AUX")
	)
	(via
		(at 4.445 -189.992)
		(size 0.508)
		(drill 0.254)
		(layers "F.Cu" "B.Cu")
		(net "P3V3_AUX")
	)
	(via
		(at 2.794 -129.794)
		(size 0.508)
		(drill 0.254)
		(layers "F.Cu" "B.Cu")
		(net "P3V3_AUX")
	)
	(via
		(at 42.926 -135.90905)
		(size 0.508)
		(drill 0.254)
		(layers "F.Cu" "B.Cu")
		(net "P3V3_AUX")
	)
	(via
		(at 30.353 -179.705)
		(size 0.508)
		(drill 0.254)
		(layers "F.Cu" "B.Cu")
		(net "P3V3_AUX")
	)
	(via
		(at 8.32104 -166.878)
		(size 0.508)
		(drill 0.254)
		(layers "F.Cu" "B.Cu")
		(net "P3V3_AUX")
	)
	(via
		(at 43.04665 -189.738)
		(size 0.508)
		(drill 0.254)
		(layers "F.Cu" "B.Cu")
		(net "P3V3_AUX")
	)
	(via
		(at 32.258 -290.322)
		(size 0.508)
		(drill 0.254)
		(layers "F.Cu" "B.Cu")
		(net "P3V3_AUX")
	)
	(via
		(at 10.406888 -256.554986)
		(size 0.508)
		(drill 0.254)
		(layers "F.Cu" "B.Cu")
		(net "P3V3_AUX")
	)
	(via
		(at 29.34335 -187.452)
		(size 0.508)
		(drill 0.254)
		(layers "F.Cu" "B.Cu")
		(net "P3V3_AUX")
	)
	(via
		(at 14.34465 -173.99)
		(size 0.508)
		(drill 0.254)
		(layers "F.Cu" "B.Cu")
		(net "P3V3_AUX")
	)
	(via
		(at 28.829 -123.19)
		(size 0.508)
		(drill 0.254)
		(layers "F.Cu" "B.Cu")
		(net "P3V3_AUX")
	)
	(via
		(at 10.279888 -71.954898)
		(size 0.508)
		(drill 0.254)
		(layers "F.Cu" "B.Cu")
		(net "P3V3_AUX")
	)
	(via
		(at 18.796 -154.53995)
		(size 0.508)
		(drill 0.254)
		(layers "F.Cu" "B.Cu")
		(net "P3V3_AUX")
	)
	(via
		(at 20.574 -303.12995)
		(size 0.508)
		(drill 0.254)
		(layers "F.Cu" "B.Cu")
		(net "P3V3_AUX")
	)
	(via
		(at 22.225 -134.994904)
		(size 0.508)
		(drill 0.254)
		(layers "F.Cu" "B.Cu")
		(net "P3V3_AUX")
	)
	(via
		(at 21.3487 -141.20495)
		(size 0.508)
		(drill 0.254)
		(layers "F.Cu" "B.Cu")
		(net "P3V3_AUX")
	)
	(via
		(at 19.431 -134.994904)
		(size 0.508)
		(drill 0.254)
		(layers "F.Cu" "B.Cu")
		(net "P3V3_AUX")
	)
	(via
		(at 27.178 -101.70795)
		(size 0.508)
		(drill 0.254)
		(layers "F.Cu" "B.Cu")
		(net "P3V3_AUX")
	)
	(via
		(at 4.445 -188.214)
		(size 0.508)
		(drill 0.254)
		(layers "F.Cu" "B.Cu")
		(net "P3V3_AUX")
	)
	(via
		(at 28.522676 -191.590676)
		(size 0.508)
		(drill 0.254)
		(layers "F.Cu" "B.Cu")
		(net "P3V3_AUX")
	)
	(via
		(at 30.226 -123.19)
		(size 0.508)
		(drill 0.254)
		(layers "F.Cu" "B.Cu")
		(net "P3V3_AUX")
	)
	(via
		(at 45.466 -135.10895)
		(size 0.508)
		(drill 0.254)
		(layers "F.Cu" "B.Cu")
		(net "P3V3_AUX")
	)
	(via
		(at 25.12695 -135.636)
		(size 0.508)
		(drill 0.254)
		(layers "F.Cu" "B.Cu")
		(net "P3V3_AUX")
	)
	(via
		(at 19.42465 -181.61)
		(size 0.508)
		(drill 0.254)
		(layers "F.Cu" "B.Cu")
		(net "P3V3_AUX")
	)
	(via
		(at 8.193532 -164.084)
		(size 0.508)
		(drill 0.254)
		(layers "F.Cu" "B.Cu")
		(net "P3V3_AUX")
	)
	(via
		(at 23.114 -298.04995)
		(size 0.508)
		(drill 0.254)
		(layers "F.Cu" "B.Cu")
		(net "P3V3_AUX")
	)
	(via
		(at 29.34335 -185.674)
		(size 0.508)
		(drill 0.254)
		(layers "F.Cu" "B.Cu")
		(net "P3V3_AUX")
	)
	(via
		(at 7.493 -135.65505)
		(size 0.508)
		(drill 0.254)
		(layers "F.Cu" "B.Cu")
		(net "P3V3_AUX")
	)
	(via
		(at 15.621 -185.039)
		(size 0.508)
		(drill 0.254)
		(layers "F.Cu" "B.Cu")
		(net "P3V3_AUX")
	)
	(via
		(at 40.92067 -67.584574)
		(size 0.508)
		(drill 0.254)
		(layers "F.Cu" "B.Cu")
		(net "P3V3_AUX")
	)
	(via
		(at 18.415 -72.077834)
		(size 0.508)
		(drill 0.254)
		(layers "F.Cu" "B.Cu")
		(net "P3V3_AUX")
	)
	(via
		(at 9.87552 -66.844926)
		(size 0.508)
		(drill 0.254)
		(layers "F.Cu" "B.Cu")
		(net "P3V3_AUX")
	)
	(via
		(at 21.48205 -123.71705)
		(size 0.508)
		(drill 0.254)
		(layers "F.Cu" "B.Cu")
		(net "P3V3_AUX")
	)
	(via
		(at 20.092924 -298.85005)
		(size 0.508)
		(drill 0.254)
		(layers "F.Cu" "B.Cu")
		(net "P3V3_AUX")
	)
	(via
		(at 4.445 -186.436)
		(size 0.508)
		(drill 0.254)
		(layers "F.Cu" "B.Cu")
		(net "P3V3_AUX")
	)
	(via
		(at 21.844 -177.8)
		(size 0.508)
		(drill 0.254)
		(layers "F.Cu" "B.Cu")
		(net "P3V3_AUX")
	)
	(via
		(at 32.83839 -198.576946)
		(size 0.508)
		(drill 0.254)
		(layers "F.Cu" "B.Cu")
		(net "P3V3_AUX")
	)
	(via
		(at 48.133 -130.048)
		(size 0.508)
		(drill 0.254)
		(layers "F.Cu" "B.Cu")
		(net "P3V3_AUX")
	)
	(via
		(at 44.577 -165.481)
		(size 0.508)
		(drill 0.254)
		(layers "F.Cu" "B.Cu")
		(net "P3V3_AUX")
	)
	(via
		(at 18.161 -204.597)
		(size 0.508)
		(drill 0.254)
		(layers "F.Cu" "B.Cu")
		(net "P3V3_AUX")
	)
	(via
		(at 5.46735 -166.116)
		(size 0.508)
		(drill 0.254)
		(layers "F.Cu" "B.Cu")
		(net "P3V3_AUX")
	)
	(via
		(at 32.639 -140.95095)
		(size 0.508)
		(drill 0.254)
		(layers "F.Cu" "B.Cu")
		(net "P3V3_AUX")
	)
	(via
		(at 5.46735 -167.64)
		(size 0.508)
		(drill 0.254)
		(layers "F.Cu" "B.Cu")
		(net "P3V3_AUX")
	)
	(via
		(at 41.63695 -192.151)
		(size 0.508)
		(drill 0.254)
		(layers "F.Cu" "B.Cu")
		(net "P3V3_AUX")
	)
	(via
		(at 49.022 -191.643)
		(size 0.508)
		(drill 0.254)
		(layers "F.Cu" "B.Cu")
		(net "P3V3_AUX")
	)
	(via
		(at 45.417994 -255.992122)
		(size 0.508)
		(drill 0.254)
		(layers "F.Cu" "B.Cu")
		(net "P3V3_AUX")
	)
	(via
		(at 43.04665 -187.96)
		(size 0.508)
		(drill 0.254)
		(layers "F.Cu" "B.Cu")
		(net "P3V3_AUX")
	)
	(via
		(at 34.417 -123.196096)
		(size 0.508)
		(drill 0.254)
		(layers "F.Cu" "B.Cu")
		(net "P3V3_AUX")
	)
	(via
		(at 18.731738 -144.96161)
		(size 0.508)
		(drill 0.254)
		(layers "F.Cu" "B.Cu")
		(net "P3V3_AUX")
	)
	(via
		(at 19.431 -180.213)
		(size 0.508)
		(drill 0.254)
		(layers "F.Cu" "B.Cu")
		(net "P3V3_AUX")
	)
	(via
		(at 45.417994 -71.392034)
		(size 0.508)
		(drill 0.254)
		(layers "F.Cu" "B.Cu")
		(net "P3V3_AUX")
	)
	(via
		(at 28.829 -132.842)
		(size 0.508)
		(drill 0.254)
		(layers "F.Cu" "B.Cu")
		(net "P3V3_AUX")
	)
	(via
		(at 49.53 -191.135)
		(size 0.508)
		(drill 0.254)
		(layers "F.Cu" "B.Cu")
		(net "P3V3_AUX")
	)
	(via
		(at 18.01495 -190.246)
		(size 0.508)
		(drill 0.254)
		(layers "F.Cu" "B.Cu")
		(net "P3V3_AUX")
	)
	(via
		(at 14.34465 -172.466)
		(size 0.508)
		(drill 0.254)
		(layers "F.Cu" "B.Cu")
		(net "P3V3_AUX")
	)
	(via
		(at 43.04665 -182.88)
		(size 0.508)
		(drill 0.254)
		(layers "F.Cu" "B.Cu")
		(net "P3V3_AUX")
	)
	(via
		(at 38.041326 -71.954898)
		(size 0.508)
		(drill 0.254)
		(layers "F.Cu" "B.Cu")
		(net "P3V3_AUX")
	)
	(segment
		(start 3.57632 -129.794)
		(end 2.794 -129.794)
		(width 0.4572)
		(layer "B.Cu")
		(net "P3V3_AUX")
	)
	(segment
		(start 2.82448 -127.47752)
		(end 2.794 -127.508)
		(width 0.4572)
		(layer "B.Cu")
		(net "P3V3_AUX")
	)
	(segment
		(start 3.059938 -66.482976)
		(end 3.059938 -67.045078)
		(width 0.4572)
		(layer "B.Cu")
		(net "P3V3_AUX")
	)
	(segment
		(start 33.916366 -252.121924)
		(end 33.916366 -252.807724)
		(width 0.4572)
		(layer "B.Cu")
		(net "P3V3_AUX")
	)
	(segment
		(start 3.49504 -127.47752)
		(end 2.82448 -127.47752)
		(width 0.4572)
		(layer "B.Cu")
		(net "P3V3_AUX")
	)
	(segment
		(start 8.91032 -251.445014)
		(end 9.87552 -251.445014)
		(width 0.3302)
		(layer "B.Cu")
		(net "P3V3_AUX")
	)
	(segment
		(start 39.006526 -71.954898)
		(end 38.041326 -71.954898)
		(width 0.3302)
		(layer "B.Cu")
		(net "P3V3_AUX")
	)
	(segment
		(start 11.245088 -71.954898)
		(end 10.279888 -71.954898)
		(width 0.3302)
		(layer "B.Cu")
		(net "P3V3_AUX")
	)
	(segment
		(start 8.91032 -66.844926)
		(end 9.87552 -66.844926)
		(width 0.3302)
		(layer "B.Cu")
		(net "P3V3_AUX")
	)
	(segment
		(start 40.46982 -252.386846)
		(end 40.327834 -252.24486)
		(width 0.3302)
		(layer "B.Cu")
		(net "P3V3_AUX")
	)
	(segment
		(start 40.327834 -66.844926)
		(end 40.92067 -67.437762)
		(width 0.3302)
		(layer "B.Cu")
		(net "P3V3_AUX")
	)
	(segment
		(start 3.059938 -251.830078)
		(end 2.956052 -251.830078)
		(width 0.4572)
		(layer "B.Cu")
		(net "P3V3_AUX")
	)
	(segment
		(start 18.415 -72.077834)
		(end 17.656556 -72.077834)
		(width 0.4572)
		(layer "B.Cu")
		(net "P3V3_AUX")
	)
	(segment
		(start 11.372088 -256.554986)
		(end 10.406888 -256.554986)
		(width 0.3302)
		(layer "B.Cu")
		(net "P3V3_AUX")
	)
	(segment
		(start 40.527478 -252.386846)
		(end 40.46982 -252.386846)
		(width 0.3302)
		(layer "B.Cu")
		(net "P3V3_AUX")
	)
	(segment
		(start 18.415 -256.667)
		(end 18.404078 -256.677922)
		(width 0.4572)
		(layer "B.Cu")
		(net "P3V3_AUX")
	)
	(segment
		(start 3.248914 -66.294)
		(end 3.059938 -66.482976)
		(width 0.4572)
		(layer "B.Cu")
		(net "P3V3_AUX")
	)
	(segment
		(start 2.82321 -132.91566)
		(end 2.790698 -132.948172)
		(width 0.4572)
		(layer "B.Cu")
		(net "P3V3_AUX")
	)
	(segment
		(start 3.58902 -132.91566)
		(end 2.82321 -132.91566)
		(width 0.4572)
		(layer "B.Cu")
		(net "P3V3_AUX")
	)
	(segment
		(start 21.079968 -7.869428)
		(end 21.079968 -4.350004)
		(width 0.8128)
		(layer "B.Cu")
		(net "P3V3_AUX")
	)
	(segment
		(start 21.07565 -13.546582)
		(end 21.07565 -12.97305)
		(width 0.4572)
		(layer "B.Cu")
		(net "P3V3_AUX")
	)
	(segment
		(start 39.006526 -256.554986)
		(end 38.041326 -256.554986)
		(width 0.3302)
		(layer "B.Cu")
		(net "P3V3_AUX")
	)
	(segment
		(start 20.9042 -12.8016)
		(end 20.9042 -8.045196)
		(width 0.8128)
		(layer "B.Cu")
		(net "P3V3_AUX")
	)
	(segment
		(start 41.041574 -252.900942)
		(end 40.527478 -252.386846)
		(width 0.3302)
		(layer "B.Cu")
		(net "P3V3_AUX")
	)
	(segment
		(start 18.542 -256.667)
		(end 18.415 -256.667)
		(width 0.4572)
		(layer "B.Cu")
		(net "P3V3_AUX")
	)
	(segment
		(start 33.916366 -66.72199)
		(end 33.916366 -67.40779)
		(width 0.4572)
		(layer "B.Cu")
		(net "P3V3_AUX")
	)
	(segment
		(start 2.498852 -252.287278)
		(end 2.498852 -252.661166)
		(width 0.4572)
		(layer "B.Cu")
		(net "P3V3_AUX")
	)
	(segment
		(start 18.404078 -256.677922)
		(end 17.783556 -256.677922)
		(width 0.4572)
		(layer "B.Cu")
		(net "P3V3_AUX")
	)
	(segment
		(start 21.07565 -12.97305)
		(end 20.9042 -12.8016)
		(width 0.4572)
		(layer "B.Cu")
		(net "P3V3_AUX")
	)
	(segment
		(start 20.9042 -8.045196)
		(end 21.079968 -7.869428)
		(width 0.8128)
		(layer "B.Cu")
		(net "P3V3_AUX")
	)
	(segment
		(start 45.417994 -72.077834)
		(end 45.417994 -71.392034)
		(width 0.4572)
		(layer "B.Cu")
		(net "P3V3_AUX")
	)
	(segment
		(start 45.417994 -256.677922)
		(end 45.417994 -255.992122)
		(width 0.4572)
		(layer "B.Cu")
		(net "P3V3_AUX")
	)
	(segment
		(start 2.956052 -251.830078)
		(end 2.498852 -252.287278)
		(width 0.4572)
		(layer "B.Cu")
		(net "P3V3_AUX")
	)
	(segment
		(start 40.92067 -67.437762)
		(end 40.92067 -67.584574)
		(width 0.3302)
		(layer "B.Cu")
		(net "P3V3_AUX")
	)
	(segment
		(start 28.454604 -103.70947)
		(end 28.454604 -102.349554)
		(width 0.4572)
		(layer "In2.Cu")
		(net "P3V3_AUX")
	)
	(segment
		(start 28.067 -113.03)
		(end 27.7876 -112.7506)
		(width 0.4572)
		(layer "In2.Cu")
		(net "P3V3_AUX")
	)
	(segment
		(start 27.327098 -104.836976)
		(end 28.454604 -103.70947)
		(width 0.4572)
		(layer "In2.Cu")
		(net "P3V3_AUX")
	)
	(segment
		(start 27.327098 -111.400844)
		(end 27.327098 -104.836976)
		(width 0.4572)
		(layer "In2.Cu")
		(net "P3V3_AUX")
	)
	(segment
		(start 27.7876 -112.7506)
		(end 27.7876 -111.861346)
		(width 0.4572)
		(layer "In2.Cu")
		(net "P3V3_AUX")
	)
	(segment
		(start 28.454604 -102.349554)
		(end 27.813 -101.70795)
		(width 0.4572)
		(layer "In2.Cu")
		(net "P3V3_AUX")
	)
	(segment
		(start 27.813 -101.70795)
		(end 27.178 -101.70795)
		(width 0.4572)
		(layer "In2.Cu")
		(net "P3V3_AUX")
	)
	(segment
		(start 27.7876 -111.861346)
		(end 27.327098 -111.400844)
		(width 0.4572)
		(layer "In2.Cu")
		(net "P3V3_AUX")
	)
	(segment
		(start 16.129 -258.17195)
		(end 16.02105 -258.064)
		(width 0.2794)
		(layer "F.Cu")
		(net "FAN_7_FAULT_R")
	)
	(segment
		(start 16.02105 -258.064)
		(end 15.13205 -258.064)
		(width 0.2794)
		(layer "F.Cu")
		(net "FAN_7_FAULT_R")
	)
	(segment
		(start 17.50695 -183.134)
		(end 18.01495 -182.626)
		(width 0.2794)
		(layer "F.Cu")
		(net "SMB_PDBV_FAN_R_IOX_SCL")
	)
	(segment
		(start 17.2974 -183.134)
		(end 16.814546 -183.134)
		(width 0.2794)
		(layer "F.Cu")
		(net "SMB_PDBV_FAN_R_IOX_SCL")
	)
	(segment
		(start 16.814546 -183.134)
		(end 15.914624 -182.234078)
		(width 0.2794)
		(layer "F.Cu")
		(net "SMB_PDBV_FAN_R_IOX_SCL")
	)
	(segment
		(start 17.2974 -183.134)
		(end 17.50695 -183.134)
		(width 0.2794)
		(layer "F.Cu")
		(net "SMB_PDBV_FAN_R_IOX_SCL")
	)
	(segment
		(start 15.914624 -182.234078)
		(end 13.208 -182.234078)
		(width 0.2794)
		(layer "F.Cu")
		(net "SMB_PDBV_FAN_R_IOX_SCL")
	)
	(via
		(at 17.2974 -183.134)
		(size 0.508)
		(drill 0.254)
		(layers "F.Cu" "B.Cu")
		(net "SMB_PDBV_FAN_R_IOX_SCL")
	)
	(segment
		(start 23.876 -199.954134)
		(end 25.216866 -198.613268)
		(width 0.2794)
		(layer "F.Cu")
		(net "SMB_FAN6_SCL")
	)
	(segment
		(start 21.444966 -202.280266)
		(end 22.70379 -202.280266)
		(width 0.2794)
		(layer "F.Cu")
		(net "SMB_FAN6_SCL")
	)
	(segment
		(start 19.8247 -200.66)
		(end 21.444966 -202.280266)
		(width 0.2794)
		(layer "F.Cu")
		(net "SMB_FAN6_SCL")
	)
	(segment
		(start 23.876 -201.108056)
		(end 23.876 -199.954134)
		(width 0.2794)
		(layer "F.Cu")
		(net "SMB_FAN6_SCL")
	)
	(segment
		(start 22.70379 -202.280266)
		(end 23.876 -201.108056)
		(width 0.2794)
		(layer "F.Cu")
		(net "SMB_FAN6_SCL")
	)
	(segment
		(start 24.892 -160.54705)
		(end 24.892 -161.036)
		(width 0.2794)
		(layer "F.Cu")
		(net "SMB_FAN6_SCL")
	)
	(segment
		(start 15.027656 -200.180956)
		(end 15.5067 -200.66)
		(width 0.2794)
		(layer "F.Cu")
		(net "SMB_FAN6_SCL")
	)
	(segment
		(start 15.5067 -200.66)
		(end 19.8247 -200.66)
		(width 0.2794)
		(layer "F.Cu")
		(net "SMB_FAN6_SCL")
	)
	(segment
		(start 25.019 -160.42005)
		(end 24.892 -160.54705)
		(width 0.2794)
		(layer "F.Cu")
		(net "SMB_FAN6_SCL")
	)
	(segment
		(start 24.892 -161.036)
		(end 25.158954 -161.302954)
		(width 0.2794)
		(layer "F.Cu")
		(net "SMB_FAN6_SCL")
	)
	(segment
		(start 14.75105 -200.180956)
		(end 15.027656 -200.180956)
		(width 0.2794)
		(layer "F.Cu")
		(net "SMB_FAN6_SCL")
	)
	(via
		(at 25.216866 -198.613268)
		(size 0.508)
		(drill 0.254)
		(layers "F.Cu" "B.Cu")
		(net "SMB_FAN6_SCL")
	)
	(via
		(at 25.158954 -161.302954)
		(size 0.508)
		(drill 0.254)
		(layers "F.Cu" "B.Cu")
		(net "SMB_FAN6_SCL")
	)
	(segment
		(start 25.216866 -196.179948)
		(end 25.7556 -195.641214)
		(width 0.2286)
		(layer "In2.Cu")
		(net "SMB_FAN6_SCL")
	)
	(segment
		(start 25.216866 -198.613268)
		(end 25.216866 -196.179948)
		(width 0.2286)
		(layer "In2.Cu")
		(net "SMB_FAN6_SCL")
	)
	(segment
		(start 25.7556 -195.641214)
		(end 25.7556 -184.279032)
		(width 0.2286)
		(layer "In2.Cu")
		(net "SMB_FAN6_SCL")
	)
	(segment
		(start 27.837892 -163.981892)
		(end 25.158954 -161.302954)
		(width 0.2286)
		(layer "In2.Cu")
		(net "SMB_FAN6_SCL")
	)
	(segment
		(start 27.837892 -182.19674)
		(end 27.837892 -163.981892)
		(width 0.2286)
		(layer "In2.Cu")
		(net "SMB_FAN6_SCL")
	)
	(segment
		(start 25.7556 -184.279032)
		(end 27.837892 -182.19674)
		(width 0.2286)
		(layer "In2.Cu")
		(net "SMB_FAN6_SCL")
	)
	(segment
		(start 23.111714 -142.002764)
		(end 23.114 -142.00505)
		(width 0.2794)
		(layer "F.Cu")
		(net "SMB_FAN0_R_SDA")
	)
	(segment
		(start 21.59 -144.29105)
		(end 21.59 -144.498568)
		(width 0.2794)
		(layer "F.Cu")
		(net "SMB_FAN0_R_SDA")
	)
	(segment
		(start 22.252178 -144.040352)
		(end 22.333204 -143.632936)
		(width 0.2794)
		(layer "F.Cu")
		(net "SMB_FAN0_R_SDA")
	)
	(segment
		(start 22.333204 -143.632936)
		(end 22.333204 -142.385796)
		(width 0.2794)
		(layer "F.Cu")
		(net "SMB_FAN0_R_SDA")
	)
	(segment
		(start 23.139908 -148.238972)
		(end 23.139908 -149.098)
		(width 0.2794)
		(layer "F.Cu")
		(net "SMB_FAN0_R_SDA")
	)
	(segment
		(start 22.76094 -147.32381)
		(end 23.139908 -148.238972)
		(width 0.2794)
		(layer "F.Cu")
		(net "SMB_FAN0_R_SDA")
	)
	(segment
		(start 21.946616 -144.29105)
		(end 22.252178 -144.040352)
		(width 0.2794)
		(layer "F.Cu")
		(net "SMB_FAN0_R_SDA")
	)
	(segment
		(start 22.716236 -142.002764)
		(end 23.111714 -142.002764)
		(width 0.2794)
		(layer "F.Cu")
		(net "SMB_FAN0_R_SDA")
	)
	(segment
		(start 21.59 -144.498568)
		(end 22.76094 -147.32381)
		(width 0.2794)
		(layer "F.Cu")
		(net "SMB_FAN0_R_SDA")
	)
	(segment
		(start 21.59 -144.29105)
		(end 21.946616 -144.29105)
		(width 0.2794)
		(layer "F.Cu")
		(net "SMB_FAN0_R_SDA")
	)
	(segment
		(start 22.333204 -142.385796)
		(end 22.716236 -142.002764)
		(width 0.2794)
		(layer "F.Cu")
		(net "SMB_FAN0_R_SDA")
	)
	(via
		(at 22.76094 -147.32381)
		(size 0.762)
		(drill 0.381)
		(layers "F.Cu" "B.Cu")
		(net "SMB_FAN0_R_SDA")
	)
	(via
		(at 16.764 -260.35)
		(size 0.762)
		(drill 0.254)
		(layers "F.Cu" "B.Cu")
		(net "FAN_7_SS")
	)
	(segment
		(start 15.78229 -261.347204)
		(end 16.525494 -260.604)
		(width 0.1016)
		(layer "B.Cu")
		(net "FAN_7_SS")
	)
	(segment
		(start 16.525494 -260.604)
		(end 16.525494 -260.588506)
		(width 0.1016)
		(layer "B.Cu")
		(net "FAN_7_SS")
	)
	(segment
		(start 16.764 -260.35)
		(end 17.414494 -259.699506)
		(width 0.2794)
		(layer "B.Cu")
		(net "FAN_7_SS")
	)
	(segment
		(start 15.78229 -262.054848)
		(end 15.78229 -261.347204)
		(width 0.1016)
		(layer "B.Cu")
		(net "FAN_7_SS")
	)
	(segment
		(start 17.414494 -259.699506)
		(end 17.414494 -258.97205)
		(width 0.2794)
		(layer "B.Cu")
		(net "FAN_7_SS")
	)
	(segment
		(start 16.525494 -260.588506)
		(end 16.764 -260.35)
		(width 0.1016)
		(layer "B.Cu")
		(net "FAN_7_SS")
	)
	(segment
		(start 15.13205 -259.08)
		(end 15.13205 -260.096)
		(width 0.2794)
		(layer "F.Cu")
		(net "FAN_7_MODE")
	)
	(segment
		(start 14.562836 -261.281164)
		(end 15.13205 -260.71195)
		(width 0.2794)
		(layer "F.Cu")
		(net "FAN_7_MODE")
	)
	(segment
		(start 15.13205 -260.71195)
		(end 15.13205 -260.096)
		(width 0.2794)
		(layer "F.Cu")
		(net "FAN_7_MODE")
	)
	(segment
		(start 11.2014 -261.0739)
		(end 11.408664 -261.281164)
		(width 0.2794)
		(layer "F.Cu")
		(net "FAN_7_MODE")
	)
	(segment
		(start 11.408664 -261.281164)
		(end 14.562836 -261.281164)
		(width 0.2794)
		(layer "F.Cu")
		(net "FAN_7_MODE")
	)
	(via
		(at 11.2014 -261.0739)
		(size 0.762)
		(drill 0.254)
		(layers "F.Cu" "B.Cu")
		(net "FAN_7_MODE")
	)
	(segment
		(start 12.0015 -261.874)
		(end 12.182348 -262.054848)
		(width 0.1016)
		(layer "B.Cu")
		(net "FAN_7_MODE")
	)
	(segment
		(start 11.2014 -261.0739)
		(end 12.0015 -261.874)
		(width 0.2794)
		(layer "B.Cu")
		(net "FAN_7_MODE")
	)
	(segment
		(start 17.27835 -165.7096)
		(end 16.01978 -165.7096)
		(width 0.2794)
		(layer "F.Cu")
		(net "FAN_2_PRESENT_N")
	)
	(segment
		(start 15.595854 -165.7096)
		(end 15.22095 -166.084504)
		(width 0.2794)
		(layer "F.Cu")
		(net "FAN_2_PRESENT_N")
	)
	(segment
		(start 10.85596 -166.228014)
		(end 10.967974 -166.116)
		(width 0.2794)
		(layer "F.Cu")
		(net "FAN_2_PRESENT_N")
	)
	(segment
		(start 13.577316 -166.910258)
		(end 14.803628 -166.910258)
		(width 0.2794)
		(layer "F.Cu")
		(net "FAN_2_PRESENT_N")
	)
	(segment
		(start 10.967974 -166.116)
		(end 12.93495 -166.116)
		(width 0.2794)
		(layer "F.Cu")
		(net "FAN_2_PRESENT_N")
	)
	(segment
		(start 15.22095 -166.492936)
		(end 15.22095 -166.4716)
		(width 0.2794)
		(layer "F.Cu")
		(net "FAN_2_PRESENT_N")
	)
	(segment
		(start 14.803628 -166.910258)
		(end 15.22095 -166.492936)
		(width 0.2794)
		(layer "F.Cu")
		(net "FAN_2_PRESENT_N")
	)
	(segment
		(start 17.50695 -165.481)
		(end 17.27835 -165.7096)
		(width 0.2794)
		(layer "F.Cu")
		(net "FAN_2_PRESENT_N")
	)
	(segment
		(start 16.01978 -165.7096)
		(end 15.595854 -165.7096)
		(width 0.2794)
		(layer "F.Cu")
		(net "FAN_2_PRESENT_N")
	)
	(segment
		(start 15.22095 -166.084504)
		(end 15.22095 -166.4716)
		(width 0.2794)
		(layer "F.Cu")
		(net "FAN_2_PRESENT_N")
	)
	(segment
		(start 12.93495 -166.116)
		(end 12.93495 -166.267892)
		(width 0.2794)
		(layer "F.Cu")
		(net "FAN_2_PRESENT_N")
	)
	(segment
		(start 12.93495 -166.267892)
		(end 13.577316 -166.910258)
		(width 0.2794)
		(layer "F.Cu")
		(net "FAN_2_PRESENT_N")
	)
	(via
		(at 16.01978 -165.7096)
		(size 0.508)
		(drill 0.254)
		(layers "F.Cu" "B.Cu")
		(net "FAN_2_PRESENT_N")
	)
	(segment
		(start 13.208 -182.884064)
		(end 15.218664 -182.884064)
		(width 0.2794)
		(layer "F.Cu")
		(net "SMB_PDBV_FAN_R_IOX_SDA")
	)
	(segment
		(start 17.71015 -184.2008)
		(end 18.01495 -183.896)
		(width 0.2794)
		(layer "F.Cu")
		(net "SMB_PDBV_FAN_R_IOX_SDA")
	)
	(segment
		(start 15.218664 -182.884064)
		(end 16.5354 -184.2008)
		(width 0.2794)
		(layer "F.Cu")
		(net "SMB_PDBV_FAN_R_IOX_SDA")
	)
	(segment
		(start 16.5354 -184.2008)
		(end 17.71015 -184.2008)
		(width 0.2794)
		(layer "F.Cu")
		(net "SMB_PDBV_FAN_R_IOX_SDA")
	)
	(via
		(at 16.5354 -184.2008)
		(size 0.762)
		(drill 0.381)
		(layers "F.Cu" "B.Cu")
		(net "SMB_PDBV_FAN_R_IOX_SDA")
	)
	(via
		(at 10.668 -259.842)
		(size 0.762)
		(drill 0.254)
		(layers "F.Cu" "B.Cu")
		(net "FAN_7_TEMP")
	)
	(segment
		(start 10.668 -259.842)
		(end 10.699242 -259.810758)
		(width 0.2794)
		(layer "B.Cu")
		(net "FAN_7_TEMP")
	)
	(segment
		(start 10.77341 -259.842)
		(end 11.68527 -260.75386)
		(width 0.2794)
		(layer "B.Cu")
		(net "FAN_7_TEMP")
	)
	(segment
		(start 11.68527 -260.75386)
		(end 12.38504 -261.388352)
		(width 0.1016)
		(layer "B.Cu")
		(net "FAN_7_TEMP")
	)
	(segment
		(start 10.699242 -259.810758)
		(end 10.699242 -258.962906)
		(width 0.2794)
		(layer "B.Cu")
		(net "FAN_7_TEMP")
	)
	(segment
		(start 9.667494 -258.962906)
		(end 10.699242 -258.962906)
		(width 0.2794)
		(layer "B.Cu")
		(net "FAN_7_TEMP")
	)
	(segment
		(start 10.668 -259.842)
		(end 10.77341 -259.842)
		(width 0.2794)
		(layer "B.Cu")
		(net "FAN_7_TEMP")
	)
	(segment
		(start 12.38504 -261.388352)
		(end 12.582144 -261.683246)
		(width 0.1016)
		(layer "B.Cu")
		(net "FAN_7_TEMP")
	)
	(segment
		(start 12.582144 -261.683246)
		(end 12.582144 -262.054848)
		(width 0.1016)
		(layer "B.Cu")
		(net "FAN_7_TEMP")
	)
	(segment
		(start 6.87705 -167.64)
		(end 8.31088 -167.64)
		(width 0.2794)
		(layer "F.Cu")
		(net "FAN_3_PRSNT_BUF_R_N")
	)
	(segment
		(start 8.31088 -167.64)
		(end 8.844026 -167.64)
		(width 0.2794)
		(layer "F.Cu")
		(net "FAN_3_PRSNT_BUF_R_N")
	)
	(segment
		(start 6.87705 -167.488108)
		(end 6.87705 -167.64)
		(width 0.2794)
		(layer "F.Cu")
		(net "FAN_3_PRSNT_BUF_R_N")
	)
	(segment
		(start 8.844026 -167.64)
		(end 8.95604 -167.527986)
		(width 0.2794)
		(layer "F.Cu")
		(net "FAN_3_PRSNT_BUF_R_N")
	)
	(segment
		(start 5.26415 -166.9669)
		(end 6.355842 -166.9669)
		(width 0.2794)
		(layer "F.Cu")
		(net "FAN_3_PRSNT_BUF_R_N")
	)
	(segment
		(start 4.59105 -167.64)
		(end 5.26415 -166.9669)
		(width 0.2794)
		(layer "F.Cu")
		(net "FAN_3_PRSNT_BUF_R_N")
	)
	(segment
		(start 6.355842 -166.9669)
		(end 6.87705 -167.488108)
		(width 0.2794)
		(layer "F.Cu")
		(net "FAN_3_PRSNT_BUF_R_N")
	)
	(via
		(at 8.31088 -167.64)
		(size 0.508)
		(drill 0.254)
		(layers "F.Cu" "B.Cu")
		(net "FAN_3_PRSNT_BUF_R_N")
	)
	(segment
		(start 35.179 -299.82795)
		(end 35.28695 -299.9359)
		(width 0.2794)
		(layer "F.Cu")
		(net "FAN_0_PWM_IL_R")
	)
	(segment
		(start 35.28695 -299.9359)
		(end 37.19195 -299.9359)
		(width 0.2794)
		(layer "F.Cu")
		(net "FAN_0_PWM_IL_R")
	)
	(segment
		(start 39.878 -300.355)
		(end 44.04487 -300.355)
		(width 0.2794)
		(layer "F.Cu")
		(net "FAN_0_PWM_IL_R")
	)
	(segment
		(start 37.196522 -299.940218)
		(end 37.73805 -299.39869)
		(width 0.2794)
		(layer "F.Cu")
		(net "FAN_0_PWM_IL_R")
	)
	(segment
		(start 44.04487 -300.355)
		(end 44.99991 -301.31004)
		(width 0.2794)
		(layer "F.Cu")
		(net "FAN_0_PWM_IL_R")
	)
	(segment
		(start 37.73805 -299.39869)
		(end 37.73805 -299.339)
		(width 0.2794)
		(layer "F.Cu")
		(net "FAN_0_PWM_IL_R")
	)
	(segment
		(start 37.19195 -299.9359)
		(end 37.196522 -299.940218)
		(width 0.2794)
		(layer "F.Cu")
		(net "FAN_0_PWM_IL_R")
	)
	(segment
		(start 38.75405 -300.355)
		(end 39.878 -300.355)
		(width 0.2794)
		(layer "F.Cu")
		(net "FAN_0_PWM_IL_R")
	)
	(segment
		(start 33.444942 -299.339)
		(end 34.69005 -299.339)
		(width 0.2794)
		(layer "F.Cu")
		(net "FAN_0_PWM_IL_R")
	)
	(segment
		(start 37.73805 -299.339)
		(end 38.75405 -300.355)
		(width 0.2794)
		(layer "F.Cu")
		(net "FAN_0_PWM_IL_R")
	)
	(segment
		(start 34.69005 -299.339)
		(end 35.179 -299.82795)
		(width 0.2794)
		(layer "F.Cu")
		(net "FAN_0_PWM_IL_R")
	)
	(via
		(at 39.878 -300.355)
		(size 0.762)
		(drill 0.381)
		(layers "F.Cu" "B.Cu")
		(net "FAN_0_PWM_IL_R")
	)
	(segment
		(start 12.93495 -167.791892)
		(end 12.93495 -167.64)
		(width 0.2794)
		(layer "F.Cu")
		(net "FAN_3_PRESENT_N")
	)
	(segment
		(start 14.54785 -168.3131)
		(end 15.22095 -167.64)
		(width 0.2794)
		(layer "F.Cu")
		(net "FAN_3_PRESENT_N")
	)
	(segment
		(start 10.967974 -167.64)
		(end 10.85596 -167.527986)
		(width 0.2794)
		(layer "F.Cu")
		(net "FAN_3_PRESENT_N")
	)
	(segment
		(start 13.456158 -168.3131)
		(end 14.54785 -168.3131)
		(width 0.2794)
		(layer "F.Cu")
		(net "FAN_3_PRESENT_N")
	)
	(segment
		(start 17.50695 -167.005)
		(end 16.19885 -168.3131)
		(width 0.2794)
		(layer "F.Cu")
		(net "FAN_3_PRESENT_N")
	)
	(segment
		(start 16.19885 -168.3131)
		(end 15.742158 -168.3131)
		(width 0.2794)
		(layer "F.Cu")
		(net "FAN_3_PRESENT_N")
	)
	(segment
		(start 15.742158 -168.3131)
		(end 15.22095 -167.791892)
		(width 0.2794)
		(layer "F.Cu")
		(net "FAN_3_PRESENT_N")
	)
	(segment
		(start 12.93495 -167.64)
		(end 10.967974 -167.64)
		(width 0.2794)
		(layer "F.Cu")
		(net "FAN_3_PRESENT_N")
	)
	(segment
		(start 15.22095 -167.791892)
		(end 15.22095 -167.64)
		(width 0.2794)
		(layer "F.Cu")
		(net "FAN_3_PRESENT_N")
	)
	(segment
		(start 13.456158 -168.3131)
		(end 12.93495 -167.791892)
		(width 0.2794)
		(layer "F.Cu")
		(net "FAN_3_PRESENT_N")
	)
	(via
		(at 13.456158 -168.3131)
		(size 0.508)
		(drill 0.254)
		(layers "F.Cu" "B.Cu")
		(net "FAN_3_PRESENT_N")
	)
	(segment
		(start 30.734 -160.930082)
		(end 30.734 -160.42005)
		(width 0.2794)
		(layer "F.Cu")
		(net "SMB_FAN5_SDA")
	)
	(segment
		(start 14.75105 -109.023912)
		(end 15.36065 -109.023912)
		(width 0.2794)
		(layer "F.Cu")
		(net "SMB_FAN5_SDA")
	)
	(segment
		(start 29.992066 -162.019234)
		(end 30.488382 -161.522918)
		(width 0.2794)
		(layer "F.Cu")
		(net "SMB_FAN5_SDA")
	)
	(segment
		(start 30.488382 -161.522918)
		(end 30.734 -160.930082)
		(width 0.2794)
		(layer "F.Cu")
		(net "SMB_FAN5_SDA")
	)
	(segment
		(start 29.992066 -162.548316)
		(end 29.992066 -162.019234)
		(width 0.2794)
		(layer "F.Cu")
		(net "SMB_FAN5_SDA")
	)
	(via
		(at 29.992066 -162.548316)
		(size 0.508)
		(drill 0.254)
		(layers "F.Cu" "B.Cu")
		(net "SMB_FAN5_SDA")
	)
	(via
		(at 15.36065 -109.023912)
		(size 0.508)
		(drill 0.254)
		(layers "F.Cu" "B.Cu")
		(net "SMB_FAN5_SDA")
	)
	(segment
		(start 23.9014 -148.067522)
		(end 29.729176 -162.437064)
		(width 0.2286)
		(layer "In2.Cu")
		(net "SMB_FAN5_SDA")
	)
	(segment
		(start 13.20546 -127.478536)
		(end 13.338302 -127.611378)
		(width 0.2286)
		(layer "In2.Cu")
		(net "SMB_FAN5_SDA")
	)
	(segment
		(start 15.36065 -109.023912)
		(end 13.3985 -110.986062)
		(width 0.2286)
		(layer "In2.Cu")
		(net "SMB_FAN5_SDA")
	)
	(segment
		(start 14.859 -128.524)
		(end 17.526 -131.191)
		(width 0.2286)
		(layer "In2.Cu")
		(net "SMB_FAN5_SDA")
	)
	(segment
		(start 13.3985 -116.68506)
		(end 13.53312 -116.81968)
		(width 0.2286)
		(layer "In2.Cu")
		(net "SMB_FAN5_SDA")
	)
	(segment
		(start 17.526 -131.191)
		(end 17.526 -131.9276)
		(width 0.2286)
		(layer "In2.Cu")
		(net "SMB_FAN5_SDA")
	)
	(segment
		(start 23.9014 -143.975328)
		(end 23.9014 -148.067522)
		(width 0.2286)
		(layer "In2.Cu")
		(net "SMB_FAN5_SDA")
	)
	(segment
		(start 24.294846 -141.134846)
		(end 24.294846 -143.581882)
		(width 0.2286)
		(layer "In2.Cu")
		(net "SMB_FAN5_SDA")
	)
	(segment
		(start 13.53312 -121.19864)
		(end 13.20546 -121.5263)
		(width 0.2286)
		(layer "In2.Cu")
		(net "SMB_FAN5_SDA")
	)
	(segment
		(start 17.526 -131.9276)
		(end 18.669 -133.0706)
		(width 0.2286)
		(layer "In2.Cu")
		(net "SMB_FAN5_SDA")
	)
	(segment
		(start 13.338302 -127.638302)
		(end 14.1732 -128.4732)
		(width 0.2286)
		(layer "In2.Cu")
		(net "SMB_FAN5_SDA")
	)
	(segment
		(start 14.743176 -128.4732)
		(end 14.793976 -128.524)
		(width 0.2286)
		(layer "In2.Cu")
		(net "SMB_FAN5_SDA")
	)
	(segment
		(start 13.53312 -116.81968)
		(end 13.53312 -121.19864)
		(width 0.2286)
		(layer "In2.Cu")
		(net "SMB_FAN5_SDA")
	)
	(segment
		(start 13.338302 -127.611378)
		(end 13.338302 -127.638302)
		(width 0.2286)
		(layer "In2.Cu")
		(net "SMB_FAN5_SDA")
	)
	(segment
		(start 14.793976 -128.524)
		(end 14.859 -128.524)
		(width 0.2286)
		(layer "In2.Cu")
		(net "SMB_FAN5_SDA")
	)
	(segment
		(start 13.20546 -121.5263)
		(end 13.20546 -127.478536)
		(width 0.2286)
		(layer "In2.Cu")
		(net "SMB_FAN5_SDA")
	)
	(segment
		(start 24.294846 -143.581882)
		(end 23.9014 -143.975328)
		(width 0.2286)
		(layer "In2.Cu")
		(net "SMB_FAN5_SDA")
	)
	(segment
		(start 14.1732 -128.4732)
		(end 14.743176 -128.4732)
		(width 0.2286)
		(layer "In2.Cu")
		(net "SMB_FAN5_SDA")
	)
	(segment
		(start 18.669 -133.0706)
		(end 18.669 -135.509)
		(width 0.2286)
		(layer "In2.Cu")
		(net "SMB_FAN5_SDA")
	)
	(segment
		(start 13.3985 -110.986062)
		(end 13.3985 -116.68506)
		(width 0.2286)
		(layer "In2.Cu")
		(net "SMB_FAN5_SDA")
	)
	(segment
		(start 29.729176 -162.437064)
		(end 29.992066 -162.548316)
		(width 0.2286)
		(layer "In2.Cu")
		(net "SMB_FAN5_SDA")
	)
	(segment
		(start 18.669 -135.509)
		(end 24.294846 -141.134846)
		(width 0.2286)
		(layer "In2.Cu")
		(net "SMB_FAN5_SDA")
	)
	(via
		(at 18.796 -260.604)
		(size 0.762)
		(drill 0.254)
		(layers "F.Cu" "B.Cu")
		(net "FAN_7_CS")
	)
	(segment
		(start 16.830802 -261.726172)
		(end 16.739108 -261.787386)
		(width 0.1016)
		(layer "B.Cu")
		(net "FAN_7_CS")
	)
	(segment
		(start 16.91513 -261.726172)
		(end 16.830802 -261.726172)
		(width 0.1016)
		(layer "B.Cu")
		(net "FAN_7_CS")
	)
	(segment
		(start 18.210022 -261.18947)
		(end 16.91513 -261.726172)
		(width 0.2794)
		(layer "B.Cu")
		(net "FAN_7_CS")
	)
	(segment
		(start 16.739108 -261.787386)
		(end 16.582136 -261.944358)
		(width 0.1016)
		(layer "B.Cu")
		(net "FAN_7_CS")
	)
	(segment
		(start 18.796 -260.604)
		(end 18.210022 -261.18947)
		(width 0.2794)
		(layer "B.Cu")
		(net "FAN_7_CS")
	)
	(segment
		(start 16.582136 -261.944358)
		(end 16.582136 -262.054848)
		(width 0.1016)
		(layer "B.Cu")
		(net "FAN_7_CS")
	)
	(segment
		(start 19.446494 -258.97205)
		(end 19.446494 -259.953506)
		(width 0.2794)
		(layer "B.Cu")
		(net "FAN_7_CS")
	)
	(segment
		(start 19.446494 -259.953506)
		(end 18.796 -260.604)
		(width 0.2794)
		(layer "B.Cu")
		(net "FAN_7_CS")
	)
	(segment
		(start 35.035236 -164.105336)
		(end 35.433 -164.5031)
		(width 0.2794)
		(layer "F.Cu")
		(net "FAN_0_PRESENT_R_N")
	)
	(segment
		(start 19.751802 -164.836856)
		(end 20.278344 -164.836856)
		(width 0.2794)
		(layer "F.Cu")
		(net "FAN_0_PRESENT_R_N")
	)
	(segment
		(start 20.278344 -164.836856)
		(end 21.009864 -164.105336)
		(width 0.2794)
		(layer "F.Cu")
		(net "FAN_0_PRESENT_R_N")
	)
	(segment
		(start 21.009864 -164.105336)
		(end 35.035236 -164.105336)
		(width 0.2794)
		(layer "F.Cu")
		(net "FAN_0_PRESENT_R_N")
	)
	(segment
		(start 37.0205 -164.5031)
		(end 37.465 -164.0586)
		(width 0.2794)
		(layer "F.Cu")
		(net "FAN_0_PRESENT_R_N")
	)
	(segment
		(start 37.465 -164.0586)
		(end 38.1762 -164.0586)
		(width 0.2794)
		(layer "F.Cu")
		(net "FAN_0_PRESENT_R_N")
	)
	(segment
		(start 35.433 -164.5031)
		(end 37.0205 -164.5031)
		(width 0.2794)
		(layer "F.Cu")
		(net "FAN_0_PRESENT_R_N")
	)
	(segment
		(start 18.30705 -162.814)
		(end 18.30705 -163.392104)
		(width 0.2794)
		(layer "F.Cu")
		(net "FAN_0_PRESENT_R_N")
	)
	(segment
		(start 18.30705 -163.392104)
		(end 19.751802 -164.836856)
		(width 0.2794)
		(layer "F.Cu")
		(net "FAN_0_PRESENT_R_N")
	)
	(via
		(at 38.1762 -164.0586)
		(size 0.508)
		(drill 0.254)
		(layers "F.Cu" "B.Cu")
		(net "FAN_0_PRESENT_R_N")
	)
	(segment
		(start 38.1762 -182.249826)
		(end 35.923474 -184.502552)
		(width 0.2286)
		(layer "In2.Cu")
		(net "FAN_0_PRESENT_R_N")
	)
	(segment
		(start 42.61104 -301.31004)
		(end 42.999914 -301.31004)
		(width 0.2286)
		(layer "In2.Cu")
		(net "FAN_0_PRESENT_R_N")
	)
	(segment
		(start 34.925 -285.242)
		(end 38.450774 -288.767774)
		(width 0.2286)
		(layer "In2.Cu")
		(net "FAN_0_PRESENT_R_N")
	)
	(segment
		(start 32.762698 -241.218974)
		(end 29.984192 -247.927368)
		(width 0.2286)
		(layer "In2.Cu")
		(net "FAN_0_PRESENT_R_N")
	)
	(segment
		(start 29.887672 -248.023888)
		(end 29.1846 -248.726706)
		(width 0.2286)
		(layer "In2.Cu")
		(net "FAN_0_PRESENT_R_N")
	)
	(segment
		(start 29.75991 -200.07453)
		(end 32.40278 -202.7174)
		(width 0.2286)
		(layer "In2.Cu")
		(net "FAN_0_PRESENT_R_N")
	)
	(segment
		(start 32.40278 -202.7174)
		(end 36.295584 -202.7174)
		(width 0.2286)
		(layer "In2.Cu")
		(net "FAN_0_PRESENT_R_N")
	)
	(segment
		(start 35.923474 -189.501526)
		(end 29.75991 -195.66509)
		(width 0.2286)
		(layer "In2.Cu")
		(net "FAN_0_PRESENT_R_N")
	)
	(segment
		(start 36.295584 -202.7174)
		(end 36.878006 -203.299822)
		(width 0.2286)
		(layer "In2.Cu")
		(net "FAN_0_PRESENT_R_N")
	)
	(segment
		(start 35.923474 -184.502552)
		(end 35.923474 -189.501526)
		(width 0.2286)
		(layer "In2.Cu")
		(net "FAN_0_PRESENT_R_N")
	)
	(segment
		(start 36.878006 -203.299822)
		(end 36.878006 -209.296)
		(width 0.2286)
		(layer "In2.Cu")
		(net "FAN_0_PRESENT_R_N")
	)
	(segment
		(start 32.762698 -213.411308)
		(end 32.762698 -241.218974)
		(width 0.2286)
		(layer "In2.Cu")
		(net "FAN_0_PRESENT_R_N")
	)
	(segment
		(start 29.1846 -280.2636)
		(end 34.163 -285.242)
		(width 0.2286)
		(layer "In2.Cu")
		(net "FAN_0_PRESENT_R_N")
	)
	(segment
		(start 38.1762 -164.0586)
		(end 38.1762 -182.249826)
		(width 0.2286)
		(layer "In2.Cu")
		(net "FAN_0_PRESENT_R_N")
	)
	(segment
		(start 29.984192 -247.927368)
		(end 29.887672 -248.023888)
		(width 0.2286)
		(layer "In2.Cu")
		(net "FAN_0_PRESENT_R_N")
	)
	(segment
		(start 34.163 -285.242)
		(end 34.925 -285.242)
		(width 0.2286)
		(layer "In2.Cu")
		(net "FAN_0_PRESENT_R_N")
	)
	(segment
		(start 29.75991 -195.66509)
		(end 29.75991 -200.07453)
		(width 0.2286)
		(layer "In2.Cu")
		(net "FAN_0_PRESENT_R_N")
	)
	(segment
		(start 38.450774 -297.149774)
		(end 42.61104 -301.31004)
		(width 0.2286)
		(layer "In2.Cu")
		(net "FAN_0_PRESENT_R_N")
	)
	(segment
		(start 36.878006 -209.296)
		(end 32.762698 -213.411308)
		(width 0.2286)
		(layer "In2.Cu")
		(net "FAN_0_PRESENT_R_N")
	)
	(segment
		(start 29.1846 -248.726706)
		(end 29.1846 -280.2636)
		(width 0.2286)
		(layer "In2.Cu")
		(net "FAN_0_PRESENT_R_N")
	)
	(segment
		(start 38.450774 -288.767774)
		(end 38.450774 -297.149774)
		(width 0.2286)
		(layer "In2.Cu")
		(net "FAN_0_PRESENT_R_N")
	)
	(via
		(at 14.54404 -260.10108)
		(size 0.6604)
		(drill 0.3302)
		(layers "F.Cu" "B.Cu")
		(net "FAN_7_CLREF")
	)
	(segment
		(start 14.58214 -260.13918)
		(end 14.54404 -260.10108)
		(width 0.1016)
		(layer "B.Cu")
		(net "FAN_7_CLREF")
	)
	(segment
		(start 14.54404 -260.10108)
		(end 14.58214 -260.06298)
		(width 0.1016)
		(layer "B.Cu")
		(net "FAN_7_CLREF")
	)
	(segment
		(start 14.58214 -260.06298)
		(end 14.58214 -259.564886)
		(width 0.1016)
		(layer "B.Cu")
		(net "FAN_7_CLREF")
	)
	(segment
		(start 14.58214 -259.564886)
		(end 14.351 -259.333746)
		(width 0.2794)
		(layer "B.Cu")
		(net "FAN_7_CLREF")
	)
	(segment
		(start 14.58214 -262.054848)
		(end 14.58214 -260.13918)
		(width 0.1016)
		(layer "B.Cu")
		(net "FAN_7_CLREF")
	)
	(segment
		(start 15.367 -258.97205)
		(end 14.351 -258.97205)
		(width 0.2794)
		(layer "B.Cu")
		(net "FAN_7_CLREF")
	)
	(segment
		(start 14.351 -259.333746)
		(end 14.351 -258.97205)
		(width 0.2794)
		(layer "B.Cu")
		(net "FAN_7_CLREF")
	)
	(segment
		(start 15.22095 -164.338)
		(end 15.22095 -164.489892)
		(width 0.2794)
		(layer "F.Cu")
		(net "FAN_1_PRESENT_N")
	)
	(segment
		(start 12.93495 -164.489892)
		(end 13.456158 -165.0111)
		(width 0.2794)
		(layer "F.Cu")
		(net "FAN_1_PRESENT_N")
	)
	(segment
		(start 10.967974 -164.846)
		(end 10.85596 -164.733986)
		(width 0.2794)
		(layer "F.Cu")
		(net "FAN_1_PRESENT_N")
	)
	(segment
		(start 13.456158 -165.0111)
		(end 14.54785 -165.0111)
		(width 0.2794)
		(layer "F.Cu")
		(net "FAN_1_PRESENT_N")
	)
	(segment
		(start 12.572746 -164.338)
		(end 12.93495 -164.338)
		(width 0.2794)
		(layer "F.Cu")
		(net "FAN_1_PRESENT_N")
	)
	(segment
		(start 12.93495 -164.338)
		(end 12.93495 -164.489892)
		(width 0.2794)
		(layer "F.Cu")
		(net "FAN_1_PRESENT_N")
	)
	(segment
		(start 15.22095 -164.489892)
		(end 15.742158 -165.0111)
		(width 0.2794)
		(layer "F.Cu")
		(net "FAN_1_PRESENT_N")
	)
	(segment
		(start 12.064746 -164.846)
		(end 10.967974 -164.846)
		(width 0.2794)
		(layer "F.Cu")
		(net "FAN_1_PRESENT_N")
	)
	(segment
		(start 16.83385 -165.0111)
		(end 17.50695 -164.338)
		(width 0.2794)
		(layer "F.Cu")
		(net "FAN_1_PRESENT_N")
	)
	(segment
		(start 15.742158 -165.0111)
		(end 16.83385 -165.0111)
		(width 0.2794)
		(layer "F.Cu")
		(net "FAN_1_PRESENT_N")
	)
	(segment
		(start 12.064746 -164.846)
		(end 12.572746 -164.338)
		(width 0.2794)
		(layer "F.Cu")
		(net "FAN_1_PRESENT_N")
	)
	(segment
		(start 14.54785 -165.0111)
		(end 15.22095 -164.338)
		(width 0.2794)
		(layer "F.Cu")
		(net "FAN_1_PRESENT_N")
	)
	(via
		(at 12.064746 -164.846)
		(size 0.508)
		(drill 0.254)
		(layers "F.Cu" "B.Cu")
		(net "FAN_1_PRESENT_N")
	)
	(segment
		(start 27.584654 -159.279336)
		(end 28.725368 -160.42005)
		(width 0.2794)
		(layer "F.Cu")
		(net "SMB_FAN5_SCL")
	)
	(segment
		(start 28.725368 -160.42005)
		(end 28.956 -160.42005)
		(width 0.2794)
		(layer "F.Cu")
		(net "SMB_FAN5_SCL")
	)
	(segment
		(start 14.75105 -107.880912)
		(end 15.36065 -107.880912)
		(width 0.2794)
		(layer "F.Cu")
		(net "SMB_FAN5_SCL")
	)
	(via
		(at 15.36065 -107.880912)
		(size 0.508)
		(drill 0.254)
		(layers "F.Cu" "B.Cu")
		(net "SMB_FAN5_SCL")
	)
	(via
		(at 27.584654 -159.279336)
		(size 0.508)
		(drill 0.254)
		(layers "F.Cu" "B.Cu")
		(net "SMB_FAN5_SCL")
	)
	(segment
		(start 23.563072 -143.314928)
		(end 23.2156 -143.6624)
		(width 0.2286)
		(layer "In2.Cu")
		(net "SMB_FAN5_SCL")
	)
	(segment
		(start 15.182342 -129.863342)
		(end 16.7894 -131.4704)
		(width 0.2286)
		(layer "In2.Cu")
		(net "SMB_FAN5_SCL")
	)
	(segment
		(start 25.416764 -154.506422)
		(end 24.754332 -154.775154)
		(width 0.2286)
		(layer "In2.Cu")
		(net "SMB_FAN5_SCL")
	)
	(segment
		(start 24.754332 -154.775154)
		(end 24.635714 -155.05557)
		(width 0.2286)
		(layer "In2.Cu")
		(net "SMB_FAN5_SCL")
	)
	(segment
		(start 26.054812 -157.85846)
		(end 26.674318 -157.607254)
		(width 0.2286)
		(layer "In2.Cu")
		(net "SMB_FAN5_SCL")
	)
	(segment
		(start 24.750776 -155.339034)
		(end 25.031192 -155.457906)
		(width 0.2286)
		(layer "In2.Cu")
		(net "SMB_FAN5_SCL")
	)
	(segment
		(start 13.071094 -129.863342)
		(end 15.182342 -129.863342)
		(width 0.2286)
		(layer "In2.Cu")
		(net "SMB_FAN5_SCL")
	)
	(segment
		(start 23.2156 -148.505926)
		(end 25.535382 -154.226006)
		(width 0.2286)
		(layer "In2.Cu")
		(net "SMB_FAN5_SCL")
	)
	(segment
		(start 25.031192 -155.457906)
		(end 25.693624 -155.189174)
		(width 0.2286)
		(layer "In2.Cu")
		(net "SMB_FAN5_SCL")
	)
	(segment
		(start 17.9451 -135.8265)
		(end 23.563072 -141.444472)
		(width 0.2286)
		(layer "In2.Cu")
		(net "SMB_FAN5_SCL")
	)
	(segment
		(start 25.777952 -157.175708)
		(end 25.659334 -157.456378)
		(width 0.2286)
		(layer "In2.Cu")
		(net "SMB_FAN5_SCL")
	)
	(segment
		(start 26.516076 -156.643832)
		(end 26.397458 -156.924502)
		(width 0.2286)
		(layer "In2.Cu")
		(net "SMB_FAN5_SCL")
	)
	(segment
		(start 24.635714 -155.05557)
		(end 24.750776 -155.339034)
		(width 0.2286)
		(layer "In2.Cu")
		(net "SMB_FAN5_SCL")
	)
	(segment
		(start 15.36065 -107.880912)
		(end 12.7127 -110.528862)
		(width 0.2286)
		(layer "In2.Cu")
		(net "SMB_FAN5_SCL")
	)
	(segment
		(start 17.9451 -133.3881)
		(end 17.9451 -135.8265)
		(width 0.2286)
		(layer "In2.Cu")
		(net "SMB_FAN5_SCL")
	)
	(segment
		(start 25.974294 -155.308046)
		(end 26.516076 -156.643832)
		(width 0.2286)
		(layer "In2.Cu")
		(net "SMB_FAN5_SCL")
	)
	(segment
		(start 26.954734 -157.725872)
		(end 27.584654 -159.279336)
		(width 0.2286)
		(layer "In2.Cu")
		(net "SMB_FAN5_SCL")
	)
	(segment
		(start 26.397458 -156.924502)
		(end 25.777952 -157.175708)
		(width 0.2286)
		(layer "In2.Cu")
		(net "SMB_FAN5_SCL")
	)
	(segment
		(start 12.7127 -119.30126)
		(end 11.83386 -120.1801)
		(width 0.2286)
		(layer "In2.Cu")
		(net "SMB_FAN5_SCL")
	)
	(segment
		(start 25.535382 -154.226006)
		(end 25.416764 -154.506422)
		(width 0.2286)
		(layer "In2.Cu")
		(net "SMB_FAN5_SCL")
	)
	(segment
		(start 16.7894 -131.4704)
		(end 16.7894 -132.2324)
		(width 0.2286)
		(layer "In2.Cu")
		(net "SMB_FAN5_SCL")
	)
	(segment
		(start 23.563072 -141.444472)
		(end 23.563072 -143.314928)
		(width 0.2286)
		(layer "In2.Cu")
		(net "SMB_FAN5_SCL")
	)
	(segment
		(start 16.7894 -132.2324)
		(end 17.9451 -133.3881)
		(width 0.2286)
		(layer "In2.Cu")
		(net "SMB_FAN5_SCL")
	)
	(segment
		(start 26.674318 -157.607254)
		(end 26.954734 -157.725872)
		(width 0.2286)
		(layer "In2.Cu")
		(net "SMB_FAN5_SCL")
	)
	(segment
		(start 11.83386 -120.1801)
		(end 11.83386 -128.626108)
		(width 0.2286)
		(layer "In2.Cu")
		(net "SMB_FAN5_SCL")
	)
	(segment
		(start 11.83386 -128.626108)
		(end 13.071094 -129.863342)
		(width 0.2286)
		(layer "In2.Cu")
		(net "SMB_FAN5_SCL")
	)
	(segment
		(start 25.693624 -155.189174)
		(end 25.974294 -155.308046)
		(width 0.2286)
		(layer "In2.Cu")
		(net "SMB_FAN5_SCL")
	)
	(segment
		(start 25.659334 -157.456378)
		(end 25.774396 -157.739842)
		(width 0.2286)
		(layer "In2.Cu")
		(net "SMB_FAN5_SCL")
	)
	(segment
		(start 12.7127 -110.528862)
		(end 12.7127 -119.30126)
		(width 0.2286)
		(layer "In2.Cu")
		(net "SMB_FAN5_SCL")
	)
	(segment
		(start 23.2156 -143.6624)
		(end 23.2156 -148.505926)
		(width 0.2286)
		(layer "In2.Cu")
		(net "SMB_FAN5_SCL")
	)
	(segment
		(start 25.774396 -157.739842)
		(end 26.054812 -157.85846)
		(width 0.2286)
		(layer "In2.Cu")
		(net "SMB_FAN5_SCL")
	)
	(segment
		(start 6.355842 -165.4429)
		(end 6.87705 -165.964108)
		(width 0.2794)
		(layer "F.Cu")
		(net "FAN_2_PRSNT_BUF_R_N")
	)
	(segment
		(start 6.87705 -165.964108)
		(end 6.87705 -166.116)
		(width 0.2794)
		(layer "F.Cu")
		(net "FAN_2_PRSNT_BUF_R_N")
	)
	(segment
		(start 8.844026 -166.116)
		(end 8.95604 -166.228014)
		(width 0.2794)
		(layer "F.Cu")
		(net "FAN_2_PRSNT_BUF_R_N")
	)
	(segment
		(start 6.87705 -166.116)
		(end 8.844026 -166.116)
		(width 0.2794)
		(layer "F.Cu")
		(net "FAN_2_PRSNT_BUF_R_N")
	)
	(segment
		(start 5.26415 -165.4429)
		(end 6.355842 -165.4429)
		(width 0.2794)
		(layer "F.Cu")
		(net "FAN_2_PRSNT_BUF_R_N")
	)
	(segment
		(start 4.59105 -166.116)
		(end 5.26415 -165.4429)
		(width 0.2794)
		(layer "F.Cu")
		(net "FAN_2_PRSNT_BUF_R_N")
	)
	(segment
		(start 34.29 -161.925)
		(end 34.29 -160.42005)
		(width 0.2794)
		(layer "F.Cu")
		(net "SMB_FAN4_SDA")
	)
	(segment
		(start 14.75105 -21.384768)
		(end 15.494 -21.384768)
		(width 0.2794)
		(layer "F.Cu")
		(net "SMB_FAN4_SDA")
	)
	(via
		(at 34.29 -161.925)
		(size 0.508)
		(drill 0.254)
		(layers "F.Cu" "B.Cu")
		(net "SMB_FAN4_SDA")
	)
	(via
		(at 15.494 -21.384768)
		(size 0.508)
		(drill 0.254)
		(layers "F.Cu" "B.Cu")
		(net "SMB_FAN4_SDA")
	)
	(segment
		(start 30.226 -141.879066)
		(end 30.226 -139.576556)
		(width 0.2286)
		(layer "In2.Cu")
		(net "SMB_FAN4_SDA")
	)
	(segment
		(start 22.911816 -84.900516)
		(end 22.36978 -84.35848)
		(width 0.2286)
		(layer "In2.Cu")
		(net "SMB_FAN4_SDA")
	)
	(segment
		(start 23.801578 -102.058978)
		(end 22.911816 -101.169216)
		(width 0.2286)
		(layer "In2.Cu")
		(net "SMB_FAN4_SDA")
	)
	(segment
		(start 22.36978 -63.110872)
		(end 17.835372 -52.148486)
		(width 0.2286)
		(layer "In2.Cu")
		(net "SMB_FAN4_SDA")
	)
	(segment
		(start 22.911816 -101.169216)
		(end 22.911816 -84.900516)
		(width 0.2286)
		(layer "In2.Cu")
		(net "SMB_FAN4_SDA")
	)
	(segment
		(start 28.2067 -122.4407)
		(end 21.832316 -116.066316)
		(width 0.2286)
		(layer "In2.Cu")
		(net "SMB_FAN4_SDA")
	)
	(segment
		(start 17.272 -25.527254)
		(end 15.494 -23.749254)
		(width 0.2286)
		(layer "In2.Cu")
		(net "SMB_FAN4_SDA")
	)
	(segment
		(start 20.828 -34.11728)
		(end 20.828 -32.385)
		(width 0.2286)
		(layer "In2.Cu")
		(net "SMB_FAN4_SDA")
	)
	(segment
		(start 34.29 -161.925)
		(end 34.29 -161.417254)
		(width 0.2286)
		(layer "In2.Cu")
		(net "SMB_FAN4_SDA")
	)
	(segment
		(start 23.801578 -108.532168)
		(end 23.801578 -102.058978)
		(width 0.2286)
		(layer "In2.Cu")
		(net "SMB_FAN4_SDA")
	)
	(segment
		(start 32.766 -157.716728)
		(end 32.6898 -157.531562)
		(width 0.2286)
		(layer "In2.Cu")
		(net "SMB_FAN4_SDA")
	)
	(segment
		(start 22.36978 -84.35848)
		(end 22.36978 -63.110872)
		(width 0.2286)
		(layer "In2.Cu")
		(net "SMB_FAN4_SDA")
	)
	(segment
		(start 17.835372 -37.109908)
		(end 20.828 -34.11728)
		(width 0.2286)
		(layer "In2.Cu")
		(net "SMB_FAN4_SDA")
	)
	(segment
		(start 17.272 -28.321254)
		(end 17.272 -25.527254)
		(width 0.2286)
		(layer "In2.Cu")
		(net "SMB_FAN4_SDA")
	)
	(segment
		(start 30.2387 -139.549886)
		(end 31.036006 -138.75258)
		(width 0.2286)
		(layer "In2.Cu")
		(net "SMB_FAN4_SDA")
	)
	(segment
		(start 28.2067 -124.78004)
		(end 28.2067 -122.4407)
		(width 0.2286)
		(layer "In2.Cu")
		(net "SMB_FAN4_SDA")
	)
	(segment
		(start 30.227524 -139.563602)
		(end 30.2387 -139.549886)
		(width 0.2286)
		(layer "In2.Cu")
		(net "SMB_FAN4_SDA")
	)
	(segment
		(start 20.828 -32.385)
		(end 18.287746 -29.844746)
		(width 0.2286)
		(layer "In2.Cu")
		(net "SMB_FAN4_SDA")
	)
	(segment
		(start 21.832316 -110.50143)
		(end 23.801578 -108.532168)
		(width 0.2286)
		(layer "In2.Cu")
		(net "SMB_FAN4_SDA")
	)
	(segment
		(start 32.766 -157.741112)
		(end 32.766 -157.716728)
		(width 0.2286)
		(layer "In2.Cu")
		(net "SMB_FAN4_SDA")
	)
	(segment
		(start 31.036006 -127.609346)
		(end 28.2067 -124.78004)
		(width 0.2286)
		(layer "In2.Cu")
		(net "SMB_FAN4_SDA")
	)
	(segment
		(start 31.036006 -138.75258)
		(end 31.036006 -127.609346)
		(width 0.2286)
		(layer "In2.Cu")
		(net "SMB_FAN4_SDA")
	)
	(segment
		(start 34.29 -161.417254)
		(end 32.766 -157.741112)
		(width 0.2286)
		(layer "In2.Cu")
		(net "SMB_FAN4_SDA")
	)
	(segment
		(start 30.226 -139.576556)
		(end 30.227524 -139.563602)
		(width 0.2286)
		(layer "In2.Cu")
		(net "SMB_FAN4_SDA")
	)
	(segment
		(start 32.6898 -147.838922)
		(end 30.22727 -141.891766)
		(width 0.2286)
		(layer "In2.Cu")
		(net "SMB_FAN4_SDA")
	)
	(segment
		(start 18.287746 -29.337)
		(end 17.272 -28.321254)
		(width 0.2286)
		(layer "In2.Cu")
		(net "SMB_FAN4_SDA")
	)
	(segment
		(start 21.832316 -116.066316)
		(end 21.832316 -110.50143)
		(width 0.2286)
		(layer "In2.Cu")
		(net "SMB_FAN4_SDA")
	)
	(segment
		(start 30.22727 -141.891766)
		(end 30.226 -141.879066)
		(width 0.2286)
		(layer "In2.Cu")
		(net "SMB_FAN4_SDA")
	)
	(segment
		(start 18.287746 -29.844746)
		(end 18.287746 -29.337)
		(width 0.2286)
		(layer "In2.Cu")
		(net "SMB_FAN4_SDA")
	)
	(segment
		(start 15.494 -23.749254)
		(end 15.494 -21.384768)
		(width 0.2286)
		(layer "In2.Cu")
		(net "SMB_FAN4_SDA")
	)
	(segment
		(start 17.835372 -52.148486)
		(end 17.835372 -37.109908)
		(width 0.2286)
		(layer "In2.Cu")
		(net "SMB_FAN4_SDA")
	)
	(segment
		(start 32.6898 -157.531562)
		(end 32.6898 -147.838922)
		(width 0.2286)
		(layer "In2.Cu")
		(net "SMB_FAN4_SDA")
	)
	(via
		(at 10.746486 -63.82258)
		(size 0.762)
		(drill 0.254)
		(layers "F.Cu" "B.Cu")
		(net "FAN_4_TEMP")
	)
	(segment
		(start 7.700264 -61.345064)
		(end 7.700264 -61.728604)
		(width 0.1016)
		(layer "B.Cu")
		(net "FAN_4_TEMP")
	)
	(segment
		(start 8.94715 -63.67399)
		(end 9.710166 -64.437006)
		(width 0.2794)
		(layer "B.Cu")
		(net "FAN_4_TEMP")
	)
	(segment
		(start 7.700264 -61.728604)
		(end 7.995412 -62.170056)
		(width 0.1016)
		(layer "B.Cu")
		(net "FAN_4_TEMP")
	)
	(segment
		(start 10.746486 -63.82258)
		(end 10.324592 -63.82258)
		(width 0.2794)
		(layer "B.Cu")
		(net "FAN_4_TEMP")
	)
	(segment
		(start 10.324592 -63.82258)
		(end 9.710166 -64.437006)
		(width 0.2794)
		(layer "B.Cu")
		(net "FAN_4_TEMP")
	)
	(segment
		(start 10.746486 -64.437006)
		(end 10.746486 -63.82258)
		(width 0.2794)
		(layer "B.Cu")
		(net "FAN_4_TEMP")
	)
	(segment
		(start 8.557006 -62.73165)
		(end 8.94715 -63.67399)
		(width 0.1016)
		(layer "B.Cu")
		(net "FAN_4_TEMP")
	)
	(segment
		(start 7.995412 -62.170056)
		(end 8.557006 -62.73165)
		(width 0.1016)
		(layer "B.Cu")
		(net "FAN_4_TEMP")
	)
	(segment
		(start 5.35305 -164.719)
		(end 6.217412 -164.719)
		(width 0.2794)
		(layer "F.Cu")
		(net "FAN_1_PRSNT_BUF_R_N")
	)
	(segment
		(start 4.59105 -163.957)
		(end 5.35305 -164.719)
		(width 0.2794)
		(layer "F.Cu")
		(net "FAN_1_PRSNT_BUF_R_N")
	)
	(segment
		(start 8.95604 -164.733986)
		(end 8.897366 -164.79266)
		(width 0.2794)
		(layer "F.Cu")
		(net "FAN_1_PRSNT_BUF_R_N")
	)
	(segment
		(start 7.102602 -164.059362)
		(end 6.87705 -164.059362)
		(width 0.2794)
		(layer "F.Cu")
		(net "FAN_1_PRSNT_BUF_R_N")
	)
	(segment
		(start 6.217412 -164.719)
		(end 6.87705 -164.059362)
		(width 0.2794)
		(layer "F.Cu")
		(net "FAN_1_PRSNT_BUF_R_N")
	)
	(segment
		(start 6.87705 -164.059362)
		(end 6.87705 -163.957)
		(width 0.2794)
		(layer "F.Cu")
		(net "FAN_1_PRSNT_BUF_R_N")
	)
	(segment
		(start 7.8359 -164.79266)
		(end 7.71652 -164.67328)
		(width 0.2794)
		(layer "F.Cu")
		(net "FAN_1_PRSNT_BUF_R_N")
	)
	(segment
		(start 8.897366 -164.79266)
		(end 7.8359 -164.79266)
		(width 0.2794)
		(layer "F.Cu")
		(net "FAN_1_PRSNT_BUF_R_N")
	)
	(segment
		(start 7.71652 -164.67328)
		(end 7.102602 -164.059362)
		(width 0.2794)
		(layer "F.Cu")
		(net "FAN_1_PRSNT_BUF_R_N")
	)
	(via
		(at 7.71652 -164.67328)
		(size 0.508)
		(drill 0.254)
		(layers "F.Cu" "B.Cu")
		(net "FAN_1_PRSNT_BUF_R_N")
	)
	(segment
		(start 14.634972 -286.6771)
		(end 14.634972 -286.482028)
		(width 0.2794)
		(layer "F.Cu")
		(net "FAN_7_PWM_OL")
	)
	(segment
		(start 14.634972 -286.482028)
		(end 15.748 -285.369)
		(width 0.2794)
		(layer "F.Cu")
		(net "FAN_7_PWM_OL")
	)
	(segment
		(start 24.83104 -288.783014)
		(end 21.417026 -285.369)
		(width 0.2794)
		(layer "F.Cu")
		(net "FAN_7_PWM_OL")
	)
	(segment
		(start 21.417026 -285.369)
		(end 20.828 -285.369)
		(width 0.2794)
		(layer "F.Cu")
		(net "FAN_7_PWM_OL")
	)
	(segment
		(start 15.748 -285.369)
		(end 20.828 -285.369)
		(width 0.2794)
		(layer "F.Cu")
		(net "FAN_7_PWM_OL")
	)
	(via
		(at 20.828 -285.369)
		(size 0.762)
		(drill 0.381)
		(layers "F.Cu" "B.Cu")
		(net "FAN_7_PWM_OL")
	)
	(segment
		(start 8.452866 -63.881)
		(end 6.49605 -63.881)
		(width 0.2794)
		(layer "F.Cu")
		(net "FAN_4_MODE")
	)
	(segment
		(start 9.36752 -63.301118)
		(end 9.032748 -63.301118)
		(width 0.2794)
		(layer "F.Cu")
		(net "FAN_4_MODE")
	)
	(segment
		(start 9.032748 -63.301118)
		(end 8.452866 -63.881)
		(width 0.2794)
		(layer "F.Cu")
		(net "FAN_4_MODE")
	)
	(segment
		(start 6.71195 -64.0969)
		(end 6.49605 -63.881)
		(width 0.2794)
		(layer "F.Cu")
		(net "FAN_4_MODE")
	)
	(segment
		(start 6.71195 -64.897)
		(end 6.71195 -64.0969)
		(width 0.2794)
		(layer "F.Cu")
		(net "FAN_4_MODE")
	)
	(via
		(at 9.36752 -63.301118)
		(size 0.762)
		(drill 0.254)
		(layers "F.Cu" "B.Cu")
		(net "FAN_4_MODE")
	)
	(segment
		(start 8.470392 -61.79439)
		(end 8.201914 -61.525912)
		(width 0.2794)
		(layer "B.Cu")
		(net "FAN_4_MODE")
	)
	(segment
		(start 8.10006 -61.424058)
		(end 8.10006 -61.345064)
		(width 0.1016)
		(layer "B.Cu")
		(net "FAN_4_MODE")
	)
	(segment
		(start 8.201914 -61.525912)
		(end 8.10006 -61.424058)
		(width 0.1016)
		(layer "B.Cu")
		(net "FAN_4_MODE")
	)
	(segment
		(start 9.36752 -62.445392)
		(end 8.716518 -61.79439)
		(width 0.2794)
		(layer "B.Cu")
		(net "FAN_4_MODE")
	)
	(segment
		(start 9.36752 -63.301118)
		(end 9.36752 -62.445392)
		(width 0.2794)
		(layer "B.Cu")
		(net "FAN_4_MODE")
	)
	(segment
		(start 8.716518 -61.79439)
		(end 8.470392 -61.79439)
		(width 0.2794)
		(layer "B.Cu")
		(net "FAN_4_MODE")
	)
	(segment
		(start 12.93495 -162.965892)
		(end 13.456158 -163.4871)
		(width 0.2794)
		(layer "F.Cu")
		(net "FAN_0_PRESENT_N")
	)
	(segment
		(start 10.967974 -163.322)
		(end 12.318746 -163.322)
		(width 0.2794)
		(layer "F.Cu")
		(net "FAN_0_PRESENT_N")
	)
	(segment
		(start 12.318746 -163.322)
		(end 12.826746 -162.814)
		(width 0.2794)
		(layer "F.Cu")
		(net "FAN_0_PRESENT_N")
	)
	(segment
		(start 17.50695 -162.365944)
		(end 17.50695 -162.814)
		(width 0.2794)
		(layer "F.Cu")
		(net "FAN_0_PRESENT_N")
	)
	(segment
		(start 16.740886 -161.59988)
		(end 17.50695 -162.365944)
		(width 0.2794)
		(layer "F.Cu")
		(net "FAN_0_PRESENT_N")
	)
	(segment
		(start 16.37792 -161.59988)
		(end 16.740886 -161.59988)
		(width 0.2794)
		(layer "F.Cu")
		(net "FAN_0_PRESENT_N")
	)
	(segment
		(start 15.22095 -162.452304)
		(end 15.22095 -162.814)
		(width 0.2794)
		(layer "F.Cu")
		(net "FAN_0_PRESENT_N")
	)
	(segment
		(start 12.826746 -162.814)
		(end 12.93495 -162.814)
		(width 0.2794)
		(layer "F.Cu")
		(net "FAN_0_PRESENT_N")
	)
	(segment
		(start 14.54785 -163.4871)
		(end 15.22095 -162.814)
		(width 0.2794)
		(layer "F.Cu")
		(net "FAN_0_PRESENT_N")
	)
	(segment
		(start 13.456158 -163.4871)
		(end 14.54785 -163.4871)
		(width 0.2794)
		(layer "F.Cu")
		(net "FAN_0_PRESENT_N")
	)
	(segment
		(start 10.85596 -163.434014)
		(end 10.967974 -163.322)
		(width 0.2794)
		(layer "F.Cu")
		(net "FAN_0_PRESENT_N")
	)
	(segment
		(start 16.37792 -161.59988)
		(end 16.073374 -161.59988)
		(width 0.2794)
		(layer "F.Cu")
		(net "FAN_0_PRESENT_N")
	)
	(segment
		(start 16.073374 -161.59988)
		(end 15.22095 -162.452304)
		(width 0.2794)
		(layer "F.Cu")
		(net "FAN_0_PRESENT_N")
	)
	(segment
		(start 12.93495 -162.814)
		(end 12.93495 -162.965892)
		(width 0.2794)
		(layer "F.Cu")
		(net "FAN_0_PRESENT_N")
	)
	(via
		(at 16.37792 -161.59988)
		(size 0.762)
		(drill 0.381)
		(layers "F.Cu" "B.Cu")
		(net "FAN_0_PRESENT_N")
	)
	(segment
		(start 14.75105 -20.241768)
		(end 15.36065 -20.241768)
		(width 0.2794)
		(layer "F.Cu")
		(net "SMB_FAN4_SCL")
	)
	(segment
		(start 33.401 -160.54705)
		(end 33.401 -161.163)
		(width 0.2794)
		(layer "F.Cu")
		(net "SMB_FAN4_SCL")
	)
	(segment
		(start 33.274 -160.42005)
		(end 33.401 -160.54705)
		(width 0.2794)
		(layer "F.Cu")
		(net "SMB_FAN4_SCL")
	)
	(via
		(at 15.36065 -20.241768)
		(size 0.508)
		(drill 0.254)
		(layers "F.Cu" "B.Cu")
		(net "SMB_FAN4_SCL")
	)
	(via
		(at 33.401 -161.163)
		(size 0.508)
		(drill 0.254)
		(layers "F.Cu" "B.Cu")
		(net "SMB_FAN4_SCL")
	)
	(segment
		(start 27.9908 -149.185884)
		(end 32.724598 -160.874202)
		(width 0.2286)
		(layer "In2.Cu")
		(net "SMB_FAN4_SCL")
	)
	(segment
		(start 26.81986 -131.72186)
		(end 27.94 -132.842)
		(width 0.2286)
		(layer "In2.Cu")
		(net "SMB_FAN4_SCL")
	)
	(segment
		(start 17.149572 -36.825682)
		(end 17.149572 -52.284884)
		(width 0.2286)
		(layer "In2.Cu")
		(net "SMB_FAN4_SCL")
	)
	(segment
		(start 14.674596 -26.764996)
		(end 17.526 -29.6164)
		(width 0.2286)
		(layer "In2.Cu")
		(net "SMB_FAN4_SCL")
	)
	(segment
		(start 26.289 -123.824746)
		(end 26.289 -129.245106)
		(width 0.2286)
		(layer "In2.Cu")
		(net "SMB_FAN4_SCL")
	)
	(segment
		(start 27.9908 -142.868396)
		(end 27.9908 -149.185884)
		(width 0.2286)
		(layer "In2.Cu")
		(net "SMB_FAN4_SCL")
	)
	(segment
		(start 23.115778 -108.151422)
		(end 21.146516 -110.120684)
		(width 0.2286)
		(layer "In2.Cu")
		(net "SMB_FAN4_SCL")
	)
	(segment
		(start 32.724598 -160.874202)
		(end 33.401 -161.163)
		(width 0.2286)
		(layer "In2.Cu")
		(net "SMB_FAN4_SCL")
	)
	(segment
		(start 20.066 -32.639)
		(end 20.066 -33.909254)
		(width 0.2286)
		(layer "In2.Cu")
		(net "SMB_FAN4_SCL")
	)
	(segment
		(start 21.146516 -116.650262)
		(end 23.241 -118.744746)
		(width 0.2286)
		(layer "In2.Cu")
		(net "SMB_FAN4_SCL")
	)
	(segment
		(start 21.68398 -84.64296)
		(end 22.226016 -85.184996)
		(width 0.2286)
		(layer "In2.Cu")
		(net "SMB_FAN4_SCL")
	)
	(segment
		(start 22.226016 -101.453442)
		(end 23.115778 -102.343204)
		(width 0.2286)
		(layer "In2.Cu")
		(net "SMB_FAN4_SCL")
	)
	(segment
		(start 22.226016 -85.184996)
		(end 22.226016 -101.453442)
		(width 0.2286)
		(layer "In2.Cu")
		(net "SMB_FAN4_SCL")
	)
	(segment
		(start 21.146516 -110.120684)
		(end 21.146516 -116.650262)
		(width 0.2286)
		(layer "In2.Cu")
		(net "SMB_FAN4_SCL")
	)
	(segment
		(start 21.68398 -63.247778)
		(end 21.68398 -84.64296)
		(width 0.2286)
		(layer "In2.Cu")
		(net "SMB_FAN4_SCL")
	)
	(segment
		(start 14.674596 -20.927822)
		(end 14.674596 -26.764996)
		(width 0.2286)
		(layer "In2.Cu")
		(net "SMB_FAN4_SCL")
	)
	(segment
		(start 17.149572 -52.284884)
		(end 21.68398 -63.247778)
		(width 0.2286)
		(layer "In2.Cu")
		(net "SMB_FAN4_SCL")
	)
	(segment
		(start 28.956 -137.16)
		(end 28.956 -141.903196)
		(width 0.2286)
		(layer "In2.Cu")
		(net "SMB_FAN4_SCL")
	)
	(segment
		(start 26.289 -129.245106)
		(end 26.81986 -129.775966)
		(width 0.2286)
		(layer "In2.Cu")
		(net "SMB_FAN4_SCL")
	)
	(segment
		(start 27.94 -132.842)
		(end 27.94 -136.144)
		(width 0.2286)
		(layer "In2.Cu")
		(net "SMB_FAN4_SCL")
	)
	(segment
		(start 20.066 -33.909254)
		(end 17.149572 -36.825682)
		(width 0.2286)
		(layer "In2.Cu")
		(net "SMB_FAN4_SCL")
	)
	(segment
		(start 17.526 -30.099)
		(end 20.066 -32.639)
		(width 0.2286)
		(layer "In2.Cu")
		(net "SMB_FAN4_SCL")
	)
	(segment
		(start 27.94 -136.144)
		(end 28.956 -137.16)
		(width 0.2286)
		(layer "In2.Cu")
		(net "SMB_FAN4_SCL")
	)
	(segment
		(start 15.36065 -20.241768)
		(end 14.674596 -20.927822)
		(width 0.2286)
		(layer "In2.Cu")
		(net "SMB_FAN4_SCL")
	)
	(segment
		(start 23.115778 -102.343204)
		(end 23.115778 -108.151422)
		(width 0.2286)
		(layer "In2.Cu")
		(net "SMB_FAN4_SCL")
	)
	(segment
		(start 17.526 -29.6164)
		(end 17.526 -30.099)
		(width 0.2286)
		(layer "In2.Cu")
		(net "SMB_FAN4_SCL")
	)
	(segment
		(start 23.241 -118.744746)
		(end 23.241 -120.776746)
		(width 0.2286)
		(layer "In2.Cu")
		(net "SMB_FAN4_SCL")
	)
	(segment
		(start 26.81986 -129.775966)
		(end 26.81986 -131.72186)
		(width 0.2286)
		(layer "In2.Cu")
		(net "SMB_FAN4_SCL")
	)
	(segment
		(start 28.956 -141.903196)
		(end 27.9908 -142.868396)
		(width 0.2286)
		(layer "In2.Cu")
		(net "SMB_FAN4_SCL")
	)
	(segment
		(start 23.241 -120.776746)
		(end 26.289 -123.824746)
		(width 0.2286)
		(layer "In2.Cu")
		(net "SMB_FAN4_SCL")
	)
	(segment
		(start 6.71195 -66.088768)
		(end 6.71195 -65.913)
		(width 0.2794)
		(layer "F.Cu")
		(net "FAN_4_FAULT_R")
	)
	(segment
		(start 6.32587 -67.019678)
		(end 6.523736 -67.217544)
		(width 0.2794)
		(layer "F.Cu")
		(net "FAN_4_FAULT_R")
	)
	(segment
		(start 5.715 -65.67805)
		(end 5.715 -65.947798)
		(width 0.2794)
		(layer "F.Cu")
		(net "FAN_4_FAULT_R")
	)
	(segment
		(start 6.32587 -66.558668)
		(end 6.32587 -67.019678)
		(width 0.2794)
		(layer "F.Cu")
		(net "FAN_4_FAULT_R")
	)
	(segment
		(start 5.715 -65.947798)
		(end 6.32587 -66.558668)
		(width 0.2794)
		(layer "F.Cu")
		(net "FAN_4_FAULT_R")
	)
	(segment
		(start 7.108698 -66.485516)
		(end 6.71195 -66.088768)
		(width 0.2794)
		(layer "F.Cu")
		(net "FAN_4_FAULT_R")
	)
	(segment
		(start 7.108698 -67.217544)
		(end 7.108698 -66.485516)
		(width 0.2794)
		(layer "F.Cu")
		(net "FAN_4_FAULT_R")
	)
	(segment
		(start 6.523736 -67.217544)
		(end 7.108698 -67.217544)
		(width 0.2794)
		(layer "F.Cu")
		(net "FAN_4_FAULT_R")
	)
	(via
		(at 7.108698 -67.217544)
		(size 0.762)
		(drill 0.381)
		(layers "F.Cu" "B.Cu")
		(net "FAN_4_FAULT_R")
	)
	(segment
		(start 24.83104 -290.082986)
		(end 22.433026 -292.481)
		(width 0.2794)
		(layer "F.Cu")
		(net "FAN_7_PWM_IL")
	)
	(segment
		(start 16.129 -292.481)
		(end 15.1511 -291.5031)
		(width 0.2794)
		(layer "F.Cu")
		(net "FAN_7_PWM_IL")
	)
	(segment
		(start 22.433026 -292.481)
		(end 20.32 -292.481)
		(width 0.2794)
		(layer "F.Cu")
		(net "FAN_7_PWM_IL")
	)
	(segment
		(start 20.32 -292.481)
		(end 16.129 -292.481)
		(width 0.2794)
		(layer "F.Cu")
		(net "FAN_7_PWM_IL")
	)
	(segment
		(start 15.1511 -291.5031)
		(end 14.761972 -291.5031)
		(width 0.2794)
		(layer "F.Cu")
		(net "FAN_7_PWM_IL")
	)
	(via
		(at 20.32 -292.481)
		(size 0.762)
		(drill 0.381)
		(layers "F.Cu" "B.Cu")
		(net "FAN_7_PWM_IL")
	)
	(via
		(at 2.613914 -63.288164)
		(size 0.6604)
		(drill 0.3302)
		(layers "F.Cu" "B.Cu")
		(net "FAN_4_IMON")
	)
	(segment
		(start 4.100068 -61.762386)
		(end 3.599942 -62.262512)
		(width 0.1016)
		(layer "B.Cu")
		(net "FAN_4_IMON")
	)
	(segment
		(start 2.794 -64.437006)
		(end 2.794 -64.310006)
		(width 0.2794)
		(layer "B.Cu")
		(net "FAN_4_IMON")
	)
	(segment
		(start 2.794 -64.310006)
		(end 2.613914 -64.12992)
		(width 0.2794)
		(layer "B.Cu")
		(net "FAN_4_IMON")
	)
	(segment
		(start 2.613914 -63.19774)
		(end 2.613914 -63.288164)
		(width 0.2794)
		(layer "B.Cu")
		(net "FAN_4_IMON")
	)
	(segment
		(start 3.599942 -62.262512)
		(end 3.549142 -62.262512)
		(width 0.1016)
		(layer "B.Cu")
		(net "FAN_4_IMON")
	)
	(segment
		(start 4.100068 -61.345064)
		(end 4.100068 -61.762386)
		(width 0.1016)
		(layer "B.Cu")
		(net "FAN_4_IMON")
	)
	(segment
		(start 2.613914 -64.12992)
		(end 2.613914 -63.288164)
		(width 0.2794)
		(layer "B.Cu")
		(net "FAN_4_IMON")
	)
	(segment
		(start 3.549142 -62.262512)
		(end 2.613914 -63.19774)
		(width 0.2794)
		(layer "B.Cu")
		(net "FAN_4_IMON")
	)
	(segment
		(start 17.35963 -135.44931)
		(end 17.52727 -135.61695)
		(width 0.2794)
		(layer "F.Cu")
		(net "MAX31790_U330_WD_START")
	)
	(segment
		(start 17.3609 -135.44804)
		(end 17.35963 -135.44931)
		(width 0.2794)
		(layer "F.Cu")
		(net "MAX31790_U330_WD_START")
	)
	(segment
		(start 18.034 -133.58495)
		(end 18.60296 -133.01599)
		(width 0.2794)
		(layer "F.Cu")
		(net "MAX31790_U330_WD_START")
	)
	(segment
		(start 20.55495 -131.731512)
		(end 20.55495 -131.158996)
		(width 0.1016)
		(layer "F.Cu")
		(net "MAX31790_U330_WD_START")
	)
	(segment
		(start 17.907 -133.71195)
		(end 17.755108 -133.71195)
		(width 0.2794)
		(layer "F.Cu")
		(net "MAX31790_U330_WD_START")
	)
	(segment
		(start 18.034 -133.58495)
		(end 17.907 -133.71195)
		(width 0.2794)
		(layer "F.Cu")
		(net "MAX31790_U330_WD_START")
	)
	(segment
		(start 18.60296 -133.01599)
		(end 19.270472 -133.01599)
		(width 0.2794)
		(layer "F.Cu")
		(net "MAX31790_U330_WD_START")
	)
	(segment
		(start 17.755108 -133.71195)
		(end 17.3609 -134.106158)
		(width 0.2794)
		(layer "F.Cu")
		(net "MAX31790_U330_WD_START")
	)
	(segment
		(start 19.270472 -133.01599)
		(end 20.55495 -131.731512)
		(width 0.1016)
		(layer "F.Cu")
		(net "MAX31790_U330_WD_START")
	)
	(segment
		(start 17.3609 -134.106158)
		(end 17.3609 -135.44804)
		(width 0.2794)
		(layer "F.Cu")
		(net "MAX31790_U330_WD_START")
	)
	(segment
		(start 17.52727 -135.61695)
		(end 18.034 -135.61695)
		(width 0.2794)
		(layer "F.Cu")
		(net "MAX31790_U330_WD_START")
	)
	(via
		(at 17.35963 -135.44931)
		(size 0.508)
		(drill 0.254)
		(layers "F.Cu" "B.Cu")
		(net "MAX31790_U330_WD_START")
	)
	(via
		(at 8.040878 -63.256668)
		(size 0.6604)
		(drill 0.3302)
		(layers "F.Cu" "B.Cu")
		(net "FAN_4_P5V")
	)
	(segment
		(start 7.981696 -62.581282)
		(end 7.430262 -62.029848)
		(width 0.1016)
		(layer "B.Cu")
		(net "FAN_4_P5V")
	)
	(segment
		(start 8.040878 -63.256668)
		(end 8.080502 -62.858396)
		(width 0.1016)
		(layer "B.Cu")
		(net "FAN_4_P5V")
	)
	(segment
		(start 8.41375 -64.15659)
		(end 8.694166 -64.437006)
		(width 0.2794)
		(layer "B.Cu")
		(net "FAN_4_P5V")
	)
	(segment
		(start 8.080502 -62.858396)
		(end 7.981696 -62.581282)
		(width 0.1016)
		(layer "B.Cu")
		(net "FAN_4_P5V")
	)
	(segment
		(start 8.040878 -63.256668)
		(end 8.41375 -64.15659)
		(width 0.2794)
		(layer "B.Cu")
		(net "FAN_4_P5V")
	)
	(segment
		(start 7.300214 -61.71565)
		(end 7.300214 -61.345064)
		(width 0.1016)
		(layer "B.Cu")
		(net "FAN_4_P5V")
	)
	(segment
		(start 7.430262 -62.029848)
		(end 7.300214 -61.71565)
		(width 0.1016)
		(layer "B.Cu")
		(net "FAN_4_P5V")
	)
	(segment
		(start 24.32304 -196.454014)
		(end 21.290026 -193.421)
		(width 0.2794)
		(layer "F.Cu")
		(net "FAN_6_PWM_OL")
	)
	(segment
		(start 21.290026 -193.421)
		(end 16.338804 -193.421)
		(width 0.2794)
		(layer "F.Cu")
		(net "FAN_6_PWM_OL")
	)
	(segment
		(start 14.634972 -194.250056)
		(end 14.989048 -194.250056)
		(width 0.2794)
		(layer "F.Cu")
		(net "FAN_6_PWM_OL")
	)
	(segment
		(start 16.338804 -193.421)
		(end 16.161004 -193.5988)
		(width 0.2794)
		(layer "F.Cu")
		(net "FAN_6_PWM_OL")
	)
	(segment
		(start 16.161004 -193.5988)
		(end 15.640304 -193.5988)
		(width 0.2794)
		(layer "F.Cu")
		(net "FAN_6_PWM_OL")
	)
	(segment
		(start 14.989048 -194.250056)
		(end 15.640304 -193.5988)
		(width 0.2794)
		(layer "F.Cu")
		(net "FAN_6_PWM_OL")
	)
	(via
		(at 15.640304 -193.5988)
		(size 0.508)
		(drill 0.254)
		(layers "F.Cu" "B.Cu")
		(net "FAN_6_PWM_OL")
	)
	(segment
		(start 22.225 -135.61695)
		(end 22.479 -135.61695)
		(width 0.2794)
		(layer "F.Cu")
		(net "MAX31790_U330_SPIN_START")
	)
	(segment
		(start 22.225 -132.520944)
		(end 22.225 -132.7912)
		(width 0.2794)
		(layer "F.Cu")
		(net "MAX31790_U330_SPIN_START")
	)
	(segment
		(start 22.8981 -135.19785)
		(end 22.8981 -134.106158)
		(width 0.2794)
		(layer "F.Cu")
		(net "MAX31790_U330_SPIN_START")
	)
	(segment
		(start 21.7551 -131.158996)
		(end 21.7551 -131.82981)
		(width 0.1016)
		(layer "F.Cu")
		(net "MAX31790_U330_SPIN_START")
	)
	(segment
		(start 22.225 -132.29971)
		(end 22.225 -132.520944)
		(width 0.1016)
		(layer "F.Cu")
		(net "MAX31790_U330_SPIN_START")
	)
	(segment
		(start 22.8981 -134.106158)
		(end 22.376892 -133.58495)
		(width 0.2794)
		(layer "F.Cu")
		(net "MAX31790_U330_SPIN_START")
	)
	(segment
		(start 22.376892 -133.58495)
		(end 22.225 -133.58495)
		(width 0.2794)
		(layer "F.Cu")
		(net "MAX31790_U330_SPIN_START")
	)
	(segment
		(start 22.479 -135.61695)
		(end 22.8981 -135.19785)
		(width 0.2794)
		(layer "F.Cu")
		(net "MAX31790_U330_SPIN_START")
	)
	(segment
		(start 21.7551 -131.82981)
		(end 22.225 -132.29971)
		(width 0.1016)
		(layer "F.Cu")
		(net "MAX31790_U330_SPIN_START")
	)
	(segment
		(start 22.225 -132.7912)
		(end 22.225 -133.58495)
		(width 0.2794)
		(layer "F.Cu")
		(net "MAX31790_U330_SPIN_START")
	)
	(via
		(at 22.225 -132.7912)
		(size 0.508)
		(drill 0.254)
		(layers "F.Cu" "B.Cu")
		(net "MAX31790_U330_SPIN_START")
	)
	(segment
		(start 7.51205 -65.913)
		(end 7.51205 -64.897)
		(width 0.2794)
		(layer "F.Cu")
		(net "FAN_4_P3V_R")
	)
	(segment
		(start 9.646412 -62.628018)
		(end 10.07618 -63.057786)
		(width 0.2794)
		(layer "F.Cu")
		(net "FAN_4_P3V_R")
	)
	(segment
		(start 7.564882 -62.628018)
		(end 9.646412 -62.628018)
		(width 0.2794)
		(layer "F.Cu")
		(net "FAN_4_P3V_R")
	)
	(segment
		(start 10.07618 -63.057786)
		(end 10.07618 -63.723266)
		(width 0.2794)
		(layer "F.Cu")
		(net "FAN_4_P3V_R")
	)
	(segment
		(start 8.902446 -64.897)
		(end 7.51205 -64.897)
		(width 0.2794)
		(layer "F.Cu")
		(net "FAN_4_P3V_R")
	)
	(segment
		(start 7.46506 -62.72784)
		(end 7.564882 -62.628018)
		(width 0.2794)
		(layer "F.Cu")
		(net "FAN_4_P3V_R")
	)
	(segment
		(start 10.07618 -63.723266)
		(end 8.902446 -64.897)
		(width 0.2794)
		(layer "F.Cu")
		(net "FAN_4_P3V_R")
	)
	(via
		(at 7.46506 -62.72784)
		(size 0.762)
		(drill 0.254)
		(layers "F.Cu" "B.Cu")
		(net "FAN_4_P3V_R")
	)
	(segment
		(start 7.21995 -62.48273)
		(end 6.900164 -61.710062)
		(width 0.1016)
		(layer "B.Cu")
		(net "FAN_4_P3V_R")
	)
	(segment
		(start 7.46506 -62.72784)
		(end 7.21995 -62.48273)
		(width 0.1016)
		(layer "B.Cu")
		(net "FAN_4_P3V_R")
	)
	(segment
		(start 7.46506 -62.72784)
		(end 7.314692 -62.959488)
		(width 0.2794)
		(layer "B.Cu")
		(net "FAN_4_P3V_R")
	)
	(segment
		(start 6.900164 -61.710062)
		(end 6.900164 -61.345064)
		(width 0.1016)
		(layer "B.Cu")
		(net "FAN_4_P3V_R")
	)
	(segment
		(start 7.606284 -64.427608)
		(end 7.62 -64.437006)
		(width 0.2794)
		(layer "B.Cu")
		(net "FAN_4_P3V_R")
	)
	(segment
		(start 7.314692 -62.959488)
		(end 7.606284 -64.427608)
		(width 0.2794)
		(layer "B.Cu")
		(net "FAN_4_P3V_R")
	)
	(segment
		(start 5.35178 -161.5567)
		(end 5.008626 -161.5567)
		(width 0.2794)
		(layer "F.Cu")
		(net "FAN_0_PRSNT_BUF_R_N")
	)
	(segment
		(start 8.844026 -163.322)
		(end 8.95604 -163.434014)
		(width 0.2794)
		(layer "F.Cu")
		(net "FAN_0_PRSNT_BUF_R_N")
	)
	(segment
		(start 5.771642 -161.5567)
		(end 5.35178 -161.5567)
		(width 0.2794)
		(layer "F.Cu")
		(net "FAN_0_PRSNT_BUF_R_N")
	)
	(segment
		(start 6.87705 -162.814)
		(end 7.38505 -163.322)
		(width 0.2794)
		(layer "F.Cu")
		(net "FAN_0_PRSNT_BUF_R_N")
	)
	(segment
		(start 6.87705 -162.814)
		(end 6.87705 -162.662108)
		(width 0.2794)
		(layer "F.Cu")
		(net "FAN_0_PRSNT_BUF_R_N")
	)
	(segment
		(start 4.59105 -161.974276)
		(end 4.59105 -162.814)
		(width 0.2794)
		(layer "F.Cu")
		(net "FAN_0_PRSNT_BUF_R_N")
	)
	(segment
		(start 5.008626 -161.5567)
		(end 4.59105 -161.974276)
		(width 0.2794)
		(layer "F.Cu")
		(net "FAN_0_PRSNT_BUF_R_N")
	)
	(segment
		(start 7.38505 -163.322)
		(end 8.844026 -163.322)
		(width 0.2794)
		(layer "F.Cu")
		(net "FAN_0_PRSNT_BUF_R_N")
	)
	(segment
		(start 6.87705 -162.662108)
		(end 5.771642 -161.5567)
		(width 0.2794)
		(layer "F.Cu")
		(net "FAN_0_PRSNT_BUF_R_N")
	)
	(via
		(at 5.35178 -161.5567)
		(size 0.762)
		(drill 0.381)
		(layers "F.Cu" "B.Cu")
		(net "FAN_0_PRSNT_BUF_R_N")
	)
	(segment
		(start 22.154896 -131.549648)
		(end 22.154896 -131.158996)
		(width 0.1016)
		(layer "F.Cu")
		(net "MAX31790_U330_FREQ_START")
	)
	(segment
		(start 23.622 -135.61695)
		(end 23.876 -135.61695)
		(width 0.2794)
		(layer "F.Cu")
		(net "MAX31790_U330_FREQ_START")
	)
	(segment
		(start 23.876 -135.61695)
		(end 24.2951 -135.19785)
		(width 0.2794)
		(layer "F.Cu")
		(net "MAX31790_U330_FREQ_START")
	)
	(segment
		(start 23.20036 -133.16331)
		(end 23.20036 -132.48386)
		(width 0.2794)
		(layer "F.Cu")
		(net "MAX31790_U330_FREQ_START")
	)
	(segment
		(start 24.2951 -135.19785)
		(end 24.2951 -134.106158)
		(width 0.2794)
		(layer "F.Cu")
		(net "MAX31790_U330_FREQ_START")
	)
	(segment
		(start 22.805898 -132.20065)
		(end 22.154896 -131.549648)
		(width 0.1016)
		(layer "F.Cu")
		(net "MAX31790_U330_FREQ_START")
	)
	(segment
		(start 23.773892 -133.58495)
		(end 23.622 -133.58495)
		(width 0.2794)
		(layer "F.Cu")
		(net "MAX31790_U330_FREQ_START")
	)
	(segment
		(start 23.20036 -132.48386)
		(end 23.11146 -132.39496)
		(width 0.2794)
		(layer "F.Cu")
		(net "MAX31790_U330_FREQ_START")
	)
	(segment
		(start 24.2951 -134.106158)
		(end 23.773892 -133.58495)
		(width 0.2794)
		(layer "F.Cu")
		(net "MAX31790_U330_FREQ_START")
	)
	(segment
		(start 23.000208 -132.39496)
		(end 22.805898 -132.20065)
		(width 0.2794)
		(layer "F.Cu")
		(net "MAX31790_U330_FREQ_START")
	)
	(segment
		(start 23.11146 -132.39496)
		(end 23.000208 -132.39496)
		(width 0.2794)
		(layer "F.Cu")
		(net "MAX31790_U330_FREQ_START")
	)
	(segment
		(start 23.622 -133.58495)
		(end 23.20036 -133.16331)
		(width 0.2794)
		(layer "F.Cu")
		(net "MAX31790_U330_FREQ_START")
	)
	(via
		(at 23.11146 -132.39496)
		(size 0.762)
		(drill 0.381)
		(layers "F.Cu" "B.Cu")
		(net "MAX31790_U330_FREQ_START")
	)
	(via
		(at 2.3876 -61.345064)
		(size 0.762)
		(drill 0.254)
		(layers "F.Cu" "B.Cu")
		(net "FAN_4_CS")
	)
	(segment
		(start 1.778 -64.427862)
		(end 1.778 -63.932562)
		(width 0.2794)
		(layer "B.Cu")
		(net "FAN_4_CS")
	)
	(segment
		(start 2.3876 -61.345064)
		(end 3.546856 -61.345064)
		(width 0.2794)
		(layer "B.Cu")
		(net "FAN_4_CS")
	)
	(segment
		(start 1.785366 -63.925196)
		(end 1.785366 -61.947298)
		(width 0.2794)
		(layer "B.Cu")
		(net "FAN_4_CS")
	)
	(segment
		(start 1.778 -63.932562)
		(end 1.785366 -63.925196)
		(width 0.2794)
		(layer "B.Cu")
		(net "FAN_4_CS")
	)
	(segment
		(start 1.785366 -61.947298)
		(end 2.3876 -61.345064)
		(width 0.2794)
		(layer "B.Cu")
		(net "FAN_4_CS")
	)
	(segment
		(start 3.546856 -61.345064)
		(end 3.700272 -61.345064)
		(width 0.1016)
		(layer "B.Cu")
		(net "FAN_4_CS")
	)
	(segment
		(start 22.357842 -201.3331)
		(end 21.7551 -201.3331)
		(width 0.2794)
		(layer "F.Cu")
		(net "FAN_6_PWM_IL")
	)
	(segment
		(start 20.701 -200.279)
		(end 20.701 -200.406)
		(width 0.2794)
		(layer "F.Cu")
		(net "FAN_6_PWM_IL")
	)
	(segment
		(start 14.761972 -199.076056)
		(end 15.180056 -199.076056)
		(width 0.2794)
		(layer "F.Cu")
		(net "FAN_6_PWM_IL")
	)
	(segment
		(start 21.7551 -201.3331)
		(end 20.828 -200.406)
		(width 0.2794)
		(layer "F.Cu")
		(net "FAN_6_PWM_IL")
	)
	(segment
		(start 20.193 -199.771)
		(end 20.701 -200.279)
		(width 0.2794)
		(layer "F.Cu")
		(net "FAN_6_PWM_IL")
	)
	(segment
		(start 15.875 -199.771)
		(end 20.193 -199.771)
		(width 0.2794)
		(layer "F.Cu")
		(net "FAN_6_PWM_IL")
	)
	(segment
		(start 24.32304 -198.20001)
		(end 22.87905 -199.644)
		(width 0.2794)
		(layer "F.Cu")
		(net "FAN_6_PWM_IL")
	)
	(segment
		(start 24.32304 -197.753986)
		(end 24.32304 -198.20001)
		(width 0.2794)
		(layer "F.Cu")
		(net "FAN_6_PWM_IL")
	)
	(segment
		(start 22.87905 -200.811892)
		(end 22.357842 -201.3331)
		(width 0.2794)
		(layer "F.Cu")
		(net "FAN_6_PWM_IL")
	)
	(segment
		(start 20.828 -200.406)
		(end 20.701 -200.406)
		(width 0.2794)
		(layer "F.Cu")
		(net "FAN_6_PWM_IL")
	)
	(segment
		(start 15.180056 -199.076056)
		(end 15.875 -199.771)
		(width 0.2794)
		(layer "F.Cu")
		(net "FAN_6_PWM_IL")
	)
	(segment
		(start 22.87905 -199.644)
		(end 22.87905 -200.811892)
		(width 0.2794)
		(layer "F.Cu")
		(net "FAN_6_PWM_IL")
	)
	(via
		(at 20.701 -200.406)
		(size 0.762)
		(drill 0.381)
		(layers "F.Cu" "B.Cu")
		(net "FAN_6_PWM_IL")
	)
	(segment
		(start 24.511508 -125.964442)
		(end 25.12695 -125.349)
		(width 0.2794)
		(layer "F.Cu")
		(net "MAX31790_U330_PWM_START0")
	)
	(segment
		(start 25.12695 -124.079)
		(end 25.12695 -125.349)
		(width 0.2794)
		(layer "F.Cu")
		(net "MAX31790_U330_PWM_START0")
	)
	(segment
		(start 24.511508 -128.341882)
		(end 24.511508 -127.847598)
		(width 0.1016)
		(layer "F.Cu")
		(net "MAX31790_U330_PWM_START0")
	)
	(segment
		(start 24.511508 -127.49022)
		(end 24.511508 -125.964442)
		(width 0.2794)
		(layer "F.Cu")
		(net "MAX31790_U330_PWM_START0")
	)
	(segment
		(start 23.69439 -129.159)
		(end 24.511508 -128.341882)
		(width 0.1016)
		(layer "F.Cu")
		(net "MAX31790_U330_PWM_START0")
	)
	(segment
		(start 24.511508 -127.847598)
		(end 24.511508 -127.49022)
		(width 0.2794)
		(layer "F.Cu")
		(net "MAX31790_U330_PWM_START0")
	)
	(segment
		(start 22.954996 -129.159)
		(end 23.69439 -129.159)
		(width 0.1016)
		(layer "F.Cu")
		(net "MAX31790_U330_PWM_START0")
	)
	(via
		(at 24.511508 -127.49022)
		(size 0.508)
		(drill 0.254)
		(layers "F.Cu" "B.Cu")
		(net "MAX31790_U330_PWM_START0")
	)
	(segment
		(start 24.90216 -128.70942)
		(end 25.12695 -128.48463)
		(width 0.2794)
		(layer "F.Cu")
		(net "MAX31790_U330_PWM_START1")
	)
	(segment
		(start 25.12695 -126.619)
		(end 25.12695 -127.889)
		(width 0.2794)
		(layer "F.Cu")
		(net "MAX31790_U330_PWM_START1")
	)
	(segment
		(start 24.05253 -129.55905)
		(end 24.57958 -129.032)
		(width 0.1016)
		(layer "F.Cu")
		(net "MAX31790_U330_PWM_START1")
	)
	(segment
		(start 22.954996 -129.55905)
		(end 24.05253 -129.55905)
		(width 0.1016)
		(layer "F.Cu")
		(net "MAX31790_U330_PWM_START1")
	)
	(segment
		(start 24.57958 -129.032)
		(end 24.90216 -128.70942)
		(width 0.2794)
		(layer "F.Cu")
		(net "MAX31790_U330_PWM_START1")
	)
	(segment
		(start 25.12695 -128.48463)
		(end 25.12695 -127.889)
		(width 0.2794)
		(layer "F.Cu")
		(net "MAX31790_U330_PWM_START1")
	)
	(via
		(at 24.90216 -128.70942)
		(size 0.508)
		(drill 0.254)
		(layers "F.Cu" "B.Cu")
		(net "MAX31790_U330_PWM_START1")
	)
	(via
		(at 5.2451 -63.12154)
		(size 0.6604)
		(drill 0.3302)
		(layers "F.Cu" "B.Cu")
		(net "FAN_4_TIMER")
	)
	(segment
		(start 4.826 -63.881)
		(end 4.826 -64.437006)
		(width 0.2794)
		(layer "B.Cu")
		(net "FAN_4_TIMER")
	)
	(segment
		(start 5.08 -63.28664)
		(end 5.08 -63.627)
		(width 0.1016)
		(layer "B.Cu")
		(net "FAN_4_TIMER")
	)
	(segment
		(start 5.08 -63.627)
		(end 4.826 -63.881)
		(width 0.2794)
		(layer "B.Cu")
		(net "FAN_4_TIMER")
	)
	(segment
		(start 5.15112 -63.02756)
		(end 5.15112 -62.18682)
		(width 0.1016)
		(layer "B.Cu")
		(net "FAN_4_TIMER")
	)
	(segment
		(start 5.15112 -62.18682)
		(end 5.300218 -61.826648)
		(width 0.1016)
		(layer "B.Cu")
		(net "FAN_4_TIMER")
	)
	(segment
		(start 5.300218 -61.826648)
		(end 5.300218 -61.345064)
		(width 0.1016)
		(layer "B.Cu")
		(net "FAN_4_TIMER")
	)
	(segment
		(start 5.2451 -63.12154)
		(end 5.15112 -63.02756)
		(width 0.1016)
		(layer "B.Cu")
		(net "FAN_4_TIMER")
	)
	(segment
		(start 5.2451 -63.12154)
		(end 5.08 -63.28664)
		(width 0.1016)
		(layer "B.Cu")
		(net "FAN_4_TIMER")
	)
	(segment
		(start 22.648926 -101.9429)
		(end 20.7899 -101.9429)
		(width 0.2794)
		(layer "F.Cu")
		(net "FAN_5_PWM_OL")
	)
	(segment
		(start 19.177 -100.33)
		(end 16.254984 -100.33)
		(width 0.2794)
		(layer "F.Cu")
		(net "FAN_5_PWM_OL")
	)
	(segment
		(start 16.254984 -100.33)
		(end 14.634972 -101.950012)
		(width 0.2794)
		(layer "F.Cu")
		(net "FAN_5_PWM_OL")
	)
	(segment
		(start 20.7899 -101.9429)
		(end 19.177 -100.33)
		(width 0.2794)
		(layer "F.Cu")
		(net "FAN_5_PWM_OL")
	)
	(segment
		(start 24.45004 -103.744014)
		(end 22.648926 -101.9429)
		(width 0.2794)
		(layer "F.Cu")
		(net "FAN_5_PWM_OL")
	)
	(via
		(at 22.648926 -101.9429)
		(size 0.762)
		(drill 0.381)
		(layers "F.Cu" "B.Cu")
		(net "FAN_5_PWM_OL")
	)
	(segment
		(start 32.85998 -125.78842)
		(end 32.7914 -125.857)
		(width 0.2794)
		(layer "F.Cu")
		(net "MAX31790_U317_WD_START")
	)
	(segment
		(start 34.417 -124.60605)
		(end 33.80105 -125.222)
		(width 0.2794)
		(layer "F.Cu")
		(net "MAX31790_U317_WD_START")
	)
	(segment
		(start 34.568892 -124.60605)
		(end 35.0901 -124.084842)
		(width 0.2794)
		(layer "F.Cu")
		(net "MAX31790_U317_WD_START")
	)
	(segment
		(start 31.89605 -126.47295)
		(end 31.89605 -127.159004)
		(width 0.1016)
		(layer "F.Cu")
		(net "MAX31790_U317_WD_START")
	)
	(segment
		(start 32.7914 -125.857)
		(end 32.512 -125.857)
		(width 0.2794)
		(layer "F.Cu")
		(net "MAX31790_U317_WD_START")
	)
	(segment
		(start 35.0901 -124.084842)
		(end 35.0901 -122.99315)
		(width 0.2794)
		(layer "F.Cu")
		(net "MAX31790_U317_WD_START")
	)
	(segment
		(start 33.80105 -125.222)
		(end 33.4264 -125.222)
		(width 0.2794)
		(layer "F.Cu")
		(net "MAX31790_U317_WD_START")
	)
	(segment
		(start 35.0901 -122.99315)
		(end 34.417 -122.32005)
		(width 0.2794)
		(layer "F.Cu")
		(net "MAX31790_U317_WD_START")
	)
	(segment
		(start 34.417 -124.60605)
		(end 34.568892 -124.60605)
		(width 0.2794)
		(layer "F.Cu")
		(net "MAX31790_U317_WD_START")
	)
	(segment
		(start 32.512 -125.857)
		(end 31.89605 -126.47295)
		(width 0.1016)
		(layer "F.Cu")
		(net "MAX31790_U317_WD_START")
	)
	(segment
		(start 33.4264 -125.222)
		(end 32.85998 -125.78842)
		(width 0.2794)
		(layer "F.Cu")
		(net "MAX31790_U317_WD_START")
	)
	(via
		(at 32.85998 -125.78842)
		(size 0.762)
		(drill 0.381)
		(layers "F.Cu" "B.Cu")
		(net "MAX31790_U317_WD_START")
	)
	(segment
		(start 4.699 -63.78067)
		(end 4.699 -63.212472)
		(width 0.2794)
		(layer "F.Cu")
		(net "FAN_4_FAULT")
	)
	(segment
		(start 4.285742 -64.193928)
		(end 4.699 -63.78067)
		(width 0.2794)
		(layer "F.Cu")
		(net "FAN_4_FAULT")
	)
	(segment
		(start 5.367528 -64.87795)
		(end 4.961382 -65.284096)
		(width 0.2794)
		(layer "F.Cu")
		(net "FAN_4_FAULT")
	)
	(segment
		(start 4.285742 -65.284096)
		(end 4.285742 -64.193928)
		(width 0.2794)
		(layer "F.Cu")
		(net "FAN_4_FAULT")
	)
	(segment
		(start 5.715 -64.87795)
		(end 5.367528 -64.87795)
		(width 0.2794)
		(layer "F.Cu")
		(net "FAN_4_FAULT")
	)
	(segment
		(start 4.699 -63.212472)
		(end 4.516628 -63.0301)
		(width 0.2794)
		(layer "F.Cu")
		(net "FAN_4_FAULT")
	)
	(segment
		(start 4.961382 -65.284096)
		(end 4.285742 -65.284096)
		(width 0.2794)
		(layer "F.Cu")
		(net "FAN_4_FAULT")
	)
	(via
		(at 4.285742 -65.284096)
		(size 0.762)
		(drill 0.381)
		(layers "F.Cu" "B.Cu")
		(net "FAN_4_FAULT")
	)
	(via
		(at 4.516628 -63.0301)
		(size 0.508)
		(drill 0.254)
		(layers "F.Cu" "B.Cu")
		(net "FAN_4_FAULT")
	)
	(segment
		(start 4.516628 -63.0301)
		(end 4.516628 -62.85484)
		(width 0.2794)
		(layer "B.Cu")
		(net "FAN_4_FAULT")
	)
	(segment
		(start 4.900168 -61.928248)
		(end 4.900168 -61.345064)
		(width 0.1016)
		(layer "B.Cu")
		(net "FAN_4_FAULT")
	)
	(segment
		(start 4.516628 -62.85484)
		(end 4.900168 -61.928248)
		(width 0.1016)
		(layer "B.Cu")
		(net "FAN_4_FAULT")
	)
	(segment
		(start 30.09646 -125.81382)
		(end 30.278324 -125.995684)
		(width 0.2794)
		(layer "F.Cu")
		(net "MAX31790_U317_SPIN_START")
	)
	(segment
		(start 30.226 -124.60605)
		(end 30.09646 -124.73559)
		(width 0.2794)
		(layer "F.Cu")
		(net "MAX31790_U317_SPIN_START")
	)
	(segment
		(start 30.8991 -122.99315)
		(end 30.226 -122.32005)
		(width 0.2794)
		(layer "F.Cu")
		(net "MAX31790_U317_SPIN_START")
	)
	(segment
		(start 30.226 -124.60605)
		(end 30.377892 -124.60605)
		(width 0.2794)
		(layer "F.Cu")
		(net "MAX31790_U317_SPIN_START")
	)
	(segment
		(start 30.09646 -124.73559)
		(end 30.09646 -125.81382)
		(width 0.2794)
		(layer "F.Cu")
		(net "MAX31790_U317_SPIN_START")
	)
	(segment
		(start 30.278324 -125.995684)
		(end 30.341316 -125.995684)
		(width 0.2794)
		(layer "F.Cu")
		(net "MAX31790_U317_SPIN_START")
	)
	(segment
		(start 30.8991 -124.084842)
		(end 30.8991 -122.99315)
		(width 0.2794)
		(layer "F.Cu")
		(net "MAX31790_U317_SPIN_START")
	)
	(segment
		(start 30.341316 -125.995684)
		(end 30.6959 -126.350268)
		(width 0.1016)
		(layer "F.Cu")
		(net "MAX31790_U317_SPIN_START")
	)
	(segment
		(start 30.377892 -124.60605)
		(end 30.8991 -124.084842)
		(width 0.2794)
		(layer "F.Cu")
		(net "MAX31790_U317_SPIN_START")
	)
	(segment
		(start 30.6959 -126.350268)
		(end 30.6959 -127.159004)
		(width 0.1016)
		(layer "F.Cu")
		(net "MAX31790_U317_SPIN_START")
	)
	(via
		(at 30.09646 -125.81382)
		(size 0.508)
		(drill 0.254)
		(layers "F.Cu" "B.Cu")
		(net "MAX31790_U317_SPIN_START")
	)
	(via
		(at 3.756914 -62.91961)
		(size 0.762)
		(drill 0.254)
		(layers "F.Cu" "B.Cu")
		(net "FAN_4_SS")
	)
	(segment
		(start 3.756914 -64.25692)
		(end 3.81 -64.310006)
		(width 0.2794)
		(layer "B.Cu")
		(net "FAN_4_SS")
	)
	(segment
		(start 3.756914 -62.795912)
		(end 3.756914 -62.91961)
		(width 0.1016)
		(layer "B.Cu")
		(net "FAN_4_SS")
	)
	(segment
		(start 3.756914 -62.91961)
		(end 3.756914 -64.25692)
		(width 0.2794)
		(layer "B.Cu")
		(net "FAN_4_SS")
	)
	(segment
		(start 3.81 -64.310006)
		(end 3.81 -64.437006)
		(width 0.2794)
		(layer "B.Cu")
		(net "FAN_4_SS")
	)
	(segment
		(start 4.500118 -61.345064)
		(end 4.500118 -62.052708)
		(width 0.1016)
		(layer "B.Cu")
		(net "FAN_4_SS")
	)
	(segment
		(start 4.500118 -62.052708)
		(end 3.756914 -62.795912)
		(width 0.1016)
		(layer "B.Cu")
		(net "FAN_4_SS")
	)
	(segment
		(start 18.969228 -107.696)
		(end 19.477228 -108.204)
		(width 0.2794)
		(layer "F.Cu")
		(net "FAN_5_PWM_IL")
	)
	(segment
		(start 21.290026 -108.204)
		(end 24.45004 -105.043986)
		(width 0.2794)
		(layer "F.Cu")
		(net "FAN_5_PWM_IL")
	)
	(segment
		(start 16.002 -107.696)
		(end 18.969228 -107.696)
		(width 0.2794)
		(layer "F.Cu")
		(net "FAN_5_PWM_IL")
	)
	(segment
		(start 14.761972 -106.776012)
		(end 15.082012 -106.776012)
		(width 0.2794)
		(layer "F.Cu")
		(net "FAN_5_PWM_IL")
	)
	(segment
		(start 15.082012 -106.776012)
		(end 16.002 -107.696)
		(width 0.2794)
		(layer "F.Cu")
		(net "FAN_5_PWM_IL")
	)
	(segment
		(start 19.477228 -108.204)
		(end 21.290026 -108.204)
		(width 0.2794)
		(layer "F.Cu")
		(net "FAN_5_PWM_IL")
	)
	(via
		(at 19.477228 -108.204)
		(size 0.762)
		(drill 0.381)
		(layers "F.Cu" "B.Cu")
		(net "FAN_5_PWM_IL")
	)
	(segment
		(start 29.69895 -126.365)
		(end 29.718 -126.365)
		(width 0.2794)
		(layer "F.Cu")
		(net "MAX31790_U317_FREQ_START")
	)
	(segment
		(start 28.829 -124.60605)
		(end 28.829 -125.49505)
		(width 0.2794)
		(layer "F.Cu")
		(net "MAX31790_U317_FREQ_START")
	)
	(segment
		(start 28.829 -124.60605)
		(end 28.980892 -124.60605)
		(width 0.2794)
		(layer "F.Cu")
		(net "MAX31790_U317_FREQ_START")
	)
	(segment
		(start 28.980892 -124.60605)
		(end 29.5021 -124.084842)
		(width 0.2794)
		(layer "F.Cu")
		(net "MAX31790_U317_FREQ_START")
	)
	(segment
		(start 29.187902 -125.853952)
		(end 29.69895 -126.365)
		(width 0.2794)
		(layer "F.Cu")
		(net "MAX31790_U317_FREQ_START")
	)
	(segment
		(start 29.5021 -124.084842)
		(end 29.5021 -122.99315)
		(width 0.2794)
		(layer "F.Cu")
		(net "MAX31790_U317_FREQ_START")
	)
	(segment
		(start 30.296104 -126.689104)
		(end 30.296104 -127.159004)
		(width 0.1016)
		(layer "F.Cu")
		(net "MAX31790_U317_FREQ_START")
	)
	(segment
		(start 28.829 -125.49505)
		(end 29.187902 -125.853952)
		(width 0.2794)
		(layer "F.Cu")
		(net "MAX31790_U317_FREQ_START")
	)
	(segment
		(start 29.5021 -122.99315)
		(end 28.829 -122.32005)
		(width 0.2794)
		(layer "F.Cu")
		(net "MAX31790_U317_FREQ_START")
	)
	(segment
		(start 30.099 -126.492)
		(end 30.296104 -126.689104)
		(width 0.1016)
		(layer "F.Cu")
		(net "MAX31790_U317_FREQ_START")
	)
	(segment
		(start 29.718 -126.365)
		(end 29.845 -126.492)
		(width 0.1016)
		(layer "F.Cu")
		(net "MAX31790_U317_FREQ_START")
	)
	(segment
		(start 29.845 -126.492)
		(end 30.099 -126.492)
		(width 0.1016)
		(layer "F.Cu")
		(net "MAX31790_U317_FREQ_START")
	)
	(via
		(at 29.187902 -125.853952)
		(size 0.762)
		(drill 0.381)
		(layers "F.Cu" "B.Cu")
		(net "MAX31790_U317_FREQ_START")
	)
	(via
		(at 5.63118 -62.5221)
		(size 0.762)
		(drill 0.254)
		(layers "F.Cu" "B.Cu")
		(net "FAN_4_CLREF")
	)
	(segment
		(start 5.63118 -62.5221)
		(end 5.887212 -63.403988)
		(width 0.1016)
		(layer "B.Cu")
		(net "FAN_4_CLREF")
	)
	(segment
		(start 5.700268 -61.345064)
		(end 5.700268 -62.239652)
		(width 0.1016)
		(layer "B.Cu")
		(net "FAN_4_CLREF")
	)
	(segment
		(start 5.82295 -63.69685)
		(end 5.82295 -64.389)
		(width 0.2794)
		(layer "B.Cu")
		(net "FAN_4_CLREF")
	)
	(segment
		(start 5.82295 -64.389)
		(end 5.82295 -65.405)
		(width 0.2794)
		(layer "B.Cu")
		(net "FAN_4_CLREF")
	)
	(segment
		(start 5.887212 -63.632588)
		(end 5.82295 -63.69685)
		(width 0.2794)
		(layer "B.Cu")
		(net "FAN_4_CLREF")
	)
	(segment
		(start 5.63118 -62.30874)
		(end 5.63118 -62.5221)
		(width 0.1016)
		(layer "B.Cu")
		(net "FAN_4_CLREF")
	)
	(segment
		(start 5.887212 -63.403988)
		(end 5.887212 -63.632588)
		(width 0.1016)
		(layer "B.Cu")
		(net "FAN_4_CLREF")
	)
	(segment
		(start 5.700268 -62.239652)
		(end 5.63118 -62.30874)
		(width 0.1016)
		(layer "B.Cu")
		(net "FAN_4_CLREF")
	)
	(segment
		(start 26.775918 -130.574796)
		(end 25.92705 -131.423664)
		(width 0.2794)
		(layer "F.Cu")
		(net "MAX31790_U317_PWM_START0")
	)
	(segment
		(start 29.496004 -129.159)
		(end 27.94 -129.159)
		(width 0.1016)
		(layer "F.Cu")
		(net "MAX31790_U317_PWM_START0")
	)
	(segment
		(start 27.11196 -129.23012)
		(end 27.078432 -129.23012)
		(width 0.2794)
		(layer "F.Cu")
		(net "MAX31790_U317_PWM_START0")
	)
	(segment
		(start 27.18308 -129.159)
		(end 27.11196 -129.23012)
		(width 0.2794)
		(layer "F.Cu")
		(net "MAX31790_U317_PWM_START0")
	)
	(segment
		(start 27.078432 -129.23012)
		(end 26.775918 -129.532634)
		(width 0.2794)
		(layer "F.Cu")
		(net "MAX31790_U317_PWM_START0")
	)
	(segment
		(start 26.775918 -129.532634)
		(end 26.775918 -130.574796)
		(width 0.2794)
		(layer "F.Cu")
		(net "MAX31790_U317_PWM_START0")
	)
	(segment
		(start 27.94 -129.159)
		(end 27.18308 -129.159)
		(width 0.2794)
		(layer "F.Cu")
		(net "MAX31790_U317_PWM_START0")
	)
	(segment
		(start 25.92705 -131.445)
		(end 25.92705 -132.461)
		(width 0.2794)
		(layer "F.Cu")
		(net "MAX31790_U317_PWM_START0")
	)
	(segment
		(start 25.92705 -131.423664)
		(end 25.92705 -131.445)
		(width 0.2794)
		(layer "F.Cu")
		(net "MAX31790_U317_PWM_START0")
	)
	(via
		(at 27.11196 -129.23012)
		(size 0.762)
		(drill 0.381)
		(layers "F.Cu" "B.Cu")
		(net "MAX31790_U317_PWM_START0")
	)
	(segment
		(start 25.21204 -18.146014)
		(end 25.070054 -18.288)
		(width 0.2794)
		(layer "F.Cu")
		(net "FAN_4_PWM_OL")
	)
	(segment
		(start 14.634972 -14.979142)
		(end 14.634972 -14.310868)
		(width 0.2794)
		(layer "F.Cu")
		(net "FAN_4_PWM_OL")
	)
	(segment
		(start 17.78127 -14.986)
		(end 17.305274 -15.461996)
		(width 0.2794)
		(layer "F.Cu")
		(net "FAN_4_PWM_OL")
	)
	(segment
		(start 21.31695 -14.986)
		(end 17.78127 -14.986)
		(width 0.2794)
		(layer "F.Cu")
		(net "FAN_4_PWM_OL")
	)
	(segment
		(start 25.070054 -18.288)
		(end 23.64105 -18.288)
		(width 0.2794)
		(layer "F.Cu")
		(net "FAN_4_PWM_OL")
	)
	(segment
		(start 23.64105 -18.288)
		(end 22.45995 -17.1069)
		(width 0.2794)
		(layer "F.Cu")
		(net "FAN_4_PWM_OL")
	)
	(segment
		(start 22.45995 -16.129)
		(end 21.31695 -14.986)
		(width 0.2794)
		(layer "F.Cu")
		(net "FAN_4_PWM_OL")
	)
	(segment
		(start 17.305274 -15.461996)
		(end 15.117826 -15.461996)
		(width 0.2794)
		(layer "F.Cu")
		(net "FAN_4_PWM_OL")
	)
	(segment
		(start 22.45995 -17.1069)
		(end 22.45995 -16.129)
		(width 0.2794)
		(layer "F.Cu")
		(net "FAN_4_PWM_OL")
	)
	(segment
		(start 15.117826 -15.461996)
		(end 14.634972 -14.979142)
		(width 0.2794)
		(layer "F.Cu")
		(net "FAN_4_PWM_OL")
	)
	(via
		(at 23.64105 -18.288)
		(size 0.762)
		(drill 0.381)
		(layers "F.Cu" "B.Cu")
		(net "FAN_4_PWM_OL")
	)
	(segment
		(start 31.00578 -125.22327)
		(end 31.00578 -125.79096)
		(width 0.2794)
		(layer "F.Cu")
		(net "MAX31790_U317_ADD1")
	)
	(segment
		(start 31.774892 -124.60605)
		(end 32.2961 -124.084842)
		(width 0.2794)
		(layer "F.Cu")
		(net "MAX31790_U317_ADD1")
	)
	(segment
		(start 32.2961 -122.99315)
		(end 31.623 -122.32005)
		(width 0.2794)
		(layer "F.Cu")
		(net "MAX31790_U317_ADD1")
	)
	(segment
		(start 31.09595 -126.008638)
		(end 31.09595 -127.159004)
		(width 0.1016)
		(layer "F.Cu")
		(net "MAX31790_U317_ADD1")
	)
	(segment
		(start 31.623 -124.60605)
		(end 31.774892 -124.60605)
		(width 0.2794)
		(layer "F.Cu")
		(net "MAX31790_U317_ADD1")
	)
	(segment
		(start 31.00578 -125.79096)
		(end 31.09595 -126.008638)
		(width 0.1016)
		(layer "F.Cu")
		(net "MAX31790_U317_ADD1")
	)
	(segment
		(start 32.2961 -124.084842)
		(end 32.2961 -122.99315)
		(width 0.2794)
		(layer "F.Cu")
		(net "MAX31790_U317_ADD1")
	)
	(segment
		(start 31.623 -124.60605)
		(end 31.00578 -125.22327)
		(width 0.2794)
		(layer "F.Cu")
		(net "MAX31790_U317_ADD1")
	)
	(via
		(at 31.00578 -125.79096)
		(size 0.762)
		(drill 0.381)
		(layers "F.Cu" "B.Cu")
		(net "MAX31790_U317_ADD1")
	)
	(segment
		(start 23.934928 -20.515072)
		(end 25.004014 -19.445986)
		(width 0.2794)
		(layer "F.Cu")
		(net "FAN_4_PWM_IL")
	)
	(segment
		(start 15.199868 -19.136868)
		(end 15.985998 -19.922998)
		(width 0.2794)
		(layer "F.Cu")
		(net "FAN_4_PWM_IL")
	)
	(segment
		(start 15.985998 -19.922998)
		(end 17.70634 -19.922998)
		(width 0.2794)
		(layer "F.Cu")
		(net "FAN_4_PWM_IL")
	)
	(segment
		(start 18.298414 -20.515072)
		(end 18.764758 -20.515072)
		(width 0.2794)
		(layer "F.Cu")
		(net "FAN_4_PWM_IL")
	)
	(segment
		(start 14.761972 -19.136868)
		(end 15.199868 -19.136868)
		(width 0.2794)
		(layer "F.Cu")
		(net "FAN_4_PWM_IL")
	)
	(segment
		(start 18.764758 -20.515072)
		(end 23.934928 -20.515072)
		(width 0.2794)
		(layer "F.Cu")
		(net "FAN_4_PWM_IL")
	)
	(segment
		(start 25.004014 -19.445986)
		(end 25.21204 -19.445986)
		(width 0.2794)
		(layer "F.Cu")
		(net "FAN_4_PWM_IL")
	)
	(segment
		(start 17.70634 -19.922998)
		(end 18.298414 -20.515072)
		(width 0.2794)
		(layer "F.Cu")
		(net "FAN_4_PWM_IL")
	)
	(via
		(at 18.764758 -20.515072)
		(size 0.762)
		(drill 0.381)
		(layers "F.Cu" "B.Cu")
		(net "FAN_4_PWM_IL")
	)
	(segment
		(start 13.716 -20.241768)
		(end 13.95095 -20.241768)
		(width 0.2794)
		(layer "F.Cu")
		(net "SMB_FAN4_SCL_R")
	)
	(segment
		(start 8.700008 -16.409924)
		(end 9.884156 -16.409924)
		(width 0.2794)
		(layer "F.Cu")
		(net "SMB_FAN4_SCL_R")
	)
	(segment
		(start 12.238736 -18.764504)
		(end 13.716 -20.241768)
		(width 0.2794)
		(layer "F.Cu")
		(net "SMB_FAN4_SCL_R")
	)
	(segment
		(start 9.884156 -16.409924)
		(end 12.238736 -18.764504)
		(width 0.2794)
		(layer "F.Cu")
		(net "SMB_FAN4_SCL_R")
	)
	(via
		(at 12.238736 -18.764504)
		(size 0.762)
		(drill 0.381)
		(layers "F.Cu" "B.Cu")
		(net "SMB_FAN4_SCL_R")
	)
	(segment
		(start 11.045444 -255.27)
		(end 9.921494 -255.27)
		(width 0.2794)
		(layer "F.Cu")
		(net "P52V_FAN_7_EN")
	)
	(segment
		(start 11.172444 -255.143)
		(end 11.045444 -255.27)
		(width 0.2794)
		(layer "F.Cu")
		(net "P52V_FAN_7_EN")
	)
	(via
		(at 9.921494 -255.27)
		(size 0.762)
		(drill 0.254)
		(layers "F.Cu" "B.Cu")
		(net "P52V_FAN_7_EN")
	)
	(segment
		(start 9.921494 -255.27)
		(end 10.429494 -255.27)
		(width 0.2794)
		(layer "B.Cu")
		(net "P52V_FAN_7_EN")
	)
	(segment
		(start 10.44448 -255.255014)
		(end 11.372088 -255.255014)
		(width 0.2794)
		(layer "B.Cu")
		(net "P52V_FAN_7_EN")
	)
	(segment
		(start 10.429494 -255.27)
		(end 10.44448 -255.255014)
		(width 0.2794)
		(layer "B.Cu")
		(net "P52V_FAN_7_EN")
	)
	(segment
		(start 27.15895 -291.69995)
		(end 25.908 -290.449)
		(width 0.2794)
		(layer "F.Cu")
		(net "FAN_7_PWM")
	)
	(segment
		(start 29.337 -291.69995)
		(end 27.15895 -291.69995)
		(width 0.2794)
		(layer "F.Cu")
		(net "FAN_7_PWM")
	)
	(segment
		(start 14.45895 -134.874)
		(end 14.45895 -135.509)
		(width 0.2794)
		(layer "F.Cu")
		(net "FAN_7_PWM")
	)
	(segment
		(start 22.162262 -283.278072)
		(end 16.314674 -283.278072)
		(width 0.2794)
		(layer "F.Cu")
		(net "FAN_7_PWM")
	)
	(segment
		(start 29.337 -290.50996)
		(end 29.3624 -290.53536)
		(width 0.2794)
		(layer "F.Cu")
		(net "FAN_7_PWM")
	)
	(segment
		(start 29.3624 -291.67455)
		(end 29.337 -291.69995)
		(width 0.2794)
		(layer "F.Cu")
		(net "FAN_7_PWM")
	)
	(segment
		(start 25.908 -287.02381)
		(end 22.162262 -283.278072)
		(width 0.2794)
		(layer "F.Cu")
		(net "FAN_7_PWM")
	)
	(segment
		(start 25.908 -290.449)
		(end 25.908 -287.02381)
		(width 0.2794)
		(layer "F.Cu")
		(net "FAN_7_PWM")
	)
	(segment
		(start 29.3624 -290.53536)
		(end 29.3624 -291.67455)
		(width 0.2794)
		(layer "F.Cu")
		(net "FAN_7_PWM")
	)
	(via
		(at 16.314674 -283.278072)
		(size 0.762)
		(drill 0.254)
		(layers "F.Cu" "B.Cu")
		(net "FAN_7_PWM")
	)
	(via
		(at 14.45895 -135.509)
		(size 0.508)
		(drill 0.254)
		(layers "F.Cu" "B.Cu")
		(net "FAN_7_PWM")
	)
	(segment
		(start 14.19352 -160.99028)
		(end 14.782038 -160.99028)
		(width 0.2286)
		(layer "In2.Cu")
		(net "FAN_7_PWM")
	)
	(segment
		(start 15.010638 -164.918898)
		(end 15.477236 -165.385496)
		(width 0.2286)
		(layer "In2.Cu")
		(net "FAN_7_PWM")
	)
	(segment
		(start 21.336 -253.608078)
		(end 21.336 -278.256746)
		(width 0.2286)
		(layer "In2.Cu")
		(net "FAN_7_PWM")
	)
	(segment
		(start 21.336 -278.256746)
		(end 16.314674 -283.278072)
		(width 0.2286)
		(layer "In2.Cu")
		(net "FAN_7_PWM")
	)
	(segment
		(start 5.826506 -159.395922)
		(end 9.418574 -162.98799)
		(width 0.2286)
		(layer "In2.Cu")
		(net "FAN_7_PWM")
	)
	(segment
		(start 15.010638 -161.21888)
		(end 15.010638 -164.918898)
		(width 0.2286)
		(layer "In2.Cu")
		(net "FAN_7_PWM")
	)
	(segment
		(start 9.418574 -162.98799)
		(end 12.19581 -162.98799)
		(width 0.2286)
		(layer "In2.Cu")
		(net "FAN_7_PWM")
	)
	(segment
		(start 17.538192 -167.390572)
		(end 18.0848 -167.93718)
		(width 0.2286)
		(layer "In2.Cu")
		(net "FAN_7_PWM")
	)
	(segment
		(start 14.45895 -135.509)
		(end 14.351254 -135.509)
		(width 0.2286)
		(layer "In2.Cu")
		(net "FAN_7_PWM")
	)
	(segment
		(start 15.477236 -166.16934)
		(end 16.698468 -167.390572)
		(width 0.2286)
		(layer "In2.Cu")
		(net "FAN_7_PWM")
	)
	(segment
		(start 14.71168 -215.81618)
		(end 14.71168 -246.983758)
		(width 0.2286)
		(layer "In2.Cu")
		(net "FAN_7_PWM")
	)
	(segment
		(start 5.826506 -144.033748)
		(end 5.826506 -159.395922)
		(width 0.2286)
		(layer "In2.Cu")
		(net "FAN_7_PWM")
	)
	(segment
		(start 14.351254 -135.509)
		(end 5.826506 -144.033748)
		(width 0.2286)
		(layer "In2.Cu")
		(net "FAN_7_PWM")
	)
	(segment
		(start 11.0744 -183.437784)
		(end 11.0744 -212.1789)
		(width 0.2286)
		(layer "In2.Cu")
		(net "FAN_7_PWM")
	)
	(segment
		(start 17.2466 -177.265584)
		(end 11.0744 -183.437784)
		(width 0.2286)
		(layer "In2.Cu")
		(net "FAN_7_PWM")
	)
	(segment
		(start 11.0744 -212.1789)
		(end 14.71168 -215.81618)
		(width 0.2286)
		(layer "In2.Cu")
		(net "FAN_7_PWM")
	)
	(segment
		(start 18.0848 -172.0342)
		(end 17.2466 -172.8724)
		(width 0.2286)
		(layer "In2.Cu")
		(net "FAN_7_PWM")
	)
	(segment
		(start 14.782038 -160.99028)
		(end 15.010638 -161.21888)
		(width 0.2286)
		(layer "In2.Cu")
		(net "FAN_7_PWM")
	)
	(segment
		(start 18.0848 -167.93718)
		(end 18.0848 -172.0342)
		(width 0.2286)
		(layer "In2.Cu")
		(net "FAN_7_PWM")
	)
	(segment
		(start 16.698468 -167.390572)
		(end 17.538192 -167.390572)
		(width 0.2286)
		(layer "In2.Cu")
		(net "FAN_7_PWM")
	)
	(segment
		(start 17.2466 -172.8724)
		(end 17.2466 -177.265584)
		(width 0.2286)
		(layer "In2.Cu")
		(net "FAN_7_PWM")
	)
	(segment
		(start 14.71168 -246.983758)
		(end 21.336 -253.608078)
		(width 0.2286)
		(layer "In2.Cu")
		(net "FAN_7_PWM")
	)
	(segment
		(start 12.19581 -162.98799)
		(end 14.19352 -160.99028)
		(width 0.2286)
		(layer "In2.Cu")
		(net "FAN_7_PWM")
	)
	(segment
		(start 15.477236 -165.385496)
		(end 15.477236 -166.16934)
		(width 0.2286)
		(layer "In2.Cu")
		(net "FAN_7_PWM")
	)
	(segment
		(start 24.889968 -11.660632)
		(end 24.889968 -4.350004)
		(width 0.2794)
		(layer "F.Cu")
		(net "SMB_PDBV_FAN_R_SDA")
	)
	(segment
		(start 26.035 -13.49375)
		(end 25.507696 -13.49375)
		(width 0.2794)
		(layer "F.Cu")
		(net "SMB_PDBV_FAN_R_SDA")
	)
	(segment
		(start 25.507696 -13.49375)
		(end 24.5618 -12.547854)
		(width 0.2794)
		(layer "F.Cu")
		(net "SMB_PDBV_FAN_R_SDA")
	)
	(segment
		(start 27.051 -13.49375)
		(end 26.035 -13.49375)
		(width 0.2794)
		(layer "F.Cu")
		(net "SMB_PDBV_FAN_R_SDA")
	)
	(segment
		(start 24.5618 -11.9888)
		(end 24.889968 -11.660632)
		(width 0.2794)
		(layer "F.Cu")
		(net "SMB_PDBV_FAN_R_SDA")
	)
	(segment
		(start 24.5618 -12.547854)
		(end 24.5618 -11.9888)
		(width 0.2794)
		(layer "F.Cu")
		(net "SMB_PDBV_FAN_R_SDA")
	)
	(segment
		(start 17.63395 -302.81245)
		(end 17.9324 -302.514)
		(width 0.2794)
		(layer "F.Cu")
		(net "FAN_7_TACH_OL_R")
	)
	(segment
		(start 17.526 -304.01895)
		(end 16.51 -304.01895)
		(width 0.2794)
		(layer "F.Cu")
		(net "FAN_7_TACH_OL_R")
	)
	(segment
		(start 16.51 -303.315878)
		(end 16.470122 -303.276)
		(width 0.2794)
		(layer "F.Cu")
		(net "FAN_7_TACH_OL_R")
	)
	(segment
		(start 16.51 -304.01895)
		(end 16.51 -303.315878)
		(width 0.2794)
		(layer "F.Cu")
		(net "FAN_7_TACH_OL_R")
	)
	(segment
		(start 17.63395 -303.911)
		(end 17.526 -304.01895)
		(width 0.2794)
		(layer "F.Cu")
		(net "FAN_7_TACH_OL_R")
	)
	(segment
		(start 16.470122 -303.276)
		(end 16.470122 -302.4251)
		(width 0.2794)
		(layer "F.Cu")
		(net "FAN_7_TACH_OL_R")
	)
	(segment
		(start 17.63395 -303.911)
		(end 17.63395 -302.81245)
		(width 0.2794)
		(layer "F.Cu")
		(net "FAN_7_TACH_OL_R")
	)
	(via
		(at 16.470122 -303.276)
		(size 0.508)
		(drill 0.254)
		(layers "F.Cu" "B.Cu")
		(net "FAN_7_TACH_OL_R")
	)
	(segment
		(start 9.236964 -252.73)
		(end 10.287 -252.73)
		(width 0.2794)
		(layer "F.Cu")
		(net "P52V_FAN_6_EN")
	)
	(segment
		(start 9.109964 -252.857)
		(end 9.236964 -252.73)
		(width 0.2794)
		(layer "F.Cu")
		(net "P52V_FAN_6_EN")
	)
	(via
		(at 10.287 -252.73)
		(size 0.762)
		(drill 0.254)
		(layers "F.Cu" "B.Cu")
		(net "P52V_FAN_6_EN")
	)
	(segment
		(start 10.287 -252.73)
		(end 9.626346 -252.73)
		(width 0.2794)
		(layer "B.Cu")
		(net "P52V_FAN_6_EN")
	)
	(segment
		(start 9.626346 -252.73)
		(end 9.61136 -252.744986)
		(width 0.2794)
		(layer "B.Cu")
		(net "P52V_FAN_6_EN")
	)
	(segment
		(start 9.61136 -252.744986)
		(end 8.91032 -252.744986)
		(width 0.2794)
		(layer "B.Cu")
		(net "P52V_FAN_6_EN")
	)
	(segment
		(start 24.000968 -11.292332)
		(end 24.000968 -7.465568)
		(width 0.2794)
		(layer "F.Cu")
		(net "SMB_PDBV_FAN_R_SCL")
	)
	(segment
		(start 24.000968 -7.465568)
		(end 23.619968 -7.084568)
		(width 0.2794)
		(layer "F.Cu")
		(net "SMB_PDBV_FAN_R_SCL")
	)
	(segment
		(start 23.619968 -7.084568)
		(end 23.619968 -4.350004)
		(width 0.2794)
		(layer "F.Cu")
		(net "SMB_PDBV_FAN_R_SCL")
	)
	(segment
		(start 23.241 -13.49375)
		(end 23.241 -12.0523)
		(width 0.2794)
		(layer "F.Cu")
		(net "SMB_PDBV_FAN_R_SCL")
	)
	(segment
		(start 23.241 -13.49375)
		(end 24.384 -13.49375)
		(width 0.2794)
		(layer "F.Cu")
		(net "SMB_PDBV_FAN_R_SCL")
	)
	(segment
		(start 23.241 -12.0523)
		(end 24.000968 -11.292332)
		(width 0.2794)
		(layer "F.Cu")
		(net "SMB_PDBV_FAN_R_SCL")
	)
	(segment
		(start 10.918444 -70.669912)
		(end 10.229596 -70.669912)
		(width 0.2794)
		(layer "F.Cu")
		(net "P52V_FAN_5_EN")
	)
	(segment
		(start 11.045444 -70.542912)
		(end 10.918444 -70.669912)
		(width 0.2794)
		(layer "F.Cu")
		(net "P52V_FAN_5_EN")
	)
	(segment
		(start 10.229596 -70.669912)
		(end 9.749282 -71.150226)
		(width 0.2794)
		(layer "F.Cu")
		(net "P52V_FAN_5_EN")
	)
	(via
		(at 9.749282 -71.150226)
		(size 0.508)
		(drill 0.254)
		(layers "F.Cu" "B.Cu")
		(net "P52V_FAN_5_EN")
	)
	(segment
		(start 9.749282 -71.150226)
		(end 10.229596 -70.669912)
		(width 0.2794)
		(layer "B.Cu")
		(net "P52V_FAN_5_EN")
	)
	(segment
		(start 10.229596 -70.669912)
		(end 10.302494 -70.669912)
		(width 0.2794)
		(layer "B.Cu")
		(net "P52V_FAN_5_EN")
	)
	(segment
		(start 10.31748 -70.654926)
		(end 11.245088 -70.654926)
		(width 0.2794)
		(layer "B.Cu")
		(net "P52V_FAN_5_EN")
	)
	(segment
		(start 10.302494 -70.669912)
		(end 10.31748 -70.654926)
		(width 0.2794)
		(layer "B.Cu")
		(net "P52V_FAN_5_EN")
	)
	(segment
		(start 20.626578 -204.978)
		(end 22.47646 -204.978)
		(width 0.2794)
		(layer "F.Cu")
		(net "FAN_6_PWM")
	)
	(segment
		(start 15.748 -206.629)
		(end 16.51 -205.867)
		(width 0.2794)
		(layer "F.Cu")
		(net "FAN_6_PWM")
	)
	(segment
		(start 20.286472 -205.318106)
		(end 20.626578 -204.978)
		(width 0.2794)
		(layer "F.Cu")
		(net "FAN_6_PWM")
	)
	(segment
		(start 16.51 -205.867)
		(end 18.090642 -205.867)
		(width 0.2794)
		(layer "F.Cu")
		(net "FAN_6_PWM")
	)
	(segment
		(start 18.090642 -205.867)
		(end 18.639536 -205.318106)
		(width 0.2794)
		(layer "F.Cu")
		(net "FAN_6_PWM")
	)
	(segment
		(start 29.083 -198.30796)
		(end 29.1084 -198.33336)
		(width 0.2794)
		(layer "F.Cu")
		(net "FAN_6_PWM")
	)
	(segment
		(start 28.4099 -201.577448)
		(end 28.4099 -199.935846)
		(width 0.2794)
		(layer "F.Cu")
		(net "FAN_6_PWM")
	)
	(segment
		(start 28.847796 -199.49795)
		(end 29.083 -199.49795)
		(width 0.2794)
		(layer "F.Cu")
		(net "FAN_6_PWM")
	)
	(segment
		(start 22.73808 -204.71638)
		(end 24.37892 -204.71638)
		(width 0.2794)
		(layer "F.Cu")
		(net "FAN_6_PWM")
	)
	(segment
		(start 24.37892 -204.71638)
		(end 25.270968 -204.71638)
		(width 0.2794)
		(layer "F.Cu")
		(net "FAN_6_PWM")
	)
	(segment
		(start 14.45895 -129.794)
		(end 14.45895 -130.429)
		(width 0.2794)
		(layer "F.Cu")
		(net "FAN_6_PWM")
	)
	(segment
		(start 22.47646 -204.978)
		(end 22.73808 -204.71638)
		(width 0.2794)
		(layer "F.Cu")
		(net "FAN_6_PWM")
	)
	(segment
		(start 29.1084 -199.47255)
		(end 29.083 -199.49795)
		(width 0.2794)
		(layer "F.Cu")
		(net "FAN_6_PWM")
	)
	(segment
		(start 28.4099 -199.935846)
		(end 28.847796 -199.49795)
		(width 0.2794)
		(layer "F.Cu")
		(net "FAN_6_PWM")
	)
	(segment
		(start 18.639536 -205.318106)
		(end 20.286472 -205.318106)
		(width 0.2794)
		(layer "F.Cu")
		(net "FAN_6_PWM")
	)
	(segment
		(start 25.270968 -204.71638)
		(end 28.4099 -201.577448)
		(width 0.2794)
		(layer "F.Cu")
		(net "FAN_6_PWM")
	)
	(segment
		(start 13.4112 -206.629)
		(end 15.748 -206.629)
		(width 0.2794)
		(layer "F.Cu")
		(net "FAN_6_PWM")
	)
	(segment
		(start 29.1084 -198.33336)
		(end 29.1084 -199.47255)
		(width 0.2794)
		(layer "F.Cu")
		(net "FAN_6_PWM")
	)
	(via
		(at 14.45895 -130.429)
		(size 0.508)
		(drill 0.254)
		(layers "F.Cu" "B.Cu")
		(net "FAN_6_PWM")
	)
	(via
		(at 13.4112 -206.629)
		(size 0.508)
		(drill 0.254)
		(layers "F.Cu" "B.Cu")
		(net "FAN_6_PWM")
	)
	(via
		(at 24.37892 -204.71638)
		(size 0.762)
		(drill 0.381)
		(layers "F.Cu" "B.Cu")
		(net "FAN_6_PWM")
	)
	(segment
		(start 17.375632 -163.165028)
		(end 17.375632 -143.061944)
		(width 0.2286)
		(layer "In2.Cu")
		(net "FAN_6_PWM")
	)
	(segment
		(start 20.287234 -178.696366)
		(end 20.287234 -166.07663)
		(width 0.2286)
		(layer "In2.Cu")
		(net "FAN_6_PWM")
	)
	(segment
		(start 14.738604 -132.386324)
		(end 14.321028 -132.386324)
		(width 0.2286)
		(layer "In2.Cu")
		(net "FAN_6_PWM")
	)
	(segment
		(start 16.07566 -135.93826)
		(end 16.07566 -133.72338)
		(width 0.2286)
		(layer "In2.Cu")
		(net "FAN_6_PWM")
	)
	(segment
		(start 16.313404 -136.176004)
		(end 16.07566 -135.93826)
		(width 0.2286)
		(layer "In2.Cu")
		(net "FAN_6_PWM")
	)
	(segment
		(start 16.313404 -140.497306)
		(end 16.313404 -136.176004)
		(width 0.2286)
		(layer "In2.Cu")
		(net "FAN_6_PWM")
	)
	(segment
		(start 14.321028 -132.386324)
		(end 13.937742 -132.003038)
		(width 0.2286)
		(layer "In2.Cu")
		(net "FAN_6_PWM")
	)
	(segment
		(start 17.375632 -143.061944)
		(end 16.313404 -140.497306)
		(width 0.2286)
		(layer "In2.Cu")
		(net "FAN_6_PWM")
	)
	(segment
		(start 18.35785 -179.3367)
		(end 19.6469 -179.3367)
		(width 0.2286)
		(layer "In2.Cu")
		(net "FAN_6_PWM")
	)
	(segment
		(start 16.07566 -133.72338)
		(end 14.738604 -132.386324)
		(width 0.2286)
		(layer "In2.Cu")
		(net "FAN_6_PWM")
	)
	(segment
		(start 13.4112 -206.629)
		(end 13.4112 -184.28335)
		(width 0.2286)
		(layer "In2.Cu")
		(net "FAN_6_PWM")
	)
	(segment
		(start 20.287234 -166.07663)
		(end 17.375632 -163.165028)
		(width 0.2286)
		(layer "In2.Cu")
		(net "FAN_6_PWM")
	)
	(segment
		(start 13.4112 -184.28335)
		(end 18.35785 -179.3367)
		(width 0.2286)
		(layer "In2.Cu")
		(net "FAN_6_PWM")
	)
	(segment
		(start 13.937742 -130.950208)
		(end 14.45895 -130.429)
		(width 0.2286)
		(layer "In2.Cu")
		(net "FAN_6_PWM")
	)
	(segment
		(start 13.937742 -132.003038)
		(end 13.937742 -130.950208)
		(width 0.2286)
		(layer "In2.Cu")
		(net "FAN_6_PWM")
	)
	(segment
		(start 19.6469 -179.3367)
		(end 20.287234 -178.696366)
		(width 0.2286)
		(layer "In2.Cu")
		(net "FAN_6_PWM")
	)
	(segment
		(start 9.236964 -68.129912)
		(end 9.109964 -68.256912)
		(width 0.2794)
		(layer "F.Cu")
		(net "P52V_FAN_4_EN")
	)
	(segment
		(start 10.633456 -67.471544)
		(end 9.975088 -68.129912)
		(width 0.2794)
		(layer "F.Cu")
		(net "P52V_FAN_4_EN")
	)
	(segment
		(start 9.975088 -68.129912)
		(end 9.236964 -68.129912)
		(width 0.2794)
		(layer "F.Cu")
		(net "P52V_FAN_4_EN")
	)
	(via
		(at 10.633456 -67.471544)
		(size 0.762)
		(drill 0.254)
		(layers "F.Cu" "B.Cu")
		(net "P52V_FAN_4_EN")
	)
	(segment
		(start 10.633456 -67.471544)
		(end 9.975088 -68.129912)
		(width 0.2794)
		(layer "B.Cu")
		(net "P52V_FAN_4_EN")
	)
	(segment
		(start 9.852914 -68.129912)
		(end 9.837928 -68.144898)
		(width 0.2794)
		(layer "B.Cu")
		(net "P52V_FAN_4_EN")
	)
	(segment
		(start 9.837928 -68.144898)
		(end 8.91032 -68.144898)
		(width 0.2794)
		(layer "B.Cu")
		(net "P52V_FAN_4_EN")
	)
	(segment
		(start 9.975088 -68.129912)
		(end 9.852914 -68.129912)
		(width 0.2794)
		(layer "B.Cu")
		(net "P52V_FAN_4_EN")
	)
	(segment
		(start 41.913556 -68.144898)
		(end 41.633902 -68.144898)
		(width 0.2794)
		(layer "F.Cu")
		(net "P52V_FAN_3_EN")
	)
	(segment
		(start 41.633902 -68.144898)
		(end 41.521888 -68.256912)
		(width 0.2794)
		(layer "F.Cu")
		(net "P52V_FAN_3_EN")
	)
	(segment
		(start 41.521888 -68.256912)
		(end 40.527478 -68.256912)
		(width 0.2794)
		(layer "F.Cu")
		(net "P52V_FAN_3_EN")
	)
	(via
		(at 41.913556 -68.144898)
		(size 0.508)
		(drill 0.254)
		(layers "F.Cu" "B.Cu")
		(net "P52V_FAN_3_EN")
	)
	(segment
		(start 41.913556 -68.144898)
		(end 40.327834 -68.144898)
		(width 0.2794)
		(layer "B.Cu")
		(net "P52V_FAN_3_EN")
	)
	(segment
		(start 38.806882 -70.542912)
		(end 38.679882 -70.669912)
		(width 0.2794)
		(layer "F.Cu")
		(net "P52V_FAN_2_EN")
	)
	(segment
		(start 38.679882 -70.669912)
		(end 37.465 -70.669912)
		(width 0.2794)
		(layer "F.Cu")
		(net "P52V_FAN_2_EN")
	)
	(via
		(at 37.465 -70.669912)
		(size 0.508)
		(drill 0.254)
		(layers "F.Cu" "B.Cu")
		(net "P52V_FAN_2_EN")
	)
	(segment
		(start 38.063932 -70.669912)
		(end 38.078918 -70.654926)
		(width 0.2794)
		(layer "B.Cu")
		(net "P52V_FAN_2_EN")
	)
	(segment
		(start 38.078918 -70.654926)
		(end 39.006526 -70.654926)
		(width 0.2794)
		(layer "B.Cu")
		(net "P52V_FAN_2_EN")
	)
	(segment
		(start 37.465 -70.669912)
		(end 38.063932 -70.669912)
		(width 0.2794)
		(layer "B.Cu")
		(net "P52V_FAN_2_EN")
	)
	(segment
		(start 41.8084 -253.656846)
		(end 40.527478 -253.656846)
		(width 0.2794)
		(layer "F.Cu")
		(net "P52V_FAN_1_EN")
	)
	(via
		(at 41.8084 -253.656846)
		(size 0.508)
		(drill 0.254)
		(layers "F.Cu" "B.Cu")
		(net "P52V_FAN_1_EN")
	)
	(segment
		(start 41.696386 -253.544832)
		(end 40.327834 -253.544832)
		(width 0.2794)
		(layer "B.Cu")
		(net "P52V_FAN_1_EN")
	)
	(segment
		(start 41.8084 -253.656846)
		(end 41.696386 -253.544832)
		(width 0.2794)
		(layer "B.Cu")
		(net "P52V_FAN_1_EN")
	)
	(segment
		(start 37.247576 -255.870202)
		(end 37.681154 -255.870202)
		(width 0.2794)
		(layer "F.Cu")
		(net "P52V_FAN_0_EN")
	)
	(segment
		(start 37.681154 -255.870202)
		(end 38.135306 -255.41605)
		(width 0.2794)
		(layer "F.Cu")
		(net "P52V_FAN_0_EN")
	)
	(segment
		(start 38.533832 -255.41605)
		(end 38.806882 -255.143)
		(width 0.2794)
		(layer "F.Cu")
		(net "P52V_FAN_0_EN")
	)
	(segment
		(start 38.135306 -255.41605)
		(end 38.533832 -255.41605)
		(width 0.2794)
		(layer "F.Cu")
		(net "P52V_FAN_0_EN")
	)
	(via
		(at 37.247576 -255.870202)
		(size 0.762)
		(drill 0.254)
		(layers "F.Cu" "B.Cu")
		(net "P52V_FAN_0_EN")
	)
	(segment
		(start 38.257734 -255.255014)
		(end 39.006526 -255.255014)
		(width 0.2794)
		(layer "B.Cu")
		(net "P52V_FAN_0_EN")
	)
	(segment
		(start 37.247576 -255.870202)
		(end 37.642546 -255.870202)
		(width 0.2794)
		(layer "B.Cu")
		(net "P52V_FAN_0_EN")
	)
	(segment
		(start 37.642546 -255.870202)
		(end 38.257734 -255.255014)
		(width 0.2794)
		(layer "B.Cu")
		(net "P52V_FAN_0_EN")
	)
	(segment
		(start 12.8016 -292.608)
		(end 12.5476 -292.862)
		(width 0.2794)
		(layer "F.Cu")
		(net "SMB_FAN7_SCL_R")
	)
	(segment
		(start 12.099544 -293.310056)
		(end 8.700008 -293.310056)
		(width 0.2794)
		(layer "F.Cu")
		(net "SMB_FAN7_SCL_R")
	)
	(segment
		(start 13.95095 -292.608)
		(end 12.8016 -292.608)
		(width 0.2794)
		(layer "F.Cu")
		(net "SMB_FAN7_SCL_R")
	)
	(segment
		(start 12.5476 -292.862)
		(end 12.099544 -293.310056)
		(width 0.2794)
		(layer "F.Cu")
		(net "SMB_FAN7_SCL_R")
	)
	(via
		(at 12.5476 -292.862)
		(size 0.762)
		(drill 0.381)
		(layers "F.Cu" "B.Cu")
		(net "SMB_FAN7_SCL_R")
	)
	(segment
		(start 48.15205 -314.305696)
		(end 48.15205 -315.087)
		(width 0.2794)
		(layer "F.Cu")
		(net "FAN_0_PRESENT")
	)
	(segment
		(start 48.401986 -313.7281)
		(end 48.401986 -314.05576)
		(width 0.2794)
		(layer "F.Cu")
		(net "FAN_0_PRESENT")
	)
	(segment
		(start 43.035982 -256.667)
		(end 43.035982 -257.28295)
		(width 0.2794)
		(layer "F.Cu")
		(net "FAN_0_PRESENT")
	)
	(segment
		(start 48.15205 -315.087)
		(end 48.768 -315.087)
		(width 0.2794)
		(layer "F.Cu")
		(net "FAN_0_PRESENT")
	)
	(segment
		(start 48.401986 -314.05576)
		(end 48.15205 -314.305696)
		(width 0.2794)
		(layer "F.Cu")
		(net "FAN_0_PRESENT")
	)
	(segment
		(start 43.035982 -257.28295)
		(end 43.016932 -257.302)
		(width 0.2794)
		(layer "F.Cu")
		(net "FAN_0_PRESENT")
	)
	(via
		(at 48.768 -315.087)
		(size 0.508)
		(drill 0.254)
		(layers "F.Cu" "B.Cu")
		(net "FAN_0_PRESENT")
	)
	(via
		(at 43.016932 -257.302)
		(size 0.508)
		(drill 0.254)
		(layers "F.Cu" "B.Cu")
		(net "FAN_0_PRESENT")
	)
	(segment
		(start 31.647892 -301.9679)
		(end 26.162 -296.482008)
		(width 0.2794)
		(layer "B.Cu")
		(net "FAN_0_PRESENT")
	)
	(segment
		(start 37.592 -257.302)
		(end 43.016932 -257.302)
		(width 0.2794)
		(layer "B.Cu")
		(net "FAN_0_PRESENT")
	)
	(segment
		(start 43.293792 -257.302)
		(end 43.91787 -256.677922)
		(width 0.2794)
		(layer "B.Cu")
		(net "FAN_0_PRESENT")
	)
	(segment
		(start 27.178 -279.781)
		(end 27.178 -257.683)
		(width 0.2794)
		(layer "B.Cu")
		(net "FAN_0_PRESENT")
	)
	(segment
		(start 26.162 -280.797)
		(end 27.178 -279.781)
		(width 0.2794)
		(layer "B.Cu")
		(net "FAN_0_PRESENT")
	)
	(segment
		(start 28.575 -256.286)
		(end 36.576 -256.286)
		(width 0.2794)
		(layer "B.Cu")
		(net "FAN_0_PRESENT")
	)
	(segment
		(start 27.178 -257.683)
		(end 28.575 -256.286)
		(width 0.2794)
		(layer "B.Cu")
		(net "FAN_0_PRESENT")
	)
	(segment
		(start 37.1729 -301.9679)
		(end 31.647892 -301.9679)
		(width 0.2794)
		(layer "B.Cu")
		(net "FAN_0_PRESENT")
	)
	(segment
		(start 48.768 -313.563)
		(end 37.1729 -301.9679)
		(width 0.2794)
		(layer "B.Cu")
		(net "FAN_0_PRESENT")
	)
	(segment
		(start 26.162 -296.482008)
		(end 26.162 -280.797)
		(width 0.2794)
		(layer "B.Cu")
		(net "FAN_0_PRESENT")
	)
	(segment
		(start 43.016932 -257.302)
		(end 43.293792 -257.302)
		(width 0.2794)
		(layer "B.Cu")
		(net "FAN_0_PRESENT")
	)
	(segment
		(start 36.576 -256.286)
		(end 37.592 -257.302)
		(width 0.2794)
		(layer "B.Cu")
		(net "FAN_0_PRESENT")
	)
	(segment
		(start 48.768 -315.087)
		(end 48.768 -313.563)
		(width 0.2794)
		(layer "B.Cu")
		(net "FAN_0_PRESENT")
	)
	(segment
		(start 11.9634 -200.5838)
		(end 9.9822 -200.5838)
		(width 0.2794)
		(layer "F.Cu")
		(net "SMB_FAN6_SCL_R")
	)
	(segment
		(start 12.496546 -200.5838)
		(end 11.9634 -200.5838)
		(width 0.2794)
		(layer "F.Cu")
		(net "SMB_FAN6_SCL_R")
	)
	(segment
		(start 9.555988 -201.010012)
		(end 8.700008 -201.010012)
		(width 0.2794)
		(layer "F.Cu")
		(net "SMB_FAN6_SCL_R")
	)
	(segment
		(start 12.89939 -200.180956)
		(end 12.496546 -200.5838)
		(width 0.2794)
		(layer "F.Cu")
		(net "SMB_FAN6_SCL_R")
	)
	(segment
		(start 13.95095 -200.180956)
		(end 12.89939 -200.180956)
		(width 0.2794)
		(layer "F.Cu")
		(net "SMB_FAN6_SCL_R")
	)
	(segment
		(start 9.9822 -200.5838)
		(end 9.555988 -201.010012)
		(width 0.2794)
		(layer "F.Cu")
		(net "SMB_FAN6_SCL_R")
	)
	(via
		(at 11.9634 -200.5838)
		(size 0.762)
		(drill 0.381)
		(layers "F.Cu" "B.Cu")
		(net "SMB_FAN6_SCL_R")
	)
	(segment
		(start 16.764 -196.448934)
		(end 16.764 -197.104)
		(width 0.2794)
		(layer "F.Cu")
		(net "FAN_6_TACH_IL_R")
	)
	(segment
		(start 18.288 -197.5104)
		(end 18.1864 -197.612)
		(width 0.2794)
		(layer "F.Cu")
		(net "FAN_6_TACH_IL_R")
	)
	(segment
		(start 16.764 -197.104)
		(end 16.764 -197.59295)
		(width 0.2794)
		(layer "F.Cu")
		(net "FAN_6_TACH_IL_R")
	)
	(segment
		(start 18.0594 -197.739)
		(end 16.91005 -197.739)
		(width 0.2794)
		(layer "F.Cu")
		(net "FAN_6_TACH_IL_R")
	)
	(segment
		(start 18.288 -196.36105)
		(end 18.288 -197.5104)
		(width 0.2794)
		(layer "F.Cu")
		(net "FAN_6_TACH_IL_R")
	)
	(segment
		(start 16.764 -197.59295)
		(end 16.91005 -197.739)
		(width 0.2794)
		(layer "F.Cu")
		(net "FAN_6_TACH_IL_R")
	)
	(segment
		(start 16.470122 -196.155056)
		(end 16.764 -196.448934)
		(width 0.2794)
		(layer "F.Cu")
		(net "FAN_6_TACH_IL_R")
	)
	(segment
		(start 18.1864 -197.612)
		(end 18.0594 -197.739)
		(width 0.2794)
		(layer "F.Cu")
		(net "FAN_6_TACH_IL_R")
	)
	(via
		(at 16.764 -197.104)
		(size 0.508)
		(drill 0.254)
		(layers "F.Cu" "B.Cu")
		(net "FAN_6_TACH_IL_R")
	)
	(zone
		(layer "F.Cu")
		(hatch none 0.5)
		(connect_pads
			(clearance 0)
		)
		(min_thickness 0.25)
		(keepout
			(tracks allowed)
			(vias allowed)
			(pads allowed)
			(copperpour allowed)
			(footprints not_allowed)
		)
		(placement
			(enabled no)
			(sheetname "")
		)
		(fill
			(thermal_gap 0.5)
			(thermal_bridge_width 0.5)
			(island_removal_mode 0)
		)
		(polygon
			(pts
				(xy 2.350008 -123.234958) (xy 13.050012 -123.234958) (xy 13.050012 -100.184966) (xy 2.350008 -100.184966)
			)
		)
	)
	(zone
		(layer "F.Cu")
		(hatch none 0.5)
		(connect_pads
			(clearance 0)
		)
		(min_thickness 0.25)
		(keepout
			(tracks allowed)
			(vias allowed)
			(pads allowed)
			(copperpour allowed)
			(footprints not_allowed)
		)
		(placement
			(enabled no)
			(sheetname "")
		)
		(fill
			(thermal_gap 0.5)
			(thermal_bridge_width 0.5)
			(island_removal_mode 0)
		)
		(polygon
			(pts
				(arc
					(start 13.34135 -145.869406)
					(mid 10.850129 -143.161203)
					(end 8.358632 -145.869406)
				)
				(arc
					(start 9.355328 -157.78607)
					(mid 10.850107 -159.161107)
					(end 12.344654 -157.78607)
				)
			)
		)
	)
	(zone
		(layer "F.Cu")
		(hatch none 0.5)
		(connect_pads
			(clearance 0)
		)
		(min_thickness 0.25)
		(keepout
			(tracks allowed)
			(vias allowed)
			(pads allowed)
			(copperpour allowed)
			(footprints not_allowed)
		)
		(placement
			(enabled no)
			(sheetname "")
		)
		(fill
			(thermal_gap 0.5)
			(thermal_bridge_width 0.5)
			(island_removal_mode 0)
		)
		(polygon
			(pts
				(arc
					(start 29.04998 -326.909938)
					(mid 25.850088 -330.10983)
					(end 22.649942 -326.909938)
				)
				(arc
					(start 22.649942 -326.909938)
					(mid 25.850088 -323.709792)
					(end 29.04998 -326.909938)
				)
			)
		)
	)
	(zone
		(layer "F.Cu")
		(hatch none 0.5)
		(connect_pads
			(clearance 0)
		)
		(min_thickness 0.25)
		(keepout
			(tracks allowed)
			(vias allowed)
			(pads allowed)
			(copperpour allowed)
			(footprints not_allowed)
		)
		(placement
			(enabled no)
			(sheetname "")
		)
		(fill
			(thermal_gap 0.5)
			(thermal_bridge_width 0.5)
			(island_removal_mode 0)
		)
		(polygon
			(pts
				(xy 17.29994 -33.910016) (xy 3.299968 -33.910016) (xy 3.299968 -45.41012) (xy 17.29994 -45.41012)
			)
		)
	)
	(zone
		(layer "F.Cu")
		(hatch none 0.5)
		(connect_pads
			(clearance 0)
		)
		(min_thickness 0.25)
		(keepout
			(tracks not_allowed)
			(vias allowed)
			(pads allowed)
			(copperpour not_allowed)
			(footprints allowed)
		)
		(placement
			(enabled no)
			(sheetname "")
		)
		(fill
			(thermal_gap 0.5)
			(thermal_bridge_width 0.5)
			(island_removal_mode 0)
		)
		(polygon
			(pts
				(arc
					(start 21.34997 -241.910108)
					(mid 25.850088 -246.410226)
					(end 30.349952 -241.910108)
				)
				(arc
					(start 30.349952 -229.909878)
					(mid 25.850088 -225.410014)
					(end 21.34997 -229.909878)
				)
			)
		)
	)
	(zone
		(layer "F.Cu")
		(hatch none 0.5)
		(connect_pads
			(clearance 0)
		)
		(min_thickness 0.25)
		(keepout
			(tracks not_allowed)
			(vias allowed)
			(pads allowed)
			(copperpour not_allowed)
			(footprints allowed)
		)
		(placement
			(enabled no)
			(sheetname "")
		)
		(fill
			(thermal_gap 0.5)
			(thermal_bridge_width 0.5)
			(island_removal_mode 0)
		)
		(polygon
			(pts
				(arc
					(start 29.04998 -326.909938)
					(mid 25.850088 -330.10983)
					(end 22.649942 -326.909938)
				)
				(arc
					(start 22.649942 -326.909938)
					(mid 25.850088 -323.709792)
					(end 29.04998 -326.909938)
				)
			)
		)
	)
	(zone
		(layer "F.Cu")
		(hatch none 0.5)
		(connect_pads
			(clearance 0)
		)
		(min_thickness 0.25)
		(keepout
			(tracks allowed)
			(vias allowed)
			(pads allowed)
			(copperpour allowed)
			(footprints not_allowed)
		)
		(placement
			(enabled no)
			(sheetname "")
		)
		(fill
			(thermal_gap 0.5)
			(thermal_bridge_width 0.5)
			(island_removal_mode 0)
		)
		(polygon
			(pts
				(xy 36.239958 -1.914144)
				(arc
					(start 36.239958 -10.999978)
					(mid 34.215623 -13.192856)
					(end 31.86811 -11.34999)
				)
				(arc
					(start 19.832066 -11.34999)
					(mid 17.484546 -13.192937)
					(end 15.459964 -10.999978)
				)
				(xy 15.459964 -1.914144) (xy 14.545818 -0.999998)
				(arc
					(start 3.999992 -0.999998)
					(mid 1.878676 -1.878676)
					(end 0.999998 -3.999992)
				)
				(arc
					(start 0.999998 -333.000096)
					(mid 1.878676 -335.121412)
					(end 3.999992 -336.00009)
				)
				(arc
					(start 17.269714 -336.00009)
					(mid 25.85018 -314.410229)
					(end 34.430208 -336.00009)
				)
				(arc
					(start 47.69993 -336.00009)
					(mid 49.821246 -335.121412)
					(end 50.699924 -333.000096)
				)
				(arc
					(start 50.699924 -3.999992)
					(mid 49.821246 -1.878676)
					(end 47.69993 -0.999998)
				)
				(xy 37.154104 -0.999998)
			)
		)
	)
	(zone
		(layer "F.Cu")
		(hatch none 0.5)
		(connect_pads
			(clearance 0)
		)
		(min_thickness 0.25)
		(keepout
			(tracks allowed)
			(vias allowed)
			(pads allowed)
			(copperpour allowed)
			(footprints not_allowed)
		)
		(placement
			(enabled no)
			(sheetname "")
		)
		(fill
			(thermal_gap 0.5)
			(thermal_bridge_width 0.5)
			(island_removal_mode 0)
		)
		(polygon
			(pts
				(xy 2.350008 -215.535002) (xy 13.050012 -215.535002) (xy 13.050012 -192.48501) (xy 2.350008 -192.48501)
			)
		)
	)
	(zone
		(layer "F.Cu")
		(hatch none 0.5)
		(connect_pads
			(clearance 0)
		)
		(min_thickness 0.25)
		(keepout
			(tracks allowed)
			(vias allowed)
			(pads allowed)
			(copperpour allowed)
			(footprints not_allowed)
		)
		(placement
			(enabled no)
			(sheetname "")
		)
		(fill
			(thermal_gap 0.5)
			(thermal_bridge_width 0.5)
			(island_removal_mode 0)
		)
		(polygon
			(pts
				(xy 13.050012 -284.785054) (xy 2.350008 -284.785054) (xy 2.350008 -307.835046) (xy 13.050012 -307.835046)
			)
		)
	)
	(zone
		(layer "F.Cu")
		(hatch none 0.5)
		(connect_pads
			(clearance 0)
		)
		(min_thickness 0.25)
		(keepout
			(tracks allowed)
			(vias allowed)
			(pads allowed)
			(copperpour allowed)
			(footprints not_allowed)
		)
		(placement
			(enabled no)
			(sheetname "")
		)
		(fill
			(thermal_gap 0.5)
			(thermal_bridge_width 0.5)
			(island_removal_mode 0)
		)
		(polygon
			(pts
				(xy 33.299908 -230.410004) (xy 47.29988 -230.410004) (xy 47.29988 -217.909902) (xy 33.299908 -217.909902)
			)
		)
	)
	(zone
		(layer "F.Cu")
		(hatch none 0.5)
		(connect_pads
			(clearance 0)
		)
		(min_thickness 0.25)
		(keepout
			(tracks allowed)
			(vias allowed)
			(pads allowed)
			(copperpour allowed)
			(footprints not_allowed)
		)
		(placement
			(enabled no)
			(sheetname "")
		)
		(fill
			(thermal_gap 0.5)
			(thermal_bridge_width 0.5)
			(island_removal_mode 0)
		)
		(polygon
			(pts
				(arc
					(start 17.269714 -336.00009)
					(mid 25.85018 -314.410229)
					(end 34.430208 -336.00009)
				)
			)
		)
	)
	(zone
		(layer "F.Cu")
		(hatch none 0.5)
		(connect_pads
			(clearance 0)
		)
		(min_thickness 0.25)
		(keepout
			(tracks not_allowed)
			(vias allowed)
			(pads allowed)
			(copperpour not_allowed)
			(footprints allowed)
		)
		(placement
			(enabled no)
			(sheetname "")
		)
		(fill
			(thermal_gap 0.5)
			(thermal_bridge_width 0.5)
			(island_removal_mode 0)
		)
		(polygon
			(pts
				(arc
					(start 21.34997 -51.90998)
					(mid 25.850088 -56.410098)
					(end 30.349952 -51.90998)
				)
				(arc
					(start 30.349952 -39.910004)
					(mid 25.850088 -35.41014)
					(end 21.34997 -39.910004)
				)
			)
		)
	)
	(zone
		(layer "F.Cu")
		(hatch none 0.5)
		(connect_pads
			(clearance 0)
		)
		(min_thickness 0.25)
		(keepout
			(tracks allowed)
			(vias allowed)
			(pads allowed)
			(copperpour allowed)
			(footprints not_allowed)
		)
		(placement
			(enabled no)
			(sheetname "")
		)
		(fill
			(thermal_gap 0.5)
			(thermal_bridge_width 0.5)
			(island_removal_mode 0)
		)
		(polygon
			(pts
				(xy 8.299958 -96.609916) (xy 43.299888 -96.609916) (xy 43.299888 -85.110066) (xy 8.299958 -85.110066)
			)
		)
	)
	(zone
		(layer "F.Cu")
		(hatch none 0.5)
		(connect_pads
			(clearance 0)
		)
		(min_thickness 0.25)
		(keepout
			(tracks allowed)
			(vias allowed)
			(pads allowed)
			(copperpour allowed)
			(footprints not_allowed)
		)
		(placement
			(enabled no)
			(sheetname "")
		)
		(fill
			(thermal_gap 0.5)
			(thermal_bridge_width 0.5)
			(island_removal_mode 0)
		)
		(polygon
			(pts
				(xy 38.64991 -123.234958) (xy 49.349914 -123.234958) (xy 49.349914 -100.184966) (xy 38.64991 -100.184966)
			)
		)
	)
	(zone
		(layer "F.Cu")
		(hatch none 0.5)
		(connect_pads
			(clearance 0)
		)
		(min_thickness 0.25)
		(keepout
			(tracks allowed)
			(vias allowed)
			(pads allowed)
			(copperpour allowed)
			(footprints not_allowed)
		)
		(placement
			(enabled no)
			(sheetname "")
		)
		(fill
			(thermal_gap 0.5)
			(thermal_bridge_width 0.5)
			(island_removal_mode 0)
		)
		(polygon
			(pts
				(xy 4.299966 -230.410004) (xy 18.299938 -230.410004) (xy 18.299938 -217.909902) (xy 4.299966 -217.909902)
			)
		)
	)
	(zone
		(layer "F.Cu")
		(hatch none 0.5)
		(connect_pads
			(clearance 0)
		)
		(min_thickness 0.25)
		(keepout
			(tracks allowed)
			(vias allowed)
			(pads allowed)
			(copperpour allowed)
			(footprints not_allowed)
		)
		(placement
			(enabled no)
			(sheetname "")
		)
		(fill
			(thermal_gap 0.5)
			(thermal_bridge_width 0.5)
			(island_removal_mode 0)
		)
		(polygon
			(pts
				(arc
					(start 21.34997 -241.910108)
					(mid 25.850088 -246.410226)
					(end 30.349952 -241.910108)
				)
				(arc
					(start 30.349952 -229.909878)
					(mid 25.850088 -225.410014)
					(end 21.34997 -229.909878)
				)
			)
		)
	)
	(zone
		(layer "F.Cu")
		(hatch none 0.5)
		(connect_pads
			(clearance 0)
		)
		(min_thickness 0.25)
		(keepout
			(tracks not_allowed)
			(vias allowed)
			(pads allowed)
			(copperpour not_allowed)
			(footprints allowed)
		)
		(placement
			(enabled no)
			(sheetname "")
		)
		(fill
			(thermal_gap 0.5)
			(thermal_bridge_width 0.5)
			(island_removal_mode 0)
		)
		(polygon
			(pts
				(arc
					(start 6.35 -157.661102)
					(mid 10.850118 -162.16122)
					(end 15.349982 -157.661102)
				)
				(arc
					(start 15.349982 -145.661126)
					(mid 10.850118 -141.161262)
					(end 6.35 -145.661126)
				)
			)
		)
	)
	(zone
		(layer "F.Cu")
		(hatch none 0.5)
		(connect_pads
			(clearance 0)
		)
		(min_thickness 0.25)
		(keepout
			(tracks allowed)
			(vias allowed)
			(pads allowed)
			(copperpour allowed)
			(footprints not_allowed)
		)
		(placement
			(enabled no)
			(sheetname "")
		)
		(fill
			(thermal_gap 0.5)
			(thermal_bridge_width 0.5)
			(island_removal_mode 0)
		)
		(polygon
			(pts
				(arc
					(start 6.35 -157.661102)
					(mid 10.850118 -162.16122)
					(end 15.349982 -157.661102)
				)
				(arc
					(start 15.349982 -145.661126)
					(mid 10.850118 -141.161262)
					(end 6.35 -145.661126)
				)
			)
		)
	)
	(zone
		(layer "F.Cu")
		(hatch none 0.5)
		(connect_pads
			(clearance 0)
		)
		(min_thickness 0.25)
		(keepout
			(tracks allowed)
			(vias allowed)
			(pads allowed)
			(copperpour allowed)
			(footprints not_allowed)
		)
		(placement
			(enabled no)
			(sheetname "")
		)
		(fill
			(thermal_gap 0.5)
			(thermal_bridge_width 0.5)
			(island_removal_mode 0)
		)
		(polygon
			(pts
				(arc
					(start 24.355044 -52.033932)
					(mid 25.850078 -53.410154)
					(end 27.344878 -52.033932)
				)
				(arc
					(start 28.349956 -39.910004)
					(mid 25.850088 -37.410136)
					(end 23.349966 -39.910004)
				)
			)
		)
	)
	(zone
		(layer "F.Cu")
		(hatch none 0.5)
		(connect_pads
			(clearance 0)
		)
		(min_thickness 0.25)
		(keepout
			(tracks allowed)
			(vias allowed)
			(pads allowed)
			(copperpour allowed)
			(footprints not_allowed)
		)
		(placement
			(enabled no)
			(sheetname "")
		)
		(fill
			(thermal_gap 0.5)
			(thermal_bridge_width 0.5)
			(island_removal_mode 0)
		)
		(polygon
			(pts
				(xy 38.64991 -215.535002) (xy 49.349914 -215.535002) (xy 49.349914 -192.48501) (xy 38.64991 -192.48501)
			)
		)
	)
	(zone
		(layer "F.Cu")
		(hatch none 0.5)
		(connect_pads
			(clearance 0)
		)
		(min_thickness 0.25)
		(keepout
			(tracks allowed)
			(vias allowed)
			(pads allowed)
			(copperpour allowed)
			(footprints not_allowed)
		)
		(placement
			(enabled no)
			(sheetname "")
		)
		(fill
			(thermal_gap 0.5)
			(thermal_bridge_width 0.5)
			(island_removal_mode 0)
		)
		(polygon
			(pts
				(xy 38.64991 -307.835046) (xy 49.349914 -307.835046) (xy 49.349914 -284.785054) (xy 38.64991 -284.785054)
			)
		)
	)
	(zone
		(layer "F.Cu")
		(hatch none 0.5)
		(connect_pads
			(clearance 0)
		)
		(min_thickness 0.25)
		(keepout
			(tracks allowed)
			(vias allowed)
			(pads allowed)
			(copperpour allowed)
			(footprints not_allowed)
		)
		(placement
			(enabled no)
			(sheetname "")
		)
		(fill
			(thermal_gap 0.5)
			(thermal_bridge_width 0.5)
			(island_removal_mode 0)
		)
		(polygon
			(pts
				(xy 38.64991 -30.934914) (xy 49.349914 -30.934914) (xy 49.349914 -7.884922) (xy 38.64991 -7.884922)
			)
		)
	)
	(zone
		(layer "F.Cu")
		(hatch none 0.5)
		(connect_pads
			(clearance 0)
		)
		(min_thickness 0.25)
		(keepout
			(tracks allowed)
			(vias allowed)
			(pads allowed)
			(copperpour allowed)
			(footprints not_allowed)
		)
		(placement
			(enabled no)
			(sheetname "")
		)
		(fill
			(thermal_gap 0.5)
			(thermal_bridge_width 0.5)
			(island_removal_mode 0)
		)
		(polygon
			(pts
				(xy 2.350008 -30.934914) (xy 13.050012 -30.934914) (xy 13.050012 -7.884922) (xy 2.350008 -7.884922)
			)
		)
	)
	(zone
		(layer "F.Cu")
		(hatch none 0.5)
		(connect_pads
			(clearance 0)
		)
		(min_thickness 0.25)
		(keepout
			(tracks allowed)
			(vias allowed)
			(pads allowed)
			(copperpour allowed)
			(footprints not_allowed)
		)
		(placement
			(enabled no)
			(sheetname "")
		)
		(fill
			(thermal_gap 0.5)
			(thermal_bridge_width 0.5)
			(island_removal_mode 0)
		)
		(polygon
			(pts
				(xy 8.299958 -281.409902) (xy 43.299888 -281.409902) (xy 43.299888 -269.910052) (xy 8.299958 -269.910052)
			)
		)
	)
	(zone
		(layer "F.Cu")
		(hatch none 0.5)
		(connect_pads
			(clearance 0)
		)
		(min_thickness 0.25)
		(keepout
			(tracks not_allowed)
			(vias allowed)
			(pads allowed)
			(copperpour not_allowed)
			(footprints allowed)
		)
		(placement
			(enabled no)
			(sheetname "")
		)
		(fill
			(thermal_gap 0.5)
			(thermal_bridge_width 0.5)
			(island_removal_mode 0)
		)
		(polygon
			(pts
				(arc
					(start 36.34994 -157.661102)
					(mid 40.850058 -162.16122)
					(end 45.349922 -157.661102)
				)
				(arc
					(start 45.349922 -145.661126)
					(mid 40.850058 -141.161262)
					(end 36.34994 -145.661126)
				)
			)
		)
	)
	(zone
		(layer "F.Cu")
		(hatch none 0.5)
		(connect_pads
			(clearance 0)
		)
		(min_thickness 0.25)
		(keepout
			(tracks allowed)
			(vias allowed)
			(pads allowed)
			(copperpour allowed)
			(footprints not_allowed)
		)
		(placement
			(enabled no)
			(sheetname "")
		)
		(fill
			(thermal_gap 0.5)
			(thermal_bridge_width 0.5)
			(island_removal_mode 0)
		)
		(polygon
			(pts
				(arc
					(start 24.355044 -242.033806)
					(mid 25.850078 -243.410028)
					(end 27.344878 -242.033806)
				)
				(arc
					(start 28.349956 -229.909878)
					(mid 25.850088 -227.41001)
					(end 23.349966 -229.909878)
				)
			)
		)
	)
	(zone
		(layer "F.Cu")
		(hatch none 0.5)
		(connect_pads
			(clearance 0)
		)
		(min_thickness 0.25)
		(keepout
			(tracks allowed)
			(vias allowed)
			(pads allowed)
			(copperpour allowed)
			(footprints not_allowed)
		)
		(placement
			(enabled no)
			(sheetname "")
		)
		(fill
			(thermal_gap 0.5)
			(thermal_bridge_width 0.5)
			(island_removal_mode 0)
		)
		(polygon
			(pts
				(arc
					(start 36.34994 -157.661102)
					(mid 40.850058 -162.16122)
					(end 45.349922 -157.661102)
				)
				(arc
					(start 45.349922 -145.661126)
					(mid 40.850058 -141.161262)
					(end 36.34994 -145.661126)
				)
			)
		)
	)
	(zone
		(layer "F.Cu")
		(hatch none 0.5)
		(connect_pads
			(clearance 0)
		)
		(min_thickness 0.25)
		(keepout
			(tracks allowed)
			(vias allowed)
			(pads allowed)
			(copperpour allowed)
			(footprints not_allowed)
		)
		(placement
			(enabled no)
			(sheetname "")
		)
		(fill
			(thermal_gap 0.5)
			(thermal_bridge_width 0.5)
			(island_removal_mode 0)
		)
		(polygon
			(pts
				(arc
					(start 21.34997 -51.90998)
					(mid 25.850088 -56.410098)
					(end 30.349952 -51.90998)
				)
				(arc
					(start 30.349952 -39.910004)
					(mid 25.850088 -35.41014)
					(end 21.34997 -39.910004)
				)
			)
		)
	)
	(zone
		(layer "F.Cu")
		(hatch none 0.5)
		(connect_pads
			(clearance 0)
		)
		(min_thickness 0.25)
		(keepout
			(tracks allowed)
			(vias allowed)
			(pads allowed)
			(copperpour allowed)
			(footprints not_allowed)
		)
		(placement
			(enabled no)
			(sheetname "")
		)
		(fill
			(thermal_gap 0.5)
			(thermal_bridge_width 0.5)
			(island_removal_mode 0)
		)
		(polygon
			(pts
				(xy 48.299878 -33.910016) (xy 34.299906 -33.910016) (xy 34.299906 -45.41012) (xy 48.299878 -45.41012)
			)
		)
	)
	(zone
		(layer "F.Cu")
		(hatch none 0.5)
		(connect_pads
			(clearance 0)
		)
		(min_thickness 0.25)
		(keepout
			(tracks not_allowed)
			(vias allowed)
			(pads allowed)
			(copperpour not_allowed)
			(footprints allowed)
		)
		(placement
			(enabled no)
			(sheetname "")
		)
		(fill
			(thermal_gap 0.5)
			(thermal_bridge_width 0.5)
			(island_removal_mode 0)
		)
		(polygon
			(pts
				(arc
					(start 20.770088 -326.909938)
					(mid 25.850088 -321.829938)
					(end 30.930088 -326.909938)
				)
				(arc
					(start 30.930088 -326.909938)
					(mid 25.850088 -331.989938)
					(end 20.770088 -326.909938)
				)
			)
		)
	)
	(zone
		(layer "F.Cu")
		(hatch none 0.5)
		(connect_pads
			(clearance 0)
		)
		(min_thickness 0.25)
		(keepout
			(tracks allowed)
			(vias allowed)
			(pads allowed)
			(copperpour allowed)
			(footprints not_allowed)
		)
		(placement
			(enabled no)
			(sheetname "")
		)
		(fill
			(thermal_gap 0.5)
			(thermal_bridge_width 0.5)
			(island_removal_mode 0)
		)
		(polygon
			(pts
				(xy 38.64991 -192.48501) (xy 38.64991 -215.535002) (xy 49.349914 -215.535002) (xy 49.349914 -192.48501)
			)
		)
	)
	(zone
		(layers "F.Cu" "B.Cu")
		(hatch none 0.5)
		(connect_pads
			(clearance 0)
		)
		(min_thickness 0.25)
		(keepout
			(tracks allowed)
			(vias allowed)
			(pads allowed)
			(copperpour allowed)
			(footprints not_allowed)
		)
		(placement
			(enabled no)
			(sheetname "")
		)
		(fill yes
			(thermal_gap 0.5)
			(thermal_bridge_width 0.5)
			(island_removal_mode 0)
		)
		(polygon
			(pts
				(xy 49.349914 -284.785054) (xy 38.64991 -284.785054) (xy 38.64991 -307.835046) (xy 49.349914 -307.835046)
			)
		)
	)
	(zone
		(layers "F.Cu" "B.Cu")
		(hatch none 0.5)
		(connect_pads
			(clearance 0)
		)
		(min_thickness 0.25)
		(keepout
			(tracks allowed)
			(vias allowed)
			(pads allowed)
			(copperpour allowed)
			(footprints not_allowed)
		)
		(placement
			(enabled no)
			(sheetname "")
		)
		(fill yes
			(thermal_gap 0.5)
			(thermal_bridge_width 0.5)
			(island_removal_mode 0)
		)
		(polygon
			(pts
				(xy 49.349914 -100.184966) (xy 38.64991 -100.184966) (xy 38.64991 -123.234958) (xy 49.349914 -123.234958)
			)
		)
	)
	(zone
		(layers "F.Cu" "B.Cu")
		(hatch none 0.5)
		(connect_pads
			(clearance 0)
		)
		(min_thickness 0.25)
		(keepout
			(tracks allowed)
			(vias allowed)
			(pads allowed)
			(copperpour allowed)
			(footprints not_allowed)
		)
		(placement
			(enabled no)
			(sheetname "")
		)
		(fill yes
			(thermal_gap 0.5)
			(thermal_bridge_width 0.5)
			(island_removal_mode 0)
		)
		(polygon
			(pts
				(xy 49.349914 -7.884922) (xy 38.64991 -7.884922) (xy 38.64991 -30.934914) (xy 49.349914 -30.934914)
			)
		)
	)
	(zone
		(layers "F.Cu" "B.Cu")
		(hatch none 0.5)
		(connect_pads
			(clearance 0)
		)
		(min_thickness 0.25)
		(keepout
			(tracks allowed)
			(vias allowed)
			(pads allowed)
			(copperpour allowed)
			(footprints not_allowed)
		)
		(placement
			(enabled no)
			(sheetname "")
		)
		(fill yes
			(thermal_gap 0.5)
			(thermal_bridge_width 0.5)
			(island_removal_mode 0)
		)
		(polygon
			(pts
				(xy 13.050012 -307.835046) (xy 13.050012 -284.785054) (xy 2.350008 -284.785054) (xy 2.350008 -307.835046)
			)
		)
	)
	(zone
		(layers "F.Cu" "B.Cu")
		(hatch none 0.5)
		(connect_pads
			(clearance 0)
		)
		(min_thickness 0.25)
		(keepout
			(tracks allowed)
			(vias allowed)
			(pads allowed)
			(copperpour allowed)
			(footprints not_allowed)
		)
		(placement
			(enabled no)
			(sheetname "")
		)
		(fill yes
			(thermal_gap 0.5)
			(thermal_bridge_width 0.5)
			(island_removal_mode 0)
		)
		(polygon
			(pts
				(xy 13.050012 -123.234958) (xy 13.050012 -100.184966) (xy 2.350008 -100.184966) (xy 2.350008 -123.234958)
			)
		)
	)
	(zone
		(layers "F.Cu" "B.Cu")
		(hatch none 0.5)
		(connect_pads
			(clearance 0)
		)
		(min_thickness 0.25)
		(keepout
			(tracks allowed)
			(vias allowed)
			(pads allowed)
			(copperpour allowed)
			(footprints not_allowed)
		)
		(placement
			(enabled no)
			(sheetname "")
		)
		(fill yes
			(thermal_gap 0.5)
			(thermal_bridge_width 0.5)
			(island_removal_mode 0)
		)
		(polygon
			(pts
				(arc
					(start 39.355268 -157.78607)
					(mid 40.850058 -159.161107)
					(end 42.344848 -157.78607)
				)
				(arc
					(start 43.34129 -145.869406)
					(mid 40.850058 -143.161203)
					(end 38.358826 -145.869406)
				)
			)
		)
	)
	(zone
		(layers "F.Cu" "B.Cu")
		(hatch none 0.5)
		(connect_pads
			(clearance 0)
		)
		(min_thickness 0.25)
		(keepout
			(tracks allowed)
			(vias allowed)
			(pads allowed)
			(copperpour allowed)
			(footprints not_allowed)
		)
		(placement
			(enabled no)
			(sheetname "")
		)
		(fill yes
			(thermal_gap 0.5)
			(thermal_bridge_width 0.5)
			(island_removal_mode 0)
		)
		(polygon
			(pts
				(xy 13.050012 -215.535002) (xy 13.050012 -192.48501) (xy 2.350008 -192.48501) (xy 2.350008 -215.535002)
			)
		)
	)
	(zone
		(layers "F.Cu" "B.Cu")
		(hatch none 0.5)
		(connect_pads
			(clearance 0)
		)
		(min_thickness 0.25)
		(keepout
			(tracks allowed)
			(vias allowed)
			(pads allowed)
			(copperpour allowed)
			(footprints not_allowed)
		)
		(placement
			(enabled no)
			(sheetname "")
		)
		(fill yes
			(thermal_gap 0.5)
			(thermal_bridge_width 0.5)
			(island_removal_mode 0)
		)
		(polygon
			(pts
				(xy 13.050012 -7.884922) (xy 2.350008 -7.884922) (xy 2.350008 -30.934914) (xy 13.050012 -30.934914)
			)
		)
	)
	(zone
		(layers "F.Cu" "B.Cu" "In1.Cu" "In2.Cu" "In3.Cu" "In4.Cu")
		(name "Package Keepin")
		(hatch none 0.5)
		(connect_pads
			(clearance 0)
		)
		(min_thickness 0.25)
		(keepout
			(tracks allowed)
			(vias allowed)
			(pads allowed)
			(copperpour allowed)
			(footprints allowed)
		)
		(placement
			(enabled no)
			(sheetname "")
		)
		(fill
			(thermal_gap 0.5)
			(thermal_bridge_width 0.5)
			(island_removal_mode 0)
		)
		(polygon
			(pts
				(arc
					(start 50.683922 -3.999992)
					(mid 49.809931 -1.889991)
					(end 47.69993 -1.016)
				)
				(xy 37.160708 -1.016) (xy 36.25596 -1.920748)
				(arc
					(start 36.25596 -10.999978)
					(mid 34.040064 -13.215874)
					(end 31.823914 -10.999978)
				)
				(xy 31.823914 -2.270506) (xy 30.91942 -1.366012) (xy 29.390594 -1.366012) (xy 28.4861 -2.270506)
				(arc
					(start 28.4861 -10.999978)
					(mid 27.120088 -12.36599)
					(end 25.754076 -10.999978)
				)
				(xy 25.754076 -2.27076) (xy 24.849328 -1.366012) (xy 20.780502 -1.366012) (xy 19.876008 -2.270506)
				(arc
					(start 19.876008 -10.999978)
					(mid 17.660112 -13.215874)
					(end 15.443962 -10.999978)
				)
				(xy 15.443962 -1.920748) (xy 14.539214 -1.016)
				(arc
					(start 3.999992 -1.016)
					(mid 1.889991 -1.889991)
					(end 1.016 -3.999992)
				)
				(xy 1.016 -264.024364) (xy -2.623566 -264.024364) (xy -3.15468 -263.49325) (xy -3.15468 -207.50657)
				(xy -3.726688 -206.934562) (xy -5.611876 -205.049374) (xy -16.597376 -205.049374) (xy -18.75917 -207.211168)
				(xy -18.75917 -299.647356) (xy -17.974564 -300.431962) (xy -17.11579 -300.431962) (xy -4.279646 -300.431962)
				(xy -3.582162 -299.734478) (xy -3.582162 -297.264582) (xy -3.582162 -265.106404) (xy -2.592832 -264.117074)
				(xy 1.016 -264.117074)
				(arc
					(start 1.016 -333.000096)
					(mid 1.889991 -335.110097)
					(end 3.999992 -335.984088)
				)
				(arc
					(start 47.69993 -335.984088)
					(mid 49.809931 -335.110097)
					(end 50.683922 -333.000096)
				)
			)
		)
	)
	(zone
		(layers "F.Cu" "B.Cu" "In1.Cu" "In2.Cu" "In3.Cu" "In4.Cu")
		(name "Route Keepin")
		(hatch none 0.5)
		(connect_pads
			(clearance 0)
		)
		(min_thickness 0.25)
		(keepout
			(tracks allowed)
			(vias allowed)
			(pads allowed)
			(copperpour allowed)
			(footprints allowed)
		)
		(placement
			(enabled no)
			(sheetname "")
		)
		(fill
			(thermal_gap 0.5)
			(thermal_bridge_width 0.5)
			(island_removal_mode 0)
		)
		(polygon
			(pts
				(arc
					(start 47.69993 -336.492088)
					(mid 50.169141 -335.469307)
					(end 51.191922 -333.000096)
				)
				(arc
					(start 51.191922 -3.999992)
					(mid 50.169141 -1.530781)
					(end 47.69993 -0.508)
				)
				(xy 36.950396 -0.508) (xy 35.74796 -1.710436)
				(arc
					(start 35.74796 -10.999978)
					(mid 34.040064 -12.707874)
					(end 32.331914 -10.999978)
				)
				(xy 32.331914 -2.060194) (xy 31.129732 -0.858012) (xy 29.180282 -0.858012) (xy 27.9781 -2.060194)
				(arc
					(start 27.9781 -10.999978)
					(mid 27.120088 -11.85799)
					(end 26.262076 -10.999978)
				)
				(xy 26.262076 -2.060448) (xy 25.05964 -0.858012) (xy 20.57019 -0.858012) (xy 19.368008 -2.060194)
				(arc
					(start 19.368008 -10.999978)
					(mid 17.660112 -12.707874)
					(end 15.951962 -10.999978)
				)
				(xy 15.951962 -1.710436) (xy 14.749526 -0.508)
				(arc
					(start 3.999992 -0.508)
					(mid 1.530781 -1.530781)
					(end 0.508 -3.999992)
				)
				(xy 0.508 -263.976358) (xy -1.994916 -263.976358) (xy -2.242312 -263.728962) (xy -2.242312 -153.803858)
				(xy -3.463798 -152.582372) (xy -18.310606 -152.582372) (xy -19.640042 -153.911808) (xy -19.640042 -335.432146)
				(xy -18.332196 -336.739992) (xy -3.375914 -336.739992) (xy -2.149856 -335.513934) (xy -2.149856 -264.426192)
				(xy -1.974596 -264.250932) (xy 0.508 -264.250932)
				(arc
					(start 0.508 -333.000096)
					(mid 1.530781 -335.469307)
					(end 3.999992 -336.492088)
				)
			)
		)
	)
	(zone
		(layer "B.Cu")
		(hatch none 0.5)
		(connect_pads
			(clearance 0)
		)
		(min_thickness 0.25)
		(keepout
			(tracks allowed)
			(vias allowed)
			(pads allowed)
			(copperpour allowed)
			(footprints not_allowed)
		)
		(placement
			(enabled no)
			(sheetname "")
		)
		(fill
			(thermal_gap 0.5)
			(thermal_bridge_width 0.5)
			(island_removal_mode 0)
		)
		(polygon
			(pts
				(xy 52.349908 -97.184972) (xy 35.649916 -97.184972) (xy 35.649916 -126.234952) (xy 52.349908 -126.234952)
			)
		)
	)
	(zone
		(layer "B.Cu")
		(hatch none 0.5)
		(connect_pads
			(clearance 0)
		)
		(min_thickness 0.25)
		(keepout
			(tracks allowed)
			(vias allowed)
			(pads allowed)
			(copperpour allowed)
			(footprints not_allowed)
		)
		(placement
			(enabled no)
			(sheetname "")
		)
		(fill
			(thermal_gap 0.5)
			(thermal_bridge_width 0.5)
			(island_removal_mode 0)
		)
		(polygon
			(pts
				(arc
					(start 18.349976 -51.90998)
					(mid 25.850088 -59.410092)
					(end 33.349946 -51.90998)
				)
				(arc
					(start 33.349946 -39.910004)
					(mid 25.850088 -32.410146)
					(end 18.349976 -39.910004)
				)
			)
		)
	)
	(zone
		(layer "B.Cu")
		(hatch none 0.5)
		(connect_pads
			(clearance 0)
		)
		(min_thickness 0.25)
		(keepout
			(tracks allowed)
			(vias allowed)
			(pads allowed)
			(copperpour allowed)
			(footprints not_allowed)
		)
		(placement
			(enabled no)
			(sheetname "")
		)
		(fill
			(thermal_gap 0.5)
			(thermal_bridge_width 0.5)
			(island_removal_mode 0)
		)
		(polygon
			(pts
				(xy 49.349914 -192.48501) (xy 38.64991 -192.48501) (xy 38.64991 -215.535002) (xy 49.349914 -215.535002)
			)
		)
	)
	(zone
		(layer "B.Cu")
		(hatch none 0.5)
		(connect_pads
			(clearance 0)
		)
		(min_thickness 0.25)
		(keepout
			(tracks allowed)
			(vias allowed)
			(pads allowed)
			(copperpour allowed)
			(footprints not_allowed)
		)
		(placement
			(enabled no)
			(sheetname "")
		)
		(fill
			(thermal_gap 0.5)
			(thermal_bridge_width 0.5)
			(island_removal_mode 0)
		)
		(polygon
			(pts
				(arc
					(start 0.999998 -333.000604)
					(mid 1.899613 -335.142652)
					(end 4.05892 -336.00009)
				)
				(arc
					(start 47.69993 -336.00009)
					(mid 49.821246 -335.121412)
					(end 50.699924 -333.000096)
				)
				(xy 50.699924 -310.83504) (xy 35.649916 -310.83504) (xy 35.649916 -281.78506) (xy 50.699924 -281.78506)
				(xy 50.699924 -261.510018) (xy 0.999998 -261.510018) (xy 0.999998 -281.78506) (xy 16.050006 -281.78506)
				(xy 16.050006 -310.83504) (xy 0.999998 -310.83504)
			)
		)
	)
	(zone
		(layer "B.Cu")
		(hatch none 0.5)
		(connect_pads
			(clearance 0)
		)
		(min_thickness 0.25)
		(keepout
			(tracks allowed)
			(vias allowed)
			(pads allowed)
			(copperpour allowed)
			(footprints not_allowed)
		)
		(placement
			(enabled no)
			(sheetname "")
		)
		(fill
			(thermal_gap 0.5)
			(thermal_bridge_width 0.5)
			(island_removal_mode 0)
		)
		(polygon
			(pts
				(xy -0.649986 -97.184972) (xy -0.649986 -126.234952) (xy 16.050006 -126.234952) (xy 16.050006 -97.184972)
			)
		)
	)
	(zone
		(layer "B.Cu")
		(hatch none 0.5)
		(connect_pads
			(clearance 0)
		)
		(min_thickness 0.25)
		(keepout
			(tracks allowed)
			(vias allowed)
			(pads allowed)
			(copperpour allowed)
			(footprints not_allowed)
		)
		(placement
			(enabled no)
			(sheetname "")
		)
		(fill
			(thermal_gap 0.5)
			(thermal_bridge_width 0.5)
			(island_removal_mode 0)
		)
		(polygon
			(pts
				(arc
					(start 18.349976 -145.661126)
					(mid 10.850118 -138.161268)
					(end 3.350006 -145.661126)
				)
				(arc
					(start 3.350006 -157.661102)
					(mid 10.850118 -165.161214)
					(end 18.349976 -157.661102)
				)
			)
		)
	)
	(zone
		(layer "B.Cu")
		(hatch none 0.5)
		(connect_pads
			(clearance 0)
		)
		(min_thickness 0.25)
		(keepout
			(tracks allowed)
			(vias allowed)
			(pads allowed)
			(copperpour allowed)
			(footprints not_allowed)
		)
		(placement
			(enabled no)
			(sheetname "")
		)
		(fill
			(thermal_gap 0.5)
			(thermal_bridge_width 0.5)
			(island_removal_mode 0)
		)
		(polygon
			(pts
				(xy 52.349908 -281.78506) (xy 35.649916 -281.78506) (xy 35.649916 -310.83504) (xy 52.349908 -310.83504)
			)
		)
	)
	(zone
		(layer "B.Cu")
		(hatch none 0.5)
		(connect_pads
			(clearance 0)
		)
		(min_thickness 0.25)
		(keepout
			(tracks allowed)
			(vias allowed)
			(pads allowed)
			(copperpour allowed)
			(footprints not_allowed)
		)
		(placement
			(enabled no)
			(sheetname "")
		)
		(fill
			(thermal_gap 0.5)
			(thermal_bridge_width 0.5)
			(island_removal_mode 0)
		)
		(polygon
			(pts
				(xy -0.649986 -281.78506) (xy -0.649986 -310.83504) (xy 16.050006 -310.83504) (xy 16.050006 -281.78506)
			)
		)
	)
	(zone
		(layer "B.Cu")
		(hatch none 0.5)
		(connect_pads
			(clearance 0)
		)
		(min_thickness 0.25)
		(keepout
			(tracks allowed)
			(vias allowed)
			(pads allowed)
			(copperpour allowed)
			(footprints not_allowed)
		)
		(placement
			(enabled no)
			(sheetname "")
		)
		(fill
			(thermal_gap 0.5)
			(thermal_bridge_width 0.5)
			(island_removal_mode 0)
		)
		(polygon
			(pts
				(xy -0.649986 -189.485016) (xy -0.649986 -218.534996) (xy 16.050006 -218.534996) (xy 16.050006 -189.485016)
			)
		)
	)
	(zone
		(layer "B.Cu")
		(hatch none 0.5)
		(connect_pads
			(clearance 0)
		)
		(min_thickness 0.25)
		(keepout
			(tracks allowed)
			(vias allowed)
			(pads allowed)
			(copperpour allowed)
			(footprints not_allowed)
		)
		(placement
			(enabled no)
			(sheetname "")
		)
		(fill
			(thermal_gap 0.5)
			(thermal_bridge_width 0.5)
			(island_removal_mode 0)
		)
		(polygon
			(pts
				(arc
					(start 33.429956 -304.909982)
					(mid 25.850088 -297.330114)
					(end 18.269966 -304.909982)
				)
				(arc
					(start 18.269966 -326.909938)
					(mid 25.850088 -334.49006)
					(end 33.429956 -326.909938)
				)
			)
		)
	)
	(zone
		(layer "B.Cu")
		(hatch none 0.5)
		(connect_pads
			(clearance 0)
		)
		(min_thickness 0.25)
		(keepout
			(tracks not_allowed)
			(vias allowed)
			(pads allowed)
			(copperpour not_allowed)
			(footprints allowed)
		)
		(placement
			(enabled no)
			(sheetname "")
		)
		(fill
			(thermal_gap 0.5)
			(thermal_bridge_width 0.5)
			(island_removal_mode 0)
		)
		(polygon
			(pts
				(arc
					(start 30.349952 -39.910004)
					(mid 25.850088 -35.41014)
					(end 21.34997 -39.910004)
				)
				(arc
					(start 21.34997 -51.90998)
					(mid 25.850088 -56.410098)
					(end 30.349952 -51.90998)
				)
			)
		)
	)
	(zone
		(layer "B.Cu")
		(hatch none 0.5)
		(connect_pads
			(clearance 0)
		)
		(min_thickness 0.25)
		(keepout
			(tracks allowed)
			(vias allowed)
			(pads allowed)
			(copperpour allowed)
			(footprints not_allowed)
		)
		(placement
			(enabled no)
			(sheetname "")
		)
		(fill
			(thermal_gap 0.5)
			(thermal_bridge_width 0.5)
			(island_removal_mode 0)
		)
		(polygon
			(pts
				(xy 0.999998 -169.209974) (xy 50.699924 -169.209974) (xy 50.699924 -126.234952) (xy 0.999998 -126.234952)
			)
		)
	)
	(zone
		(layer "B.Cu")
		(hatch none 0.5)
		(connect_pads
			(clearance 0)
		)
		(min_thickness 0.25)
		(keepout
			(tracks not_allowed)
			(vias allowed)
			(pads allowed)
			(copperpour not_allowed)
			(footprints allowed)
		)
		(placement
			(enabled no)
			(sheetname "")
		)
		(fill
			(thermal_gap 0.5)
			(thermal_bridge_width 0.5)
			(island_removal_mode 0)
		)
		(polygon
			(pts
				(arc
					(start 20.770088 -326.909938)
					(mid 25.850088 -331.989938)
					(end 30.930088 -326.909938)
				)
				(arc
					(start 30.930088 -304.909982)
					(mid 25.850088 -299.829982)
					(end 20.770088 -304.909982)
				)
			)
		)
	)
	(zone
		(layer "B.Cu")
		(hatch none 0.5)
		(connect_pads
			(clearance 0)
		)
		(min_thickness 0.25)
		(keepout
			(tracks not_allowed)
			(vias allowed)
			(pads allowed)
			(copperpour not_allowed)
			(footprints allowed)
		)
		(placement
			(enabled no)
			(sheetname "")
		)
		(fill
			(thermal_gap 0.5)
			(thermal_bridge_width 0.5)
			(island_removal_mode 0)
		)
		(polygon
			(pts
				(arc
					(start 15.349982 -145.661126)
					(mid 10.850118 -141.161262)
					(end 6.35 -145.661126)
				)
				(arc
					(start 6.35 -157.661102)
					(mid 10.850118 -162.16122)
					(end 15.349982 -157.661102)
				)
			)
		)
	)
	(zone
		(layer "B.Cu")
		(hatch none 0.5)
		(connect_pads
			(clearance 0)
		)
		(min_thickness 0.25)
		(keepout
			(tracks allowed)
			(vias allowed)
			(pads allowed)
			(copperpour allowed)
			(footprints not_allowed)
		)
		(placement
			(enabled no)
			(sheetname "")
		)
		(fill
			(thermal_gap 0.5)
			(thermal_bridge_width 0.5)
			(island_removal_mode 0)
		)
		(polygon
			(pts
				(arc
					(start 33.349946 -39.910004)
					(mid 25.850088 -32.410146)
					(end 18.349976 -39.910004)
				)
				(arc
					(start 18.349976 -51.90998)
					(mid 25.850088 -59.410092)
					(end 33.349946 -51.90998)
				)
			)
		)
	)
	(zone
		(layer "B.Cu")
		(hatch none 0.5)
		(connect_pads
			(clearance 0)
		)
		(min_thickness 0.25)
		(keepout
			(tracks allowed)
			(vias allowed)
			(pads allowed)
			(copperpour allowed)
			(footprints not_allowed)
		)
		(placement
			(enabled no)
			(sheetname "")
		)
		(fill
			(thermal_gap 0.5)
			(thermal_bridge_width 0.5)
			(island_removal_mode 0)
		)
		(polygon
			(pts
				(xy 52.349908 -4.884928) (xy 35.649916 -4.884928) (xy 35.649916 -33.934908) (xy 52.349908 -33.934908)
			)
		)
	)
	(zone
		(layer "B.Cu")
		(hatch none 0.5)
		(connect_pads
			(clearance 0)
		)
		(min_thickness 0.25)
		(keepout
			(tracks allowed)
			(vias allowed)
			(pads allowed)
			(copperpour allowed)
			(footprints not_allowed)
		)
		(placement
			(enabled no)
			(sheetname "")
		)
		(fill
			(thermal_gap 0.5)
			(thermal_bridge_width 0.5)
			(island_removal_mode 0)
		)
		(polygon
			(pts
				(arc
					(start 25.850088 -323.710046)
					(mid 22.649942 -326.910192)
					(end 25.850088 -330.110084)
				)
				(arc
					(start 25.850088 -330.110084)
					(mid 29.04998 -326.910192)
					(end 25.850088 -323.710046)
				)
			)
		)
	)
	(zone
		(layer "B.Cu")
		(hatch none 0.5)
		(connect_pads
			(clearance 0)
		)
		(min_thickness 0.25)
		(keepout
			(tracks not_allowed)
			(vias allowed)
			(pads allowed)
			(copperpour not_allowed)
			(footprints allowed)
		)
		(placement
			(enabled no)
			(sheetname "")
		)
		(fill
			(thermal_gap 0.5)
			(thermal_bridge_width 0.5)
			(island_removal_mode 0)
		)
		(polygon
			(pts
				(arc
					(start 30.349952 -229.909878)
					(mid 25.850088 -225.410014)
					(end 21.34997 -229.909878)
				)
				(arc
					(start 21.34997 -241.910108)
					(mid 25.850088 -246.410226)
					(end 30.349952 -241.910108)
				)
			)
		)
	)
	(zone
		(layer "B.Cu")
		(hatch none 0.5)
		(connect_pads
			(clearance 0)
		)
		(min_thickness 0.25)
		(keepout
			(tracks allowed)
			(vias allowed)
			(pads allowed)
			(copperpour allowed)
			(footprints not_allowed)
		)
		(placement
			(enabled no)
			(sheetname "")
		)
		(fill
			(thermal_gap 0.5)
			(thermal_bridge_width 0.5)
			(island_removal_mode 0)
		)
		(polygon
			(pts
				(arc
					(start 18.349976 -241.910108)
					(mid 25.850088 -249.41022)
					(end 33.349946 -241.910108)
				)
				(arc
					(start 33.349946 -229.909878)
					(mid 25.850088 -222.41002)
					(end 18.349976 -229.909878)
				)
			)
		)
	)
	(zone
		(layer "B.Cu")
		(hatch none 0.5)
		(connect_pads
			(clearance 0)
		)
		(min_thickness 0.25)
		(keepout
			(tracks allowed)
			(vias allowed)
			(pads allowed)
			(copperpour allowed)
			(footprints not_allowed)
		)
		(placement
			(enabled no)
			(sheetname "")
		)
		(fill
			(thermal_gap 0.5)
			(thermal_bridge_width 0.5)
			(island_removal_mode 0)
		)
		(polygon
			(pts
				(xy 50.699924 -189.485016) (xy 50.699924 -169.209974) (xy 0.999998 -169.209974) (xy 0.999998 -189.485016)
				(xy 16.050006 -189.485016) (xy 16.050006 -218.534996) (xy 35.649916 -218.534996) (xy 35.649916 -189.485016)
			)
		)
	)
	(zone
		(layer "B.Cu")
		(hatch none 0.5)
		(connect_pads
			(clearance 0)
		)
		(min_thickness 0.25)
		(keepout
			(tracks allowed)
			(vias allowed)
			(pads allowed)
			(copperpour allowed)
			(footprints not_allowed)
		)
		(placement
			(enabled no)
			(sheetname "")
		)
		(fill
			(thermal_gap 0.5)
			(thermal_bridge_width 0.5)
			(island_removal_mode 0)
		)
		(polygon
			(pts
				(xy 0.999998 -261.510018) (xy 50.699924 -261.510018) (xy 50.699924 -218.534996) (xy 0.999998 -218.534996)
			)
		)
	)
	(zone
		(layer "B.Cu")
		(hatch none 0.5)
		(connect_pads
			(clearance 0)
		)
		(min_thickness 0.25)
		(keepout
			(tracks allowed)
			(vias allowed)
			(pads allowed)
			(copperpour allowed)
			(footprints not_allowed)
		)
		(placement
			(enabled no)
			(sheetname "")
		)
		(fill
			(thermal_gap 0.5)
			(thermal_bridge_width 0.5)
			(island_removal_mode 0)
		)
		(polygon
			(pts
				(arc
					(start 28.349956 -229.909878)
					(mid 25.850088 -227.41001)
					(end 23.349966 -229.909878)
				)
				(arc
					(start 24.355044 -242.033806)
					(mid 25.850078 -243.410028)
					(end 27.344878 -242.033806)
				)
			)
		)
	)
	(zone
		(layer "B.Cu")
		(hatch none 0.5)
		(connect_pads
			(clearance 0)
		)
		(min_thickness 0.25)
		(keepout
			(tracks allowed)
			(vias allowed)
			(pads allowed)
			(copperpour allowed)
			(footprints not_allowed)
		)
		(placement
			(enabled no)
			(sheetname "")
		)
		(fill
			(thermal_gap 0.5)
			(thermal_bridge_width 0.5)
			(island_removal_mode 0)
		)
		(polygon
			(pts
				(arc
					(start 48.349916 -145.661126)
					(mid 40.850058 -138.161268)
					(end 33.349946 -145.661126)
				)
				(arc
					(start 33.349946 -157.661102)
					(mid 40.850058 -165.161214)
					(end 48.349916 -157.661102)
				)
			)
		)
	)
	(zone
		(layer "B.Cu")
		(hatch none 0.5)
		(connect_pads
			(clearance 0)
		)
		(min_thickness 0.25)
		(keepout
			(tracks allowed)
			(vias allowed)
			(pads allowed)
			(copperpour allowed)
			(footprints not_allowed)
		)
		(placement
			(enabled no)
			(sheetname "")
		)
		(fill
			(thermal_gap 0.5)
			(thermal_bridge_width 0.5)
			(island_removal_mode 0)
		)
		(polygon
			(pts
				(arc
					(start 28.349956 -39.910004)
					(mid 25.850088 -37.410136)
					(end 23.349966 -39.910004)
				)
				(arc
					(start 24.355044 -52.033932)
					(mid 25.850078 -53.410154)
					(end 27.344878 -52.033932)
				)
			)
		)
	)
	(zone
		(layer "B.Cu")
		(hatch none 0.5)
		(connect_pads
			(clearance 0)
		)
		(min_thickness 0.25)
		(keepout
			(tracks allowed)
			(vias allowed)
			(pads allowed)
			(copperpour allowed)
			(footprints not_allowed)
		)
		(placement
			(enabled no)
			(sheetname "")
		)
		(fill
			(thermal_gap 0.5)
			(thermal_bridge_width 0.5)
			(island_removal_mode 0)
		)
		(polygon
			(pts
				(xy 52.349908 -189.485016) (xy 35.649916 -189.485016) (xy 35.649916 -218.534996) (xy 52.349908 -218.534996)
			)
		)
	)
	(zone
		(layer "B.Cu")
		(hatch none 0.5)
		(connect_pads
			(clearance 0)
		)
		(min_thickness 0.25)
		(keepout
			(tracks allowed)
			(vias allowed)
			(pads allowed)
			(copperpour allowed)
			(footprints not_allowed)
		)
		(placement
			(enabled no)
			(sheetname "")
		)
		(fill
			(thermal_gap 0.5)
			(thermal_bridge_width 0.5)
			(island_removal_mode 0)
		)
		(polygon
			(pts
				(arc
					(start 3.350006 -157.661102)
					(mid 10.850118 -165.161214)
					(end 18.349976 -157.661102)
				)
				(arc
					(start 18.349976 -145.661126)
					(mid 10.850118 -138.161268)
					(end 3.350006 -145.661126)
				)
			)
		)
	)
	(zone
		(layer "B.Cu")
		(hatch none 0.5)
		(connect_pads
			(clearance 0)
		)
		(min_thickness 0.25)
		(keepout
			(tracks allowed)
			(vias allowed)
			(pads allowed)
			(copperpour allowed)
			(footprints not_allowed)
		)
		(placement
			(enabled no)
			(sheetname "")
		)
		(fill
			(thermal_gap 0.5)
			(thermal_bridge_width 0.5)
			(island_removal_mode 0)
		)
		(polygon
			(pts
				(arc
					(start 50.699924 -3.999992)
					(mid 49.821246 -1.878676)
					(end 47.69993 -0.999998)
				)
				(xy 37.154104 -0.999998) (xy 36.239958 -1.914144) (xy 36.239958 -4.884928) (xy 50.699924 -4.884928)
			)
		)
	)
	(zone
		(layer "B.Cu")
		(hatch none 0.5)
		(connect_pads
			(clearance 0)
		)
		(min_thickness 0.25)
		(keepout
			(tracks allowed)
			(vias allowed)
			(pads allowed)
			(copperpour allowed)
			(footprints not_allowed)
		)
		(placement
			(enabled no)
			(sheetname "")
		)
		(fill
			(thermal_gap 0.5)
			(thermal_bridge_width 0.5)
			(island_removal_mode 0)
		)
		(polygon
			(pts
				(xy 0.999998 -76.90993) (xy 50.699924 -76.90993) (xy 50.699924 -33.934908) (xy 35.649916 -33.934908)
				(xy 35.649916 -31.91002) (xy 16.050006 -31.91002) (xy 16.050006 -33.934908) (xy 0.999998 -33.905444)
			)
		)
	)
	(zone
		(layer "B.Cu")
		(hatch none 0.5)
		(connect_pads
			(clearance 0)
		)
		(min_thickness 0.25)
		(keepout
			(tracks not_allowed)
			(vias allowed)
			(pads allowed)
			(copperpour not_allowed)
			(footprints allowed)
		)
		(placement
			(enabled no)
			(sheetname "")
		)
		(fill
			(thermal_gap 0.5)
			(thermal_bridge_width 0.5)
			(island_removal_mode 0)
		)
		(polygon
			(pts
				(arc
					(start 45.349922 -145.661126)
					(mid 40.850058 -141.161262)
					(end 36.34994 -145.661126)
				)
				(arc
					(start 36.34994 -157.661102)
					(mid 40.850058 -162.16122)
					(end 45.349922 -157.661102)
				)
			)
		)
	)
	(zone
		(layer "B.Cu")
		(hatch none 0.5)
		(connect_pads
			(clearance 0)
		)
		(min_thickness 0.25)
		(keepout
			(tracks allowed)
			(vias allowed)
			(pads allowed)
			(copperpour allowed)
			(footprints not_allowed)
		)
		(placement
			(enabled no)
			(sheetname "")
		)
		(fill
			(thermal_gap 0.5)
			(thermal_bridge_width 0.5)
			(island_removal_mode 0)
		)
		(polygon
			(pts
				(xy 14.545818 -0.999998)
				(arc
					(start 3.999992 -0.999998)
					(mid 1.878676 -1.878676)
					(end 0.999998 -3.999992)
				)
				(xy 0.999998 -4.884928) (xy 15.459964 -4.884928) (xy 15.459964 -1.914144)
			)
		)
	)
	(zone
		(layer "B.Cu")
		(hatch none 0.5)
		(connect_pads
			(clearance 0)
		)
		(min_thickness 0.25)
		(keepout
			(tracks allowed)
			(vias allowed)
			(pads allowed)
			(copperpour allowed)
			(footprints not_allowed)
		)
		(placement
			(enabled no)
			(sheetname "")
		)
		(fill
			(thermal_gap 0.5)
			(thermal_bridge_width 0.5)
			(island_removal_mode 0)
		)
		(polygon
			(pts
				(xy -0.649986 -4.884928) (xy -0.649986 -33.934908) (xy 16.050006 -33.934908) (xy 16.050006 -4.884928)
			)
		)
	)
	(zone
		(layer "B.Cu")
		(hatch none 0.5)
		(connect_pads
			(clearance 0)
		)
		(min_thickness 0.25)
		(keepout
			(tracks allowed)
			(vias allowed)
			(pads allowed)
			(copperpour allowed)
			(footprints not_allowed)
		)
		(placement
			(enabled no)
			(sheetname "")
		)
		(fill
			(thermal_gap 0.5)
			(thermal_bridge_width 0.5)
			(island_removal_mode 0)
		)
		(polygon
			(pts
				(arc
					(start 16.050006 -12.49934)
					(mid 18.299797 -13.105051)
					(end 19.832066 -11.34999)
				)
				(arc
					(start 31.86811 -11.34999)
					(mid 33.400338 -13.104887)
					(end 35.649916 -12.49934)
				)
				(xy 35.649916 -31.91002) (xy 16.050006 -31.91002)
			)
		)
	)
	(zone
		(layer "B.Cu")
		(hatch none 0.5)
		(connect_pads
			(clearance 0)
		)
		(min_thickness 0.25)
		(keepout
			(tracks allowed)
			(vias allowed)
			(pads allowed)
			(copperpour allowed)
			(footprints not_allowed)
		)
		(placement
			(enabled no)
			(sheetname "")
		)
		(fill
			(thermal_gap 0.5)
			(thermal_bridge_width 0.5)
			(island_removal_mode 0)
		)
		(polygon
			(pts
				(arc
					(start 9.355328 -157.78607)
					(mid 10.850107 -159.161107)
					(end 12.344654 -157.78607)
				)
				(arc
					(start 13.34135 -145.869406)
					(mid 10.850129 -143.161203)
					(end 8.358632 -145.869406)
				)
			)
		)
	)
	(zone
		(layer "B.Cu")
		(hatch none 0.5)
		(connect_pads
			(clearance 0)
		)
		(min_thickness 0.25)
		(keepout
			(tracks allowed)
			(vias allowed)
			(pads allowed)
			(copperpour allowed)
			(footprints not_allowed)
		)
		(placement
			(enabled no)
			(sheetname "")
		)
		(fill
			(thermal_gap 0.5)
			(thermal_bridge_width 0.5)
			(island_removal_mode 0)
		)
		(polygon
			(pts
				(arc
					(start 18.269966 -326.909938)
					(mid 25.850088 -334.49006)
					(end 33.429956 -326.909938)
				)
				(arc
					(start 33.429956 -304.909982)
					(mid 25.850088 -297.330114)
					(end 18.269966 -304.909982)
				)
			)
		)
	)
	(zone
		(layer "B.Cu")
		(hatch none 0.5)
		(connect_pads
			(clearance 0)
		)
		(min_thickness 0.25)
		(keepout
			(tracks allowed)
			(vias allowed)
			(pads allowed)
			(copperpour allowed)
			(footprints not_allowed)
		)
		(placement
			(enabled no)
			(sheetname "")
		)
		(fill
			(thermal_gap 0.5)
			(thermal_bridge_width 0.5)
			(island_removal_mode 0)
		)
		(polygon
			(pts
				(arc
					(start 33.349946 -157.661102)
					(mid 40.850058 -165.161214)
					(end 48.349916 -157.661102)
				)
				(arc
					(start 48.349916 -145.661126)
					(mid 40.850058 -138.161268)
					(end 33.349946 -145.661126)
				)
			)
		)
	)
	(zone
		(layer "B.Cu")
		(hatch none 0.5)
		(connect_pads
			(clearance 0)
		)
		(min_thickness 0.25)
		(keepout
			(tracks allowed)
			(vias allowed)
			(pads allowed)
			(copperpour allowed)
			(footprints not_allowed)
		)
		(placement
			(enabled no)
			(sheetname "")
		)
		(fill
			(thermal_gap 0.5)
			(thermal_bridge_width 0.5)
			(island_removal_mode 0)
		)
		(polygon
			(pts
				(xy 50.699924 -97.184972) (xy 50.699924 -76.90993) (xy 0.999998 -76.90993) (xy 0.999998 -97.184972)
				(xy 16.050006 -97.184972) (xy 16.050006 -126.234952) (xy 35.649916 -126.234952) (xy 35.649916 -97.184972)
			)
		)
	)
	(zone
		(layers "In1.Cu" "In4.Cu")
		(hatch none 0.5)
		(connect_pads
			(clearance 0)
		)
		(min_thickness 0.25)
		(keepout
			(tracks not_allowed)
			(vias allowed)
			(pads allowed)
			(copperpour not_allowed)
			(footprints allowed)
		)
		(placement
			(enabled no)
			(sheetname "")
		)
		(fill yes
			(thermal_gap 0.5)
			(thermal_bridge_width 0.5)
			(island_removal_mode 0)
		)
		(polygon
			(pts
				(arc
					(start 7.03199 -80.067912)
					(mid 5.25399 -80.067912)
					(end 7.03199 -80.067912)
				)
			)
		)
	)
	(zone
		(layers "In1.Cu" "In4.Cu")
		(hatch none 0.5)
		(connect_pads
			(clearance 0)
		)
		(min_thickness 0.25)
		(keepout
			(tracks not_allowed)
			(vias allowed)
			(pads allowed)
			(copperpour not_allowed)
			(footprints allowed)
		)
		(placement
			(enabled no)
			(sheetname "")
		)
		(fill yes
			(thermal_gap 0.5)
			(thermal_bridge_width 0.5)
			(island_removal_mode 0)
		)
		(polygon
			(pts
				(arc
					(start 7.03199 -79.305912)
					(mid 5.25399 -79.305912)
					(end 7.03199 -79.305912)
				)
			)
		)
	)
	(zone
		(layers "In1.Cu" "In4.Cu")
		(hatch none 0.5)
		(connect_pads
			(clearance 0)
		)
		(min_thickness 0.25)
		(keepout
			(tracks not_allowed)
			(vias allowed)
			(pads allowed)
			(copperpour not_allowed)
			(footprints allowed)
		)
		(placement
			(enabled no)
			(sheetname "")
		)
		(fill yes
			(thermal_gap 0.5)
			(thermal_bridge_width 0.5)
			(island_removal_mode 0)
		)
		(polygon
			(pts
				(arc
					(start 47.563532 -246.1514)
					(mid 45.785532 -246.1514)
					(end 47.563532 -246.1514)
				)
			)
		)
	)
	(zone
		(layers "In1.Cu" "In4.Cu")
		(hatch none 0.5)
		(connect_pads
			(clearance 0)
		)
		(min_thickness 0.25)
		(keepout
			(tracks not_allowed)
			(vias allowed)
			(pads allowed)
			(copperpour not_allowed)
			(footprints allowed)
		)
		(placement
			(enabled no)
			(sheetname "")
		)
		(fill yes
			(thermal_gap 0.5)
			(thermal_bridge_width 0.5)
			(island_removal_mode 0)
		)
		(polygon
			(pts
				(arc
					(start 5.884418 -58.913776)
					(mid 4.106418 -58.913776)
					(end 5.884418 -58.913776)
				)
			)
		)
	)
	(zone
		(layers "In1.Cu" "In4.Cu")
		(hatch none 0.5)
		(connect_pads
			(clearance 0)
		)
		(min_thickness 0.25)
		(keepout
			(tracks not_allowed)
			(vias allowed)
			(pads allowed)
			(copperpour not_allowed)
			(footprints allowed)
		)
		(placement
			(enabled no)
			(sheetname "")
		)
		(fill yes
			(thermal_gap 0.5)
			(thermal_bridge_width 0.5)
			(island_removal_mode 0)
		)
		(polygon
			(pts
				(arc
					(start 13.159232 -222.86341)
					(mid 11.381232 -222.86341)
					(end 13.159232 -222.86341)
				)
			)
		)
	)
	(zone
		(layers "In1.Cu" "In4.Cu")
		(hatch none 0.5)
		(connect_pads
			(clearance 0)
		)
		(min_thickness 0.25)
		(keepout
			(tracks not_allowed)
			(vias allowed)
			(pads allowed)
			(copperpour not_allowed)
			(footprints allowed)
		)
		(placement
			(enabled no)
			(sheetname "")
		)
		(fill yes
			(thermal_gap 0.5)
			(thermal_bridge_width 0.5)
			(island_removal_mode 0)
		)
		(polygon
			(pts
				(arc
					(start 8.020812 -114.709956)
					(mid 5.379212 -114.709956)
					(end 8.020812 -114.709956)
				)
			)
		)
	)
	(zone
		(layers "In1.Cu" "In4.Cu")
		(hatch none 0.5)
		(connect_pads
			(clearance 0)
		)
		(min_thickness 0.25)
		(keepout
			(tracks not_allowed)
			(vias allowed)
			(pads allowed)
			(copperpour not_allowed)
			(footprints allowed)
		)
		(placement
			(enabled no)
			(sheetname "")
		)
		(fill yes
			(thermal_gap 0.5)
			(thermal_bridge_width 0.5)
			(island_removal_mode 0)
		)
		(polygon
			(pts
				(arc
					(start 42.296588 -58.570622)
					(mid 40.518588 -58.570622)
					(end 42.296588 -58.570622)
				)
			)
		)
	)
	(zone
		(layers "In1.Cu" "In4.Cu")
		(hatch none 0.5)
		(connect_pads
			(clearance 0)
		)
		(min_thickness 0.25)
		(keepout
			(tracks not_allowed)
			(vias allowed)
			(pads allowed)
			(copperpour not_allowed)
			(footprints allowed)
		)
		(placement
			(enabled no)
			(sheetname "")
		)
		(fill yes
			(thermal_gap 0.5)
			(thermal_bridge_width 0.5)
			(island_removal_mode 0)
		)
		(polygon
			(pts
				(arc
					(start 29.215588 -12.0142)
					(mid 27.437588 -12.0142)
					(end 29.215588 -12.0142)
				)
			)
		)
	)
	(zone
		(layers "In1.Cu" "In4.Cu")
		(hatch none 0.5)
		(connect_pads
			(clearance 0)
		)
		(min_thickness 0.25)
		(keepout
			(tracks not_allowed)
			(vias allowed)
			(pads allowed)
			(copperpour not_allowed)
			(footprints allowed)
		)
		(placement
			(enabled no)
			(sheetname "")
		)
		(fill yes
			(thermal_gap 0.5)
			(thermal_bridge_width 0.5)
			(island_removal_mode 0)
		)
		(polygon
			(pts
				(arc
					(start 46.776132 -246.126)
					(mid 44.998132 -246.126)
					(end 46.776132 -246.126)
				)
			)
		)
	)
	(zone
		(layers "In1.Cu" "In4.Cu")
		(hatch none 0.5)
		(connect_pads
			(clearance 0)
		)
		(min_thickness 0.25)
		(keepout
			(tracks not_allowed)
			(vias allowed)
			(pads allowed)
			(copperpour not_allowed)
			(footprints allowed)
		)
		(placement
			(enabled no)
			(sheetname "")
		)
		(fill yes
			(thermal_gap 0.5)
			(thermal_bridge_width 0.5)
			(island_removal_mode 0)
		)
		(polygon
			(pts
				(arc
					(start 42.000932 -79.721202)
					(mid 40.222932 -79.721202)
					(end 42.000932 -79.721202)
				)
			)
		)
	)
	(zone
		(layers "In1.Cu" "In4.Cu")
		(hatch none 0.5)
		(connect_pads
			(clearance 0)
		)
		(min_thickness 0.25)
		(keepout
			(tracks not_allowed)
			(vias allowed)
			(pads allowed)
			(copperpour not_allowed)
			(footprints allowed)
		)
		(placement
			(enabled no)
			(sheetname "")
		)
		(fill yes
			(thermal_gap 0.5)
			(thermal_bridge_width 0.5)
			(island_removal_mode 0)
		)
		(polygon
			(pts
				(arc
					(start 8.328914 -244.31371)
					(mid 6.550914 -244.31371)
					(end 8.328914 -244.31371)
				)
			)
		)
	)
	(zone
		(layers "In1.Cu" "In4.Cu")
		(hatch none 0.5)
		(connect_pads
			(clearance 0)
		)
		(min_thickness 0.25)
		(keepout
			(tracks not_allowed)
			(vias allowed)
			(pads allowed)
			(copperpour not_allowed)
			(footprints allowed)
		)
		(placement
			(enabled no)
			(sheetname "")
		)
		(fill yes
			(thermal_gap 0.5)
			(thermal_bridge_width 0.5)
			(island_removal_mode 0)
		)
		(polygon
			(pts
				(arc
					(start 9.15035 -230.439214)
					(mid 7.37235 -230.439214)
					(end 9.15035 -230.439214)
				)
			)
		)
	)
	(zone
		(layers "In1.Cu" "In4.Cu")
		(hatch none 0.5)
		(connect_pads
			(clearance 0)
		)
		(min_thickness 0.25)
		(keepout
			(tracks not_allowed)
			(vias allowed)
			(pads allowed)
			(copperpour not_allowed)
			(footprints allowed)
		)
		(placement
			(enabled no)
			(sheetname "")
		)
		(fill yes
			(thermal_gap 0.5)
			(thermal_bridge_width 0.5)
			(island_removal_mode 0)
		)
		(polygon
			(pts
				(arc
					(start 42.926 -312.3946)
					(mid 41.148 -312.3946)
					(end 42.926 -312.3946)
				)
			)
		)
	)
	(zone
		(layers "In1.Cu" "In4.Cu")
		(hatch none 0.5)
		(connect_pads
			(clearance 0)
		)
		(min_thickness 0.25)
		(keepout
			(tracks not_allowed)
			(vias allowed)
			(pads allowed)
			(copperpour not_allowed)
			(footprints allowed)
		)
		(placement
			(enabled no)
			(sheetname "")
		)
		(fill yes
			(thermal_gap 0.5)
			(thermal_bridge_width 0.5)
			(island_removal_mode 0)
		)
		(polygon
			(pts
				(arc
					(start 8.339074 -243.67871)
					(mid 6.561074 -243.67871)
					(end 8.339074 -243.67871)
				)
			)
		)
	)
	(zone
		(layers "In1.Cu" "In4.Cu")
		(hatch none 0.5)
		(connect_pads
			(clearance 0)
		)
		(min_thickness 0.25)
		(keepout
			(tracks not_allowed)
			(vias allowed)
			(pads allowed)
			(copperpour not_allowed)
			(footprints allowed)
		)
		(placement
			(enabled no)
			(sheetname "")
		)
		(fill yes
			(thermal_gap 0.5)
			(thermal_bridge_width 0.5)
			(island_removal_mode 0)
		)
		(polygon
			(pts
				(arc
					(start 14.726158 -59.298078)
					(mid 12.948158 -59.298078)
					(end 14.726158 -59.298078)
				)
			)
		)
	)
	(zone
		(layers "In1.Cu" "In4.Cu")
		(hatch none 0.5)
		(connect_pads
			(clearance 0)
		)
		(min_thickness 0.25)
		(keepout
			(tracks not_allowed)
			(vias allowed)
			(pads allowed)
			(copperpour not_allowed)
			(footprints allowed)
		)
		(placement
			(enabled no)
			(sheetname "")
		)
		(fill yes
			(thermal_gap 0.5)
			(thermal_bridge_width 0.5)
			(island_removal_mode 0)
		)
		(polygon
			(pts
				(arc
					(start 32.131 -299.974)
					(mid 30.353 -299.974)
					(end 32.131 -299.974)
				)
			)
		)
	)
	(zone
		(layers "In1.Cu" "In4.Cu")
		(hatch none 0.5)
		(connect_pads
			(clearance 0)
		)
		(min_thickness 0.25)
		(keepout
			(tracks not_allowed)
			(vias allowed)
			(pads allowed)
			(copperpour not_allowed)
			(footprints allowed)
		)
		(placement
			(enabled no)
			(sheetname "")
		)
		(fill yes
			(thermal_gap 0.5)
			(thermal_bridge_width 0.5)
			(island_removal_mode 0)
		)
		(polygon
			(pts
				(arc
					(start 43.810428 -80.521048)
					(mid 42.032428 -80.521048)
					(end 43.810428 -80.521048)
				)
			)
		)
	)
	(zone
		(layers "In1.Cu" "In4.Cu")
		(hatch none 0.5)
		(connect_pads
			(clearance 0)
		)
		(min_thickness 0.25)
		(keepout
			(tracks not_allowed)
			(vias allowed)
			(pads allowed)
			(copperpour not_allowed)
			(footprints allowed)
		)
		(placement
			(enabled no)
			(sheetname "")
		)
		(fill yes
			(thermal_gap 0.5)
			(thermal_bridge_width 0.5)
			(island_removal_mode 0)
		)
		(polygon
			(pts
				(arc
					(start 7.239 -281.2542)
					(mid 5.461 -281.2542)
					(end 7.239 -281.2542)
				)
			)
		)
	)
	(zone
		(layers "In1.Cu" "In4.Cu")
		(hatch none 0.5)
		(connect_pads
			(clearance 0)
		)
		(min_thickness 0.25)
		(keepout
			(tracks not_allowed)
			(vias allowed)
			(pads allowed)
			(copperpour not_allowed)
			(footprints allowed)
		)
		(placement
			(enabled no)
			(sheetname "")
		)
		(fill yes
			(thermal_gap 0.5)
			(thermal_bridge_width 0.5)
			(island_removal_mode 0)
		)
		(polygon
			(pts
				(arc
					(start 41.365932 -263.68629)
					(mid 39.587932 -263.68629)
					(end 41.365932 -263.68629)
				)
			)
		)
	)
	(zone
		(layers "In1.Cu" "In4.Cu")
		(hatch none 0.5)
		(connect_pads
			(clearance 0)
		)
		(min_thickness 0.25)
		(keepout
			(tracks not_allowed)
			(vias allowed)
			(pads allowed)
			(copperpour not_allowed)
			(footprints allowed)
		)
		(placement
			(enabled no)
			(sheetname "")
		)
		(fill yes
			(thermal_gap 0.5)
			(thermal_bridge_width 0.5)
			(island_removal_mode 0)
		)
		(polygon
			(pts
				(arc
					(start 14.366494 -264.32129)
					(mid 12.588494 -264.32129)
					(end 14.366494 -264.32129)
				)
			)
		)
	)
	(zone
		(layers "In1.Cu" "In4.Cu")
		(hatch none 0.5)
		(connect_pads
			(clearance 0)
		)
		(min_thickness 0.25)
		(keepout
			(tracks not_allowed)
			(vias allowed)
			(pads allowed)
			(copperpour not_allowed)
			(footprints allowed)
		)
		(placement
			(enabled no)
			(sheetname "")
		)
		(fill yes
			(thermal_gap 0.5)
			(thermal_bridge_width 0.5)
			(island_removal_mode 0)
		)
		(polygon
			(pts
				(arc
					(start 46.445932 -57.741312)
					(mid 44.667932 -57.741312)
					(end 46.445932 -57.741312)
				)
			)
		)
	)
	(zone
		(layers "In1.Cu" "In4.Cu")
		(hatch none 0.5)
		(connect_pads
			(clearance 0)
		)
		(min_thickness 0.25)
		(keepout
			(tracks not_allowed)
			(vias allowed)
			(pads allowed)
			(copperpour not_allowed)
			(footprints allowed)
		)
		(placement
			(enabled no)
			(sheetname "")
		)
		(fill yes
			(thermal_gap 0.5)
			(thermal_bridge_width 0.5)
			(island_removal_mode 0)
		)
		(polygon
			(pts
				(arc
					(start 43.524932 -244.2972)
					(mid 41.746932 -244.2972)
					(end 43.524932 -244.2972)
				)
			)
		)
	)
	(zone
		(layers "In1.Cu" "In4.Cu")
		(hatch none 0.5)
		(connect_pads
			(clearance 0)
		)
		(min_thickness 0.25)
		(keepout
			(tracks not_allowed)
			(vias allowed)
			(pads allowed)
			(copperpour not_allowed)
			(footprints allowed)
		)
		(placement
			(enabled no)
			(sheetname "")
		)
		(fill yes
			(thermal_gap 0.5)
			(thermal_bridge_width 0.5)
			(island_removal_mode 0)
		)
		(polygon
			(pts
				(arc
					(start 46.32071 -201.010012)
					(mid 43.67911 -201.010012)
					(end 46.32071 -201.010012)
				)
			)
		)
	)
	(zone
		(layers "In1.Cu" "In4.Cu")
		(hatch none 0.5)
		(connect_pads
			(clearance 0)
		)
		(min_thickness 0.25)
		(keepout
			(tracks not_allowed)
			(vias allowed)
			(pads allowed)
			(copperpour not_allowed)
			(footprints allowed)
		)
		(placement
			(enabled no)
			(sheetname "")
		)
		(fill yes
			(thermal_gap 0.5)
			(thermal_bridge_width 0.5)
			(island_removal_mode 0)
		)
		(polygon
			(pts
				(arc
					(start 5.50799 -79.305912)
					(mid 3.72999 -79.305912)
					(end 5.50799 -79.305912)
				)
			)
		)
	)
	(zone
		(layers "In1.Cu" "In4.Cu")
		(hatch none 0.5)
		(connect_pads
			(clearance 0)
		)
		(min_thickness 0.25)
		(keepout
			(tracks not_allowed)
			(vias allowed)
			(pads allowed)
			(copperpour not_allowed)
			(footprints allowed)
		)
		(placement
			(enabled no)
			(sheetname "")
		)
		(fill yes
			(thermal_gap 0.5)
			(thermal_bridge_width 0.5)
			(island_removal_mode 0)
		)
		(polygon
			(pts
				(arc
					(start 46.32071 -16.409924)
					(mid 43.67911 -16.409924)
					(end 46.32071 -16.409924)
				)
			)
		)
	)
	(zone
		(layers "In1.Cu" "In4.Cu")
		(hatch none 0.5)
		(connect_pads
			(clearance 0)
		)
		(min_thickness 0.25)
		(keepout
			(tracks not_allowed)
			(vias allowed)
			(pads allowed)
			(copperpour not_allowed)
			(footprints allowed)
		)
		(placement
			(enabled no)
			(sheetname "")
		)
		(fill yes
			(thermal_gap 0.5)
			(thermal_bridge_width 0.5)
			(island_removal_mode 0)
		)
		(polygon
			(pts
				(arc
					(start 41.355772 -79.721202)
					(mid 39.577772 -79.721202)
					(end 41.355772 -79.721202)
				)
			)
		)
	)
	(zone
		(layers "In1.Cu" "In4.Cu")
		(hatch none 0.5)
		(connect_pads
			(clearance 0)
		)
		(min_thickness 0.25)
		(keepout
			(tracks not_allowed)
			(vias allowed)
			(pads allowed)
			(copperpour not_allowed)
			(footprints allowed)
		)
		(placement
			(enabled no)
			(sheetname "")
		)
		(fill yes
			(thermal_gap 0.5)
			(thermal_bridge_width 0.5)
			(island_removal_mode 0)
		)
		(polygon
			(pts
				(arc
					(start 2.794 -11.176)
					(mid 1.016 -11.176)
					(end 2.794 -11.176)
				)
			)
		)
	)
	(zone
		(layers "In1.Cu" "In4.Cu")
		(hatch none 0.5)
		(connect_pads
			(clearance 0)
		)
		(min_thickness 0.25)
		(keepout
			(tracks not_allowed)
			(vias allowed)
			(pads allowed)
			(copperpour not_allowed)
			(footprints allowed)
		)
		(placement
			(enabled no)
			(sheetname "")
		)
		(fill yes
			(thermal_gap 0.5)
			(thermal_bridge_width 0.5)
			(island_removal_mode 0)
		)
		(polygon
			(pts
				(arc
					(start 37.301932 -243.67871)
					(mid 35.523932 -243.67871)
					(end 37.301932 -243.67871)
				)
			)
		)
	)
	(zone
		(layers "In1.Cu" "In4.Cu")
		(hatch none 0.5)
		(connect_pads
			(clearance 0)
		)
		(min_thickness 0.25)
		(keepout
			(tracks not_allowed)
			(vias allowed)
			(pads allowed)
			(copperpour not_allowed)
			(footprints allowed)
		)
		(placement
			(enabled no)
			(sheetname "")
		)
		(fill yes
			(thermal_gap 0.5)
			(thermal_bridge_width 0.5)
			(island_removal_mode 0)
		)
		(polygon
			(pts
				(arc
					(start 7.693914 -59.078622)
					(mid 5.915914 -59.078622)
					(end 7.693914 -59.078622)
				)
			)
		)
	)
	(zone
		(layers "In1.Cu" "In4.Cu")
		(hatch none 0.5)
		(connect_pads
			(clearance 0)
		)
		(min_thickness 0.25)
		(keepout
			(tracks not_allowed)
			(vias allowed)
			(pads allowed)
			(copperpour not_allowed)
			(footprints allowed)
		)
		(placement
			(enabled no)
			(sheetname "")
		)
		(fill yes
			(thermal_gap 0.5)
			(thermal_bridge_width 0.5)
			(island_removal_mode 0)
		)
		(polygon
			(pts
				(arc
					(start 17.46631 -264.486136)
					(mid 15.68831 -264.486136)
					(end 17.46631 -264.486136)
				)
			)
		)
	)
	(zone
		(layers "In1.Cu" "In4.Cu")
		(hatch none 0.5)
		(connect_pads
			(clearance 0)
		)
		(min_thickness 0.25)
		(keepout
			(tracks not_allowed)
			(vias allowed)
			(pads allowed)
			(copperpour not_allowed)
			(footprints allowed)
		)
		(placement
			(enabled no)
			(sheetname "")
		)
		(fill yes
			(thermal_gap 0.5)
			(thermal_bridge_width 0.5)
			(island_removal_mode 0)
		)
		(polygon
			(pts
				(arc
					(start 6.731 -193.04)
					(mid 4.953 -193.04)
					(end 6.731 -193.04)
				)
			)
		)
	)
	(zone
		(layers "In1.Cu" "In4.Cu")
		(hatch none 0.5)
		(connect_pads
			(clearance 0)
		)
		(min_thickness 0.25)
		(keepout
			(tracks not_allowed)
			(vias allowed)
			(pads allowed)
			(copperpour not_allowed)
			(footprints allowed)
		)
		(placement
			(enabled no)
			(sheetname "")
		)
		(fill yes
			(thermal_gap 0.5)
			(thermal_bridge_width 0.5)
			(island_removal_mode 0)
		)
		(polygon
			(pts
				(arc
					(start 34.006028 -264.668)
					(mid 32.228028 -264.668)
					(end 34.006028 -264.668)
				)
			)
		)
	)
	(zone
		(layers "In1.Cu" "In4.Cu")
		(hatch none 0.5)
		(connect_pads
			(clearance 0)
		)
		(min_thickness 0.25)
		(keepout
			(tracks not_allowed)
			(vias allowed)
			(pads allowed)
			(copperpour not_allowed)
			(footprints allowed)
		)
		(placement
			(enabled no)
			(sheetname "")
		)
		(fill yes
			(thermal_gap 0.5)
			(thermal_bridge_width 0.5)
			(island_removal_mode 0)
		)
		(polygon
			(pts
				(arc
					(start 6.32079 -264.6426)
					(mid 4.54279 -264.6426)
					(end 6.32079 -264.6426)
				)
			)
		)
	)
	(zone
		(layers "In1.Cu" "In4.Cu")
		(hatch none 0.5)
		(connect_pads
			(clearance 0)
		)
		(min_thickness 0.25)
		(keepout
			(tracks not_allowed)
			(vias allowed)
			(pads allowed)
			(copperpour not_allowed)
			(footprints allowed)
		)
		(placement
			(enabled no)
			(sheetname "")
		)
		(fill yes
			(thermal_gap 0.5)
			(thermal_bridge_width 0.5)
			(island_removal_mode 0)
		)
		(polygon
			(pts
				(arc
					(start 43.605958 -239.5474)
					(mid 41.827958 -239.5474)
					(end 43.605958 -239.5474)
				)
			)
		)
	)
	(zone
		(layers "In1.Cu" "In4.Cu")
		(hatch none 0.5)
		(connect_pads
			(clearance 0)
		)
		(min_thickness 0.25)
		(keepout
			(tracks not_allowed)
			(vias allowed)
			(pads allowed)
			(copperpour not_allowed)
			(footprints allowed)
		)
		(placement
			(enabled no)
			(sheetname "")
		)
		(fill yes
			(thermal_gap 0.5)
			(thermal_bridge_width 0.5)
			(island_removal_mode 0)
		)
		(polygon
			(pts
				(arc
					(start 37.229288 -272.542)
					(mid 35.451288 -272.542)
					(end 37.229288 -272.542)
				)
			)
		)
	)
	(zone
		(layers "In1.Cu" "In4.Cu")
		(hatch none 0.5)
		(connect_pads
			(clearance 0)
		)
		(min_thickness 0.25)
		(keepout
			(tracks not_allowed)
			(vias allowed)
			(pads allowed)
			(copperpour not_allowed)
			(footprints allowed)
		)
		(placement
			(enabled no)
			(sheetname "")
		)
		(fill yes
			(thermal_gap 0.5)
			(thermal_bridge_width 0.5)
			(island_removal_mode 0)
		)
		(polygon
			(pts
				(arc
					(start 46.445932 -58.503312)
					(mid 44.667932 -58.503312)
					(end 46.445932 -58.503312)
				)
			)
		)
	)
	(zone
		(layers "In1.Cu" "In4.Cu")
		(hatch none 0.5)
		(connect_pads
			(clearance 0)
		)
		(min_thickness 0.25)
		(keepout
			(tracks not_allowed)
			(vias allowed)
			(pads allowed)
			(copperpour not_allowed)
			(footprints allowed)
		)
		(placement
			(enabled no)
			(sheetname "")
		)
		(fill yes
			(thermal_gap 0.5)
			(thermal_bridge_width 0.5)
			(island_removal_mode 0)
		)
		(polygon
			(pts
				(arc
					(start 33.274 -32.893)
					(mid 31.496 -32.893)
					(end 33.274 -32.893)
				)
			)
		)
	)
	(zone
		(layers "In1.Cu" "In4.Cu")
		(hatch none 0.5)
		(connect_pads
			(clearance 0)
		)
		(min_thickness 0.25)
		(keepout
			(tracks not_allowed)
			(vias allowed)
			(pads allowed)
			(copperpour not_allowed)
			(footprints allowed)
		)
		(placement
			(enabled no)
			(sheetname "")
		)
		(fill yes
			(thermal_gap 0.5)
			(thermal_bridge_width 0.5)
			(island_removal_mode 0)
		)
		(polygon
			(pts
				(arc
					(start 16.82115 -265.121136)
					(mid 15.04315 -265.121136)
					(end 16.82115 -265.121136)
				)
			)
		)
	)
	(zone
		(layers "In1.Cu" "In4.Cu")
		(hatch none 0.5)
		(connect_pads
			(clearance 0)
		)
		(min_thickness 0.25)
		(keepout
			(tracks not_allowed)
			(vias allowed)
			(pads allowed)
			(copperpour not_allowed)
			(footprints allowed)
		)
		(placement
			(enabled no)
			(sheetname "")
		)
		(fill yes
			(thermal_gap 0.5)
			(thermal_bridge_width 0.5)
			(island_removal_mode 0)
		)
		(polygon
			(pts
				(arc
					(start 33.269428 -79.305912)
					(mid 31.491428 -79.305912)
					(end 33.269428 -79.305912)
				)
			)
		)
	)
	(zone
		(layers "In1.Cu" "In4.Cu")
		(hatch none 0.5)
		(connect_pads
			(clearance 0)
		)
		(min_thickness 0.25)
		(keepout
			(tracks not_allowed)
			(vias allowed)
			(pads allowed)
			(copperpour not_allowed)
			(footprints allowed)
		)
		(placement
			(enabled no)
			(sheetname "")
		)
		(fill yes
			(thermal_gap 0.5)
			(thermal_bridge_width 0.5)
			(island_removal_mode 0)
		)
		(polygon
			(pts
				(arc
					(start 9.22655 -233.131614)
					(mid 7.44855 -233.131614)
					(end 9.22655 -233.131614)
				)
			)
		)
	)
	(zone
		(layers "In1.Cu" "In4.Cu")
		(hatch none 0.5)
		(connect_pads
			(clearance 0)
		)
		(min_thickness 0.25)
		(keepout
			(tracks not_allowed)
			(vias allowed)
			(pads allowed)
			(copperpour not_allowed)
			(footprints allowed)
		)
		(placement
			(enabled no)
			(sheetname "")
		)
		(fill yes
			(thermal_gap 0.5)
			(thermal_bridge_width 0.5)
			(island_removal_mode 0)
		)
		(polygon
			(pts
				(arc
					(start 15.037054 -271.386046)
					(mid 13.259054 -271.386046)
					(end 15.037054 -271.386046)
				)
			)
		)
	)
	(zone
		(layers "In1.Cu" "In4.Cu")
		(hatch none 0.5)
		(connect_pads
			(clearance 0)
		)
		(min_thickness 0.25)
		(keepout
			(tracks not_allowed)
			(vias allowed)
			(pads allowed)
			(copperpour not_allowed)
			(footprints allowed)
		)
		(placement
			(enabled no)
			(sheetname "")
		)
		(fill yes
			(thermal_gap 0.5)
			(thermal_bridge_width 0.5)
			(island_removal_mode 0)
		)
		(polygon
			(pts
				(arc
					(start 8.339074 -59.078622)
					(mid 6.561074 -59.078622)
					(end 8.339074 -59.078622)
				)
			)
		)
	)
	(zone
		(layers "In1.Cu" "In4.Cu")
		(hatch none 0.5)
		(connect_pads
			(clearance 0)
		)
		(min_thickness 0.25)
		(keepout
			(tracks not_allowed)
			(vias allowed)
			(pads allowed)
			(copperpour not_allowed)
			(footprints allowed)
		)
		(placement
			(enabled no)
			(sheetname "")
		)
		(fill yes
			(thermal_gap 0.5)
			(thermal_bridge_width 0.5)
			(island_removal_mode 0)
		)
		(polygon
			(pts
				(arc
					(start 40.710612 -79.721202)
					(mid 38.932612 -79.721202)
					(end 40.710612 -79.721202)
				)
			)
		)
	)
	(zone
		(layers "In1.Cu" "In4.Cu")
		(hatch none 0.5)
		(connect_pads
			(clearance 0)
		)
		(min_thickness 0.25)
		(keepout
			(tracks not_allowed)
			(vias allowed)
			(pads allowed)
			(copperpour not_allowed)
			(footprints allowed)
		)
		(placement
			(enabled no)
			(sheetname "")
		)
		(fill yes
			(thermal_gap 0.5)
			(thermal_bridge_width 0.5)
			(island_removal_mode 0)
		)
		(polygon
			(pts
				(arc
					(start 16.69415 -80.521048)
					(mid 14.91615 -80.521048)
					(end 16.69415 -80.521048)
				)
			)
		)
	)
	(zone
		(layers "In1.Cu" "In4.Cu")
		(hatch none 0.5)
		(connect_pads
			(clearance 0)
		)
		(min_thickness 0.25)
		(keepout
			(tracks not_allowed)
			(vias allowed)
			(pads allowed)
			(copperpour not_allowed)
			(footprints allowed)
		)
		(placement
			(enabled no)
			(sheetname "")
		)
		(fill yes
			(thermal_gap 0.5)
			(thermal_bridge_width 0.5)
			(island_removal_mode 0)
		)
		(polygon
			(pts
				(arc
					(start 16.390366 -269.428468)
					(mid 14.612366 -269.428468)
					(end 16.390366 -269.428468)
				)
			)
		)
	)
	(zone
		(layers "In1.Cu" "In4.Cu")
		(hatch none 0.5)
		(connect_pads
			(clearance 0)
		)
		(min_thickness 0.25)
		(keepout
			(tracks not_allowed)
			(vias allowed)
			(pads allowed)
			(copperpour not_allowed)
			(footprints allowed)
		)
		(placement
			(enabled no)
			(sheetname "")
		)
		(fill yes
			(thermal_gap 0.5)
			(thermal_bridge_width 0.5)
			(island_removal_mode 0)
		)
		(polygon
			(pts
				(arc
					(start 46.522132 -61.856112)
					(mid 44.744132 -61.856112)
					(end 46.522132 -61.856112)
				)
			)
		)
	)
	(zone
		(layers "In1.Cu" "In4.Cu")
		(hatch none 0.5)
		(connect_pads
			(clearance 0)
		)
		(min_thickness 0.25)
		(keepout
			(tracks not_allowed)
			(vias allowed)
			(pads allowed)
			(copperpour not_allowed)
			(footprints allowed)
		)
		(placement
			(enabled no)
			(sheetname "")
		)
		(fill yes
			(thermal_gap 0.5)
			(thermal_bridge_width 0.5)
			(island_removal_mode 0)
		)
		(polygon
			(pts
				(arc
					(start 12.949174 -79.086202)
					(mid 11.171174 -79.086202)
					(end 12.949174 -79.086202)
				)
			)
		)
	)
	(zone
		(layers "In1.Cu" "In4.Cu")
		(hatch none 0.5)
		(connect_pads
			(clearance 0)
		)
		(min_thickness 0.25)
		(keepout
			(tracks not_allowed)
			(vias allowed)
			(pads allowed)
			(copperpour not_allowed)
			(footprints allowed)
		)
		(placement
			(enabled no)
			(sheetname "")
		)
		(fill yes
			(thermal_gap 0.5)
			(thermal_bridge_width 0.5)
			(island_removal_mode 0)
		)
		(polygon
			(pts
				(arc
					(start 39.389304 -37.248846)
					(mid 37.611304 -37.248846)
					(end 39.389304 -37.248846)
				)
			)
		)
	)
	(zone
		(layers "In1.Cu" "In4.Cu")
		(hatch none 0.5)
		(connect_pads
			(clearance 0)
		)
		(min_thickness 0.25)
		(keepout
			(tracks not_allowed)
			(vias allowed)
			(pads allowed)
			(copperpour not_allowed)
			(footprints allowed)
		)
		(placement
			(enabled no)
			(sheetname "")
		)
		(fill yes
			(thermal_gap 0.5)
			(thermal_bridge_width 0.5)
			(island_removal_mode 0)
		)
		(polygon
			(pts
				(arc
					(start 39.111428 -59.078622)
					(mid 37.333428 -59.078622)
					(end 39.111428 -59.078622)
				)
			)
		)
	)
	(zone
		(layers "In1.Cu" "In4.Cu")
		(hatch none 0.5)
		(connect_pads
			(clearance 0)
		)
		(min_thickness 0.25)
		(keepout
			(tracks not_allowed)
			(vias allowed)
			(pads allowed)
			(copperpour not_allowed)
			(footprints allowed)
		)
		(placement
			(enabled no)
			(sheetname "")
		)
		(fill yes
			(thermal_gap 0.5)
			(thermal_bridge_width 0.5)
			(island_removal_mode 0)
		)
		(polygon
			(pts
				(arc
					(start 11.599418 -58.477912)
					(mid 9.821418 -58.477912)
					(end 11.599418 -58.477912)
				)
			)
		)
	)
	(zone
		(layers "In1.Cu" "In4.Cu")
		(hatch none 0.5)
		(connect_pads
			(clearance 0)
		)
		(min_thickness 0.25)
		(keepout
			(tracks not_allowed)
			(vias allowed)
			(pads allowed)
			(copperpour not_allowed)
			(footprints allowed)
		)
		(placement
			(enabled no)
			(sheetname "")
		)
		(fill yes
			(thermal_gap 0.5)
			(thermal_bridge_width 0.5)
			(island_removal_mode 0)
		)
		(polygon
			(pts
				(arc
					(start 18.796 -112.649)
					(mid 17.018 -112.649)
					(end 18.796 -112.649)
				)
			)
		)
	)
	(zone
		(layers "In1.Cu" "In4.Cu")
		(hatch none 0.5)
		(connect_pads
			(clearance 0)
		)
		(min_thickness 0.25)
		(keepout
			(tracks not_allowed)
			(vias allowed)
			(pads allowed)
			(copperpour not_allowed)
			(footprints allowed)
		)
		(placement
			(enabled no)
			(sheetname "")
		)
		(fill yes
			(thermal_gap 0.5)
			(thermal_bridge_width 0.5)
			(island_removal_mode 0)
		)
		(polygon
			(pts
				(arc
					(start 7.693914 -59.713622)
					(mid 5.915914 -59.713622)
					(end 7.693914 -59.713622)
				)
			)
		)
	)
	(zone
		(layers "In1.Cu" "In4.Cu")
		(hatch none 0.5)
		(connect_pads
			(clearance 0)
		)
		(min_thickness 0.25)
		(keepout
			(tracks not_allowed)
			(vias allowed)
			(pads allowed)
			(copperpour not_allowed)
			(footprints allowed)
		)
		(placement
			(enabled no)
			(sheetname "")
		)
		(fill yes
			(thermal_gap 0.5)
			(thermal_bridge_width 0.5)
			(island_removal_mode 0)
		)
		(polygon
			(pts
				(arc
					(start 14.596618 -62.541912)
					(mid 12.818618 -62.541912)
					(end 14.596618 -62.541912)
				)
			)
		)
	)
	(zone
		(layers "In1.Cu" "In4.Cu")
		(hatch none 0.5)
		(connect_pads
			(clearance 0)
		)
		(min_thickness 0.25)
		(keepout
			(tracks not_allowed)
			(vias allowed)
			(pads allowed)
			(copperpour not_allowed)
			(footprints allowed)
		)
		(placement
			(enabled no)
			(sheetname "")
		)
		(fill yes
			(thermal_gap 0.5)
			(thermal_bridge_width 0.5)
			(island_removal_mode 0)
		)
		(polygon
			(pts
				(arc
					(start 4.318 -219.075)
					(mid 2.54 -219.075)
					(end 4.318 -219.075)
				)
			)
		)
	)
	(zone
		(layers "In1.Cu" "In4.Cu")
		(hatch none 0.5)
		(connect_pads
			(clearance 0)
		)
		(min_thickness 0.25)
		(keepout
			(tracks not_allowed)
			(vias allowed)
			(pads allowed)
			(copperpour not_allowed)
			(footprints allowed)
		)
		(placement
			(enabled no)
			(sheetname "")
		)
		(fill yes
			(thermal_gap 0.5)
			(thermal_bridge_width 0.5)
			(island_removal_mode 0)
		)
		(polygon
			(pts
				(arc
					(start 29.977588 -13.2842)
					(mid 28.199588 -13.2842)
					(end 29.977588 -13.2842)
				)
			)
		)
	)
	(zone
		(layers "In1.Cu" "In4.Cu")
		(hatch none 0.5)
		(connect_pads
			(clearance 0)
		)
		(min_thickness 0.25)
		(keepout
			(tracks not_allowed)
			(vias allowed)
			(pads allowed)
			(copperpour not_allowed)
			(footprints allowed)
		)
		(placement
			(enabled no)
			(sheetname "")
		)
		(fill yes
			(thermal_gap 0.5)
			(thermal_bridge_width 0.5)
			(island_removal_mode 0)
		)
		(polygon
			(pts
				(arc
					(start 18.923 -108.458)
					(mid 17.145 -108.458)
					(end 18.923 -108.458)
				)
			)
		)
	)
	(zone
		(layers "In1.Cu" "In4.Cu")
		(hatch none 0.5)
		(connect_pads
			(clearance 0)
		)
		(min_thickness 0.25)
		(keepout
			(tracks not_allowed)
			(vias allowed)
			(pads allowed)
			(copperpour not_allowed)
			(footprints allowed)
		)
		(placement
			(enabled no)
			(sheetname "")
		)
		(fill yes
			(thermal_gap 0.5)
			(thermal_bridge_width 0.5)
			(island_removal_mode 0)
		)
		(polygon
			(pts
				(arc
					(start 5.715 -281.2542)
					(mid 3.937 -281.2542)
					(end 5.715 -281.2542)
				)
			)
		)
	)
	(zone
		(layers "In1.Cu" "In4.Cu")
		(hatch none 0.5)
		(connect_pads
			(clearance 0)
		)
		(min_thickness 0.25)
		(keepout
			(tracks not_allowed)
			(vias allowed)
			(pads allowed)
			(copperpour not_allowed)
			(footprints allowed)
		)
		(placement
			(enabled no)
			(sheetname "")
		)
		(fill yes
			(thermal_gap 0.5)
			(thermal_bridge_width 0.5)
			(island_removal_mode 0)
		)
		(polygon
			(pts
				(arc
					(start 6.477 -280.4922)
					(mid 4.699 -280.4922)
					(end 6.477 -280.4922)
				)
			)
		)
	)
	(zone
		(layers "In1.Cu" "In4.Cu")
		(hatch none 0.5)
		(connect_pads
			(clearance 0)
		)
		(min_thickness 0.25)
		(keepout
			(tracks not_allowed)
			(vias allowed)
			(pads allowed)
			(copperpour not_allowed)
			(footprints allowed)
		)
		(placement
			(enabled no)
			(sheetname "")
		)
		(fill yes
			(thermal_gap 0.5)
			(thermal_bridge_width 0.5)
			(island_removal_mode 0)
		)
		(polygon
			(pts
				(arc
					(start 14.351 -87.883238)
					(mid 12.573 -87.883238)
					(end 14.351 -87.883238)
				)
			)
		)
	)
	(zone
		(layers "In1.Cu" "In4.Cu")
		(hatch none 0.5)
		(connect_pads
			(clearance 0)
		)
		(min_thickness 0.25)
		(keepout
			(tracks not_allowed)
			(vias allowed)
			(pads allowed)
			(copperpour not_allowed)
			(footprints allowed)
		)
		(placement
			(enabled no)
			(sheetname "")
		)
		(fill yes
			(thermal_gap 0.5)
			(thermal_bridge_width 0.5)
			(island_removal_mode 0)
		)
		(polygon
			(pts
				(arc
					(start 29.215588 -11.3792)
					(mid 27.437588 -11.3792)
					(end 29.215588 -11.3792)
				)
			)
		)
	)
	(zone
		(layers "In1.Cu" "In4.Cu")
		(hatch none 0.5)
		(connect_pads
			(clearance 0)
		)
		(min_thickness 0.25)
		(keepout
			(tracks not_allowed)
			(vias allowed)
			(pads allowed)
			(copperpour not_allowed)
			(footprints allowed)
		)
		(placement
			(enabled no)
			(sheetname "")
		)
		(fill yes
			(thermal_gap 0.5)
			(thermal_bridge_width 0.5)
			(island_removal_mode 0)
		)
		(polygon
			(pts
				(arc
					(start 47.334932 -91.38666)
					(mid 45.556932 -91.38666)
					(end 47.334932 -91.38666)
				)
			)
		)
	)
	(zone
		(layers "In1.Cu" "In4.Cu")
		(hatch none 0.5)
		(connect_pads
			(clearance 0)
		)
		(min_thickness 0.25)
		(keepout
			(tracks not_allowed)
			(vias allowed)
			(pads allowed)
			(copperpour not_allowed)
			(footprints allowed)
		)
		(placement
			(enabled no)
			(sheetname "")
		)
		(fill yes
			(thermal_gap 0.5)
			(thermal_bridge_width 0.5)
			(island_removal_mode 0)
		)
		(polygon
			(pts
				(arc
					(start 5.334 -91.878912)
					(mid 3.556 -91.878912)
					(end 5.334 -91.878912)
				)
			)
		)
	)
	(zone
		(layers "In1.Cu" "In4.Cu")
		(hatch none 0.5)
		(connect_pads
			(clearance 0)
		)
		(min_thickness 0.25)
		(keepout
			(tracks not_allowed)
			(vias allowed)
			(pads allowed)
			(copperpour not_allowed)
			(footprints allowed)
		)
		(placement
			(enabled no)
			(sheetname "")
		)
		(fill yes
			(thermal_gap 0.5)
			(thermal_bridge_width 0.5)
			(island_removal_mode 0)
		)
		(polygon
			(pts
				(arc
					(start 9.663176 -48.90516)
					(mid 7.885176 -48.90516)
					(end 9.663176 -48.90516)
				)
			)
		)
	)
	(zone
		(layers "In1.Cu" "In4.Cu")
		(hatch none 0.5)
		(connect_pads
			(clearance 0)
		)
		(min_thickness 0.25)
		(keepout
			(tracks not_allowed)
			(vias allowed)
			(pads allowed)
			(copperpour not_allowed)
			(footprints allowed)
		)
		(placement
			(enabled no)
			(sheetname "")
		)
		(fill yes
			(thermal_gap 0.5)
			(thermal_bridge_width 0.5)
			(island_removal_mode 0)
		)
		(polygon
			(pts
				(arc
					(start 12.949174 -79.721202)
					(mid 11.171174 -79.721202)
					(end 12.949174 -79.721202)
				)
			)
		)
	)
	(zone
		(layers "In1.Cu" "In4.Cu")
		(hatch none 0.5)
		(connect_pads
			(clearance 0)
		)
		(min_thickness 0.25)
		(keepout
			(tracks not_allowed)
			(vias allowed)
			(pads allowed)
			(copperpour not_allowed)
			(footprints allowed)
		)
		(placement
			(enabled no)
			(sheetname "")
		)
		(fill yes
			(thermal_gap 0.5)
			(thermal_bridge_width 0.5)
			(island_removal_mode 0)
		)
		(polygon
			(pts
				(arc
					(start 47.284132 -61.856112)
					(mid 45.506132 -61.856112)
					(end 47.284132 -61.856112)
				)
			)
		)
	)
	(zone
		(layers "In1.Cu" "In4.Cu")
		(hatch none 0.5)
		(connect_pads
			(clearance 0)
		)
		(min_thickness 0.25)
		(keepout
			(tracks not_allowed)
			(vias allowed)
			(pads allowed)
			(copperpour not_allowed)
			(footprints allowed)
		)
		(placement
			(enabled no)
			(sheetname "")
		)
		(fill yes
			(thermal_gap 0.5)
			(thermal_bridge_width 0.5)
			(island_removal_mode 0)
		)
		(polygon
			(pts
				(arc
					(start 37.6174 -85.6234)
					(mid 35.8394 -85.6234)
					(end 37.6174 -85.6234)
				)
			)
		)
	)
	(zone
		(layers "In1.Cu" "In4.Cu")
		(hatch none 0.5)
		(connect_pads
			(clearance 0)
		)
		(min_thickness 0.25)
		(keepout
			(tracks not_allowed)
			(vias allowed)
			(pads allowed)
			(copperpour not_allowed)
			(footprints allowed)
		)
		(placement
			(enabled no)
			(sheetname "")
		)
		(fill yes
			(thermal_gap 0.5)
			(thermal_bridge_width 0.5)
			(island_removal_mode 0)
		)
		(polygon
			(pts
				(arc
					(start 42.941748 -58.570622)
					(mid 41.163748 -58.570622)
					(end 42.941748 -58.570622)
				)
			)
		)
	)
	(zone
		(layers "In1.Cu" "In4.Cu")
		(hatch none 0.5)
		(connect_pads
			(clearance 0)
		)
		(min_thickness 0.25)
		(keepout
			(tracks not_allowed)
			(vias allowed)
			(pads allowed)
			(copperpour not_allowed)
			(footprints allowed)
		)
		(placement
			(enabled no)
			(sheetname "")
		)
		(fill yes
			(thermal_gap 0.5)
			(thermal_bridge_width 0.5)
			(island_removal_mode 0)
		)
		(polygon
			(pts
				(arc
					(start 42.000932 -263.68629)
					(mid 40.222932 -263.68629)
					(end 42.000932 -263.68629)
				)
			)
		)
	)
	(zone
		(layers "In1.Cu" "In4.Cu")
		(hatch none 0.5)
		(connect_pads
			(clearance 0)
		)
		(min_thickness 0.25)
		(keepout
			(tracks not_allowed)
			(vias allowed)
			(pads allowed)
			(copperpour not_allowed)
			(footprints allowed)
		)
		(placement
			(enabled no)
			(sheetname "")
		)
		(fill yes
			(thermal_gap 0.5)
			(thermal_bridge_width 0.5)
			(island_removal_mode 0)
		)
		(polygon
			(pts
				(arc
					(start 42.259758 -234.061)
					(mid 40.481758 -234.061)
					(end 42.259758 -234.061)
				)
			)
		)
	)
	(zone
		(layers "In1.Cu" "In4.Cu")
		(hatch none 0.5)
		(connect_pads
			(clearance 0)
		)
		(min_thickness 0.25)
		(keepout
			(tracks not_allowed)
			(vias allowed)
			(pads allowed)
			(copperpour not_allowed)
			(footprints allowed)
		)
		(placement
			(enabled no)
			(sheetname "")
		)
		(fill yes
			(thermal_gap 0.5)
			(thermal_bridge_width 0.5)
			(island_removal_mode 0)
		)
		(polygon
			(pts
				(arc
					(start 10.020808 -20.409916)
					(mid 7.379208 -20.409916)
					(end 10.020808 -20.409916)
				)
			)
		)
	)
	(zone
		(layers "In1.Cu" "In4.Cu")
		(hatch none 0.5)
		(connect_pads
			(clearance 0)
		)
		(min_thickness 0.25)
		(keepout
			(tracks not_allowed)
			(vias allowed)
			(pads allowed)
			(copperpour not_allowed)
			(footprints allowed)
		)
		(placement
			(enabled no)
			(sheetname "")
		)
		(fill yes
			(thermal_gap 0.5)
			(thermal_bridge_width 0.5)
			(island_removal_mode 0)
		)
		(polygon
			(pts
				(arc
					(start 37.229288 -278.13)
					(mid 35.451288 -278.13)
					(end 37.229288 -278.13)
				)
			)
		)
	)
	(zone
		(layers "In1.Cu" "In4.Cu")
		(hatch none 0.5)
		(connect_pads
			(clearance 0)
		)
		(min_thickness 0.25)
		(keepout
			(tracks not_allowed)
			(vias allowed)
			(pads allowed)
			(copperpour not_allowed)
			(footprints allowed)
		)
		(placement
			(enabled no)
			(sheetname "")
		)
		(fill yes
			(thermal_gap 0.5)
			(thermal_bridge_width 0.5)
			(island_removal_mode 0)
		)
		(polygon
			(pts
				(arc
					(start 12.166346 -38.014656)
					(mid 10.388346 -38.014656)
					(end 12.166346 -38.014656)
				)
			)
		)
	)
	(zone
		(layers "In1.Cu" "In4.Cu")
		(hatch none 0.5)
		(connect_pads
			(clearance 0)
		)
		(min_thickness 0.25)
		(keepout
			(tracks not_allowed)
			(vias allowed)
			(pads allowed)
			(copperpour not_allowed)
			(footprints allowed)
		)
		(placement
			(enabled no)
			(sheetname "")
		)
		(fill yes
			(thermal_gap 0.5)
			(thermal_bridge_width 0.5)
			(island_removal_mode 0)
		)
		(polygon
			(pts
				(arc
					(start 46.776132 -242.8494)
					(mid 44.998132 -242.8494)
					(end 46.776132 -242.8494)
				)
			)
		)
	)
	(zone
		(layers "In1.Cu" "In4.Cu")
		(hatch none 0.5)
		(connect_pads
			(clearance 0)
		)
		(min_thickness 0.25)
		(keepout
			(tracks not_allowed)
			(vias allowed)
			(pads allowed)
			(copperpour not_allowed)
			(footprints allowed)
		)
		(placement
			(enabled no)
			(sheetname "")
		)
		(fill yes
			(thermal_gap 0.5)
			(thermal_bridge_width 0.5)
			(island_removal_mode 0)
		)
		(polygon
			(pts
				(arc
					(start 14.720824 -58.474356)
					(mid 12.942824 -58.474356)
					(end 14.720824 -58.474356)
				)
			)
		)
	)
	(zone
		(layers "In1.Cu" "In4.Cu")
		(hatch none 0.5)
		(connect_pads
			(clearance 0)
		)
		(min_thickness 0.25)
		(keepout
			(tracks not_allowed)
			(vias allowed)
			(pads allowed)
			(copperpour not_allowed)
			(footprints allowed)
		)
		(placement
			(enabled no)
			(sheetname "")
		)
		(fill yes
			(thermal_gap 0.5)
			(thermal_bridge_width 0.5)
			(island_removal_mode 0)
		)
		(polygon
			(pts
				(arc
					(start 13.196824 -58.474356)
					(mid 11.418824 -58.474356)
					(end 13.196824 -58.474356)
				)
			)
		)
	)
	(zone
		(layers "In1.Cu" "In4.Cu")
		(hatch none 0.5)
		(connect_pads
			(clearance 0)
		)
		(min_thickness 0.25)
		(keepout
			(tracks not_allowed)
			(vias allowed)
			(pads allowed)
			(copperpour not_allowed)
			(footprints allowed)
		)
		(placement
			(enabled no)
			(sheetname "")
		)
		(fill yes
			(thermal_gap 0.5)
			(thermal_bridge_width 0.5)
			(island_removal_mode 0)
		)
		(polygon
			(pts
				(arc
					(start 42.259758 -234.823)
					(mid 40.481758 -234.823)
					(end 42.259758 -234.823)
				)
			)
		)
	)
	(zone
		(layers "In1.Cu" "In4.Cu")
		(hatch none 0.5)
		(connect_pads
			(clearance 0)
		)
		(min_thickness 0.25)
		(keepout
			(tracks not_allowed)
			(vias allowed)
			(pads allowed)
			(copperpour not_allowed)
			(footprints allowed)
		)
		(placement
			(enabled no)
			(sheetname "")
		)
		(fill yes
			(thermal_gap 0.5)
			(thermal_bridge_width 0.5)
			(island_removal_mode 0)
		)
		(polygon
			(pts
				(arc
					(start 48.300132 -242.8494)
					(mid 46.522132 -242.8494)
					(end 48.300132 -242.8494)
				)
			)
		)
	)
	(zone
		(layers "In1.Cu" "In4.Cu")
		(hatch none 0.5)
		(connect_pads
			(clearance 0)
		)
		(min_thickness 0.25)
		(keepout
			(tracks not_allowed)
			(vias allowed)
			(pads allowed)
			(copperpour not_allowed)
			(footprints allowed)
		)
		(placement
			(enabled no)
			(sheetname "")
		)
		(fill yes
			(thermal_gap 0.5)
			(thermal_bridge_width 0.5)
			(island_removal_mode 0)
		)
		(polygon
			(pts
				(arc
					(start 7.15899 -263.8552)
					(mid 5.38099 -263.8552)
					(end 7.15899 -263.8552)
				)
			)
		)
	)
	(zone
		(layers "In1.Cu" "In4.Cu")
		(hatch none 0.5)
		(connect_pads
			(clearance 0)
		)
		(min_thickness 0.25)
		(keepout
			(tracks not_allowed)
			(vias allowed)
			(pads allowed)
			(copperpour not_allowed)
			(footprints allowed)
		)
		(placement
			(enabled no)
			(sheetname "")
		)
		(fill yes
			(thermal_gap 0.5)
			(thermal_bridge_width 0.5)
			(island_removal_mode 0)
		)
		(polygon
			(pts
				(arc
					(start 45.100748 -79.886048)
					(mid 43.322748 -79.886048)
					(end 45.100748 -79.886048)
				)
			)
		)
	)
	(zone
		(layers "In1.Cu" "In4.Cu")
		(hatch none 0.5)
		(connect_pads
			(clearance 0)
		)
		(min_thickness 0.25)
		(keepout
			(tracks not_allowed)
			(vias allowed)
			(pads allowed)
			(copperpour not_allowed)
			(footprints allowed)
		)
		(placement
			(enabled no)
			(sheetname "")
		)
		(fill yes
			(thermal_gap 0.5)
			(thermal_bridge_width 0.5)
			(island_removal_mode 0)
		)
		(polygon
			(pts
				(arc
					(start 20.381722 -29.591)
					(mid 18.603722 -29.591)
					(end 20.381722 -29.591)
				)
			)
		)
	)
	(zone
		(layers "In1.Cu" "In4.Cu")
		(hatch none 0.5)
		(connect_pads
			(clearance 0)
		)
		(min_thickness 0.25)
		(keepout
			(tracks not_allowed)
			(vias allowed)
			(pads allowed)
			(copperpour not_allowed)
			(footprints allowed)
		)
		(placement
			(enabled no)
			(sheetname "")
		)
		(fill yes
			(thermal_gap 0.5)
			(thermal_bridge_width 0.5)
			(island_removal_mode 0)
		)
		(polygon
			(pts
				(arc
					(start 40.401748 -59.078622)
					(mid 38.623748 -59.078622)
					(end 40.401748 -59.078622)
				)
			)
		)
	)
	(zone
		(layers "In1.Cu" "In4.Cu")
		(hatch none 0.5)
		(connect_pads
			(clearance 0)
		)
		(min_thickness 0.25)
		(keepout
			(tracks not_allowed)
			(vias allowed)
			(pads allowed)
			(copperpour not_allowed)
			(footprints allowed)
		)
		(placement
			(enabled no)
			(sheetname "")
		)
		(fill yes
			(thermal_gap 0.5)
			(thermal_bridge_width 0.5)
			(island_removal_mode 0)
		)
		(polygon
			(pts
				(arc
					(start 14.351 -92.709238)
					(mid 12.573 -92.709238)
					(end 14.351 -92.709238)
				)
			)
		)
	)
	(zone
		(layers "In1.Cu" "In4.Cu")
		(hatch none 0.5)
		(connect_pads
			(clearance 0)
		)
		(min_thickness 0.25)
		(keepout
			(tracks not_allowed)
			(vias allowed)
			(pads allowed)
			(copperpour not_allowed)
			(footprints allowed)
		)
		(placement
			(enabled no)
			(sheetname "")
		)
		(fill yes
			(thermal_gap 0.5)
			(thermal_bridge_width 0.5)
			(island_removal_mode 0)
		)
		(polygon
			(pts
				(arc
					(start 46.725332 -281.092148)
					(mid 44.947332 -281.092148)
					(end 46.725332 -281.092148)
				)
			)
		)
	)
	(zone
		(layers "In1.Cu" "In4.Cu")
		(hatch none 0.5)
		(connect_pads
			(clearance 0)
		)
		(min_thickness 0.25)
		(keepout
			(tracks not_allowed)
			(vias allowed)
			(pads allowed)
			(copperpour not_allowed)
			(footprints allowed)
		)
		(placement
			(enabled no)
			(sheetname "")
		)
		(fill yes
			(thermal_gap 0.5)
			(thermal_bridge_width 0.5)
			(island_removal_mode 0)
		)
		(polygon
			(pts
				(arc
					(start 42.840656 -48.042322)
					(mid 41.062656 -48.042322)
					(end 42.840656 -48.042322)
				)
			)
		)
	)
	(zone
		(layers "In1.Cu" "In4.Cu")
		(hatch none 0.5)
		(connect_pads
			(clearance 0)
		)
		(min_thickness 0.25)
		(keepout
			(tracks not_allowed)
			(vias allowed)
			(pads allowed)
			(copperpour not_allowed)
			(footprints allowed)
		)
		(placement
			(enabled no)
			(sheetname "")
		)
		(fill yes
			(thermal_gap 0.5)
			(thermal_bridge_width 0.5)
			(island_removal_mode 0)
		)
		(polygon
			(pts
				(arc
					(start 39.756588 -59.078622)
					(mid 37.978588 -59.078622)
					(end 39.756588 -59.078622)
				)
			)
		)
	)
	(zone
		(layers "In1.Cu" "In4.Cu")
		(hatch none 0.5)
		(connect_pads
			(clearance 0)
		)
		(min_thickness 0.25)
		(keepout
			(tracks not_allowed)
			(vias allowed)
			(pads allowed)
			(copperpour not_allowed)
			(footprints allowed)
		)
		(placement
			(enabled no)
			(sheetname "")
		)
		(fill yes
			(thermal_gap 0.5)
			(thermal_bridge_width 0.5)
			(island_removal_mode 0)
		)
		(polygon
			(pts
				(arc
					(start 29.215588 -12.6492)
					(mid 27.437588 -12.6492)
					(end 29.215588 -12.6492)
				)
			)
		)
	)
	(zone
		(layers "In1.Cu" "In4.Cu")
		(hatch none 0.5)
		(connect_pads
			(clearance 0)
		)
		(min_thickness 0.25)
		(keepout
			(tracks not_allowed)
			(vias allowed)
			(pads allowed)
			(copperpour not_allowed)
			(footprints allowed)
		)
		(placement
			(enabled no)
			(sheetname "")
		)
		(fill yes
			(thermal_gap 0.5)
			(thermal_bridge_width 0.5)
			(island_removal_mode 0)
		)
		(polygon
			(pts
				(arc
					(start 4.594098 -243.513864)
					(mid 2.816098 -243.513864)
					(end 4.594098 -243.513864)
				)
			)
		)
	)
	(zone
		(layers "In1.Cu" "In4.Cu")
		(hatch none 0.5)
		(connect_pads
			(clearance 0)
		)
		(min_thickness 0.25)
		(keepout
			(tracks not_allowed)
			(vias allowed)
			(pads allowed)
			(copperpour not_allowed)
			(footprints allowed)
		)
		(placement
			(enabled no)
			(sheetname "")
		)
		(fill yes
			(thermal_gap 0.5)
			(thermal_bridge_width 0.5)
			(island_removal_mode 0)
		)
		(polygon
			(pts
				(arc
					(start 16.17599 -265.121136)
					(mid 14.39799 -265.121136)
					(end 16.17599 -265.121136)
				)
			)
		)
	)
	(zone
		(layers "In1.Cu" "In4.Cu")
		(hatch none 0.5)
		(connect_pads
			(clearance 0)
		)
		(min_thickness 0.25)
		(keepout
			(tracks not_allowed)
			(vias allowed)
			(pads allowed)
			(copperpour not_allowed)
			(footprints allowed)
		)
		(placement
			(enabled no)
			(sheetname "")
		)
		(fill yes
			(thermal_gap 0.5)
			(thermal_bridge_width 0.5)
			(island_removal_mode 0)
		)
		(polygon
			(pts
				(arc
					(start 38.857428 -80.321912)
					(mid 37.079428 -80.321912)
					(end 38.857428 -80.321912)
				)
			)
		)
	)
	(zone
		(layers "In1.Cu" "In4.Cu")
		(hatch none 0.5)
		(connect_pads
			(clearance 0)
		)
		(min_thickness 0.25)
		(keepout
			(tracks not_allowed)
			(vias allowed)
			(pads allowed)
			(copperpour not_allowed)
			(footprints allowed)
		)
		(placement
			(enabled no)
			(sheetname "")
		)
		(fill yes
			(thermal_gap 0.5)
			(thermal_bridge_width 0.5)
			(island_removal_mode 0)
		)
		(polygon
			(pts
				(arc
					(start 17.46631 -265.121136)
					(mid 15.68831 -265.121136)
					(end 17.46631 -265.121136)
				)
			)
		)
	)
	(zone
		(layers "In1.Cu" "In4.Cu")
		(hatch none 0.5)
		(connect_pads
			(clearance 0)
		)
		(min_thickness 0.25)
		(keepout
			(tracks not_allowed)
			(vias allowed)
			(pads allowed)
			(copperpour not_allowed)
			(footprints allowed)
		)
		(placement
			(enabled no)
			(sheetname "")
		)
		(fill yes
			(thermal_gap 0.5)
			(thermal_bridge_width 0.5)
			(island_removal_mode 0)
		)
		(polygon
			(pts
				(arc
					(start 34.031428 -80.067912)
					(mid 32.253428 -80.067912)
					(end 34.031428 -80.067912)
				)
			)
		)
	)
	(zone
		(layers "In1.Cu" "In4.Cu")
		(hatch none 0.5)
		(connect_pads
			(clearance 0)
		)
		(min_thickness 0.25)
		(keepout
			(tracks not_allowed)
			(vias allowed)
			(pads allowed)
			(copperpour not_allowed)
			(footprints allowed)
		)
		(placement
			(enabled no)
			(sheetname "")
		)
		(fill yes
			(thermal_gap 0.5)
			(thermal_bridge_width 0.5)
			(island_removal_mode 0)
		)
		(polygon
			(pts
				(arc
					(start 37.301932 -244.31371)
					(mid 35.523932 -244.31371)
					(end 37.301932 -244.31371)
				)
			)
		)
	)
	(zone
		(layers "In1.Cu" "In4.Cu")
		(hatch none 0.5)
		(connect_pads
			(clearance 0)
		)
		(min_thickness 0.25)
		(keepout
			(tracks not_allowed)
			(vias allowed)
			(pads allowed)
			(copperpour not_allowed)
			(footprints allowed)
		)
		(placement
			(enabled no)
			(sheetname "")
		)
		(fill yes
			(thermal_gap 0.5)
			(thermal_bridge_width 0.5)
			(island_removal_mode 0)
		)
		(polygon
			(pts
				(arc
					(start 38.095428 -264.922)
					(mid 36.317428 -264.922)
					(end 38.095428 -264.922)
				)
			)
		)
	)
	(zone
		(layers "In1.Cu" "In4.Cu")
		(hatch none 0.5)
		(connect_pads
			(clearance 0)
		)
		(min_thickness 0.25)
		(keepout
			(tracks not_allowed)
			(vias allowed)
			(pads allowed)
			(copperpour not_allowed)
			(footprints allowed)
		)
		(placement
			(enabled no)
			(sheetname "")
		)
		(fill yes
			(thermal_gap 0.5)
			(thermal_bridge_width 0.5)
			(island_removal_mode 0)
		)
		(polygon
			(pts
				(arc
					(start 38.627304 -37.883846)
					(mid 36.849304 -37.883846)
					(end 38.627304 -37.883846)
				)
			)
		)
	)
	(zone
		(layers "In1.Cu" "In4.Cu")
		(hatch none 0.5)
		(connect_pads
			(clearance 0)
		)
		(min_thickness 0.25)
		(keepout
			(tracks not_allowed)
			(vias allowed)
			(pads allowed)
			(copperpour not_allowed)
			(footprints allowed)
		)
		(placement
			(enabled no)
			(sheetname "")
		)
		(fill yes
			(thermal_gap 0.5)
			(thermal_bridge_width 0.5)
			(island_removal_mode 0)
		)
		(polygon
			(pts
				(arc
					(start 41.238932 -83.623912)
					(mid 39.460932 -83.623912)
					(end 41.238932 -83.623912)
				)
			)
		)
	)
	(zone
		(layers "In1.Cu" "In4.Cu")
		(hatch none 0.5)
		(connect_pads
			(clearance 0)
		)
		(min_thickness 0.25)
		(keepout
			(tracks not_allowed)
			(vias allowed)
			(pads allowed)
			(copperpour not_allowed)
			(footprints allowed)
		)
		(placement
			(enabled no)
			(sheetname "")
		)
		(fill yes
			(thermal_gap 0.5)
			(thermal_bridge_width 0.5)
			(island_removal_mode 0)
		)
		(polygon
			(pts
				(arc
					(start 7.693914 -243.67871)
					(mid 5.915914 -243.67871)
					(end 7.693914 -243.67871)
				)
			)
		)
	)
	(zone
		(layers "In1.Cu" "In4.Cu")
		(hatch none 0.5)
		(connect_pads
			(clearance 0)
		)
		(min_thickness 0.25)
		(keepout
			(tracks not_allowed)
			(vias allowed)
			(pads allowed)
			(copperpour not_allowed)
			(footprints allowed)
		)
		(placement
			(enabled no)
			(sheetname "")
		)
		(fill yes
			(thermal_gap 0.5)
			(thermal_bridge_width 0.5)
			(island_removal_mode 0)
		)
		(polygon
			(pts
				(arc
					(start 48.046132 -61.856112)
					(mid 46.268132 -61.856112)
					(end 48.046132 -61.856112)
				)
			)
		)
	)
	(zone
		(layers "In1.Cu" "In4.Cu")
		(hatch none 0.5)
		(connect_pads
			(clearance 0)
		)
		(min_thickness 0.25)
		(keepout
			(tracks not_allowed)
			(vias allowed)
			(pads allowed)
			(copperpour not_allowed)
			(footprints allowed)
		)
		(placement
			(enabled no)
			(sheetname "")
		)
		(fill yes
			(thermal_gap 0.5)
			(thermal_bridge_width 0.5)
			(island_removal_mode 0)
		)
		(polygon
			(pts
				(arc
					(start 48.096932 -92.02166)
					(mid 46.318932 -92.02166)
					(end 48.096932 -92.02166)
				)
			)
		)
	)
	(zone
		(layers "In1.Cu" "In4.Cu")
		(hatch none 0.5)
		(connect_pads
			(clearance 0)
		)
		(min_thickness 0.25)
		(keepout
			(tracks not_allowed)
			(vias allowed)
			(pads allowed)
			(copperpour not_allowed)
			(footprints allowed)
		)
		(placement
			(enabled no)
			(sheetname "")
		)
		(fill yes
			(thermal_gap 0.5)
			(thermal_bridge_width 0.5)
			(island_removal_mode 0)
		)
		(polygon
			(pts
				(arc
					(start 20.5486 -196.85)
					(mid 18.7706 -196.85)
					(end 20.5486 -196.85)
				)
			)
		)
	)
	(zone
		(layers "In1.Cu" "In4.Cu")
		(hatch none 0.5)
		(connect_pads
			(clearance 0)
		)
		(min_thickness 0.25)
		(keepout
			(tracks not_allowed)
			(vias allowed)
			(pads allowed)
			(copperpour not_allowed)
			(footprints allowed)
		)
		(placement
			(enabled no)
			(sheetname "")
		)
		(fill yes
			(thermal_gap 0.5)
			(thermal_bridge_width 0.5)
			(island_removal_mode 0)
		)
		(polygon
			(pts
				(arc
					(start 36.656772 -58.278776)
					(mid 34.878772 -58.278776)
					(end 36.656772 -58.278776)
				)
			)
		)
	)
	(zone
		(layers "In1.Cu" "In4.Cu")
		(hatch none 0.5)
		(connect_pads
			(clearance 0)
		)
		(min_thickness 0.25)
		(keepout
			(tracks not_allowed)
			(vias allowed)
			(pads allowed)
			(copperpour not_allowed)
			(footprints allowed)
		)
		(placement
			(enabled no)
			(sheetname "")
		)
		(fill yes
			(thermal_gap 0.5)
			(thermal_bridge_width 0.5)
			(island_removal_mode 0)
		)
		(polygon
			(pts
				(arc
					(start 29.977588 -10.1092)
					(mid 28.199588 -10.1092)
					(end 29.977588 -10.1092)
				)
			)
		)
	)
	(zone
		(layers "In1.Cu" "In4.Cu")
		(hatch none 0.5)
		(connect_pads
			(clearance 0)
		)
		(min_thickness 0.25)
		(keepout
			(tracks not_allowed)
			(vias allowed)
			(pads allowed)
			(copperpour not_allowed)
			(footprints allowed)
		)
		(placement
			(enabled no)
			(sheetname "")
		)
		(fill yes
			(thermal_gap 0.5)
			(thermal_bridge_width 0.5)
			(island_removal_mode 0)
		)
		(polygon
			(pts
				(arc
					(start 29.977588 -12.6492)
					(mid 28.199588 -12.6492)
					(end 29.977588 -12.6492)
				)
			)
		)
	)
	(zone
		(layers "In1.Cu" "In4.Cu")
		(hatch none 0.5)
		(connect_pads
			(clearance 0)
		)
		(min_thickness 0.25)
		(keepout
			(tracks not_allowed)
			(vias allowed)
			(pads allowed)
			(copperpour not_allowed)
			(footprints allowed)
		)
		(placement
			(enabled no)
			(sheetname "")
		)
		(fill yes
			(thermal_gap 0.5)
			(thermal_bridge_width 0.5)
			(island_removal_mode 0)
		)
		(polygon
			(pts
				(arc
					(start 11.19759 -264.4902)
					(mid 9.41959 -264.4902)
					(end 11.19759 -264.4902)
				)
			)
		)
	)
	(zone
		(layers "In1.Cu" "In4.Cu")
		(hatch none 0.5)
		(connect_pads
			(clearance 0)
		)
		(min_thickness 0.25)
		(keepout
			(tracks not_allowed)
			(vias allowed)
			(pads allowed)
			(copperpour not_allowed)
			(footprints allowed)
		)
		(placement
			(enabled no)
			(sheetname "")
		)
		(fill yes
			(thermal_gap 0.5)
			(thermal_bridge_width 0.5)
			(island_removal_mode 0)
		)
		(polygon
			(pts
				(arc
					(start 40.554148 -244.478556)
					(mid 38.776148 -244.478556)
					(end 40.554148 -244.478556)
				)
			)
		)
	)
	(zone
		(layers "In1.Cu" "In4.Cu")
		(hatch none 0.5)
		(connect_pads
			(clearance 0)
		)
		(min_thickness 0.25)
		(keepout
			(tracks not_allowed)
			(vias allowed)
			(pads allowed)
			(copperpour not_allowed)
			(footprints allowed)
		)
		(placement
			(enabled no)
			(sheetname "")
		)
		(fill yes
			(thermal_gap 0.5)
			(thermal_bridge_width 0.5)
			(island_removal_mode 0)
		)
		(polygon
			(pts
				(arc
					(start 5.884418 -58.278776)
					(mid 4.106418 -58.278776)
					(end 5.884418 -58.278776)
				)
			)
		)
	)
	(zone
		(layers "In1.Cu" "In4.Cu")
		(hatch none 0.5)
		(connect_pads
			(clearance 0)
		)
		(min_thickness 0.25)
		(keepout
			(tracks not_allowed)
			(vias allowed)
			(pads allowed)
			(copperpour not_allowed)
			(footprints allowed)
		)
		(placement
			(enabled no)
			(sheetname "")
		)
		(fill yes
			(thermal_gap 0.5)
			(thermal_bridge_width 0.5)
			(island_removal_mode 0)
		)
		(polygon
			(pts
				(arc
					(start 42.259758 -232.029)
					(mid 40.481758 -232.029)
					(end 42.259758 -232.029)
				)
			)
		)
	)
	(zone
		(layers "In1.Cu" "In4.Cu")
		(hatch none 0.5)
		(connect_pads
			(clearance 0)
		)
		(min_thickness 0.25)
		(keepout
			(tracks not_allowed)
			(vias allowed)
			(pads allowed)
			(copperpour not_allowed)
			(footprints allowed)
		)
		(placement
			(enabled no)
			(sheetname "")
		)
		(fill yes
			(thermal_gap 0.5)
			(thermal_bridge_width 0.5)
			(island_removal_mode 0)
		)
		(polygon
			(pts
				(arc
					(start 37.6174 -86.316312)
					(mid 35.8394 -86.316312)
					(end 37.6174 -86.316312)
				)
			)
		)
	)
	(zone
		(layers "In1.Cu" "In4.Cu")
		(hatch none 0.5)
		(connect_pads
			(clearance 0)
		)
		(min_thickness 0.25)
		(keepout
			(tracks not_allowed)
			(vias allowed)
			(pads allowed)
			(copperpour not_allowed)
			(footprints allowed)
		)
		(placement
			(enabled no)
			(sheetname "")
		)
		(fill yes
			(thermal_gap 0.5)
			(thermal_bridge_width 0.5)
			(island_removal_mode 0)
		)
		(polygon
			(pts
				(arc
					(start 35.991292 -58.913776)
					(mid 34.213292 -58.913776)
					(end 35.991292 -58.913776)
				)
			)
		)
	)
	(zone
		(layers "In1.Cu" "In4.Cu")
		(hatch none 0.5)
		(connect_pads
			(clearance 0)
		)
		(min_thickness 0.25)
		(keepout
			(tracks not_allowed)
			(vias allowed)
			(pads allowed)
			(copperpour not_allowed)
			(footprints allowed)
		)
		(placement
			(enabled no)
			(sheetname "")
		)
		(fill yes
			(thermal_gap 0.5)
			(thermal_bridge_width 0.5)
			(island_removal_mode 0)
		)
		(polygon
			(pts
				(arc
					(start 4.594098 -242.878864)
					(mid 2.816098 -242.878864)
					(end 4.594098 -242.878864)
				)
			)
		)
	)
	(zone
		(layers "In1.Cu" "In4.Cu")
		(hatch none 0.5)
		(connect_pads
			(clearance 0)
		)
		(min_thickness 0.25)
		(keepout
			(tracks not_allowed)
			(vias allowed)
			(pads allowed)
			(copperpour not_allowed)
			(footprints allowed)
		)
		(placement
			(enabled no)
			(sheetname "")
		)
		(fill yes
			(thermal_gap 0.5)
			(thermal_bridge_width 0.5)
			(island_removal_mode 0)
		)
		(polygon
			(pts
				(arc
					(start 14.366494 -263.68629)
					(mid 12.588494 -263.68629)
					(end 14.366494 -263.68629)
				)
			)
		)
	)
	(zone
		(layers "In1.Cu" "In4.Cu")
		(hatch none 0.5)
		(connect_pads
			(clearance 0)
		)
		(min_thickness 0.25)
		(keepout
			(tracks not_allowed)
			(vias allowed)
			(pads allowed)
			(copperpour not_allowed)
			(footprints allowed)
		)
		(placement
			(enabled no)
			(sheetname "")
		)
		(fill yes
			(thermal_gap 0.5)
			(thermal_bridge_width 0.5)
			(island_removal_mode 0)
		)
		(polygon
			(pts
				(arc
					(start 13.241274 -244.375178)
					(mid 11.463274 -244.375178)
					(end 13.241274 -244.375178)
				)
			)
		)
	)
	(zone
		(layers "In1.Cu" "In4.Cu")
		(hatch none 0.5)
		(connect_pads
			(clearance 0)
		)
		(min_thickness 0.25)
		(keepout
			(tracks not_allowed)
			(vias allowed)
			(pads allowed)
			(copperpour not_allowed)
			(footprints allowed)
		)
		(placement
			(enabled no)
			(sheetname "")
		)
		(fill yes
			(thermal_gap 0.5)
			(thermal_bridge_width 0.5)
			(island_removal_mode 0)
		)
		(polygon
			(pts
				(arc
					(start 6.26999 -79.305912)
					(mid 4.49199 -79.305912)
					(end 6.26999 -79.305912)
				)
			)
		)
	)
	(zone
		(layers "In1.Cu" "In4.Cu")
		(hatch none 0.5)
		(connect_pads
			(clearance 0)
		)
		(min_thickness 0.25)
		(keepout
			(tracks not_allowed)
			(vias allowed)
			(pads allowed)
			(copperpour not_allowed)
			(footprints allowed)
		)
		(placement
			(enabled no)
			(sheetname "")
		)
		(fill yes
			(thermal_gap 0.5)
			(thermal_bridge_width 0.5)
			(island_removal_mode 0)
		)
		(polygon
			(pts
				(arc
					(start 15.02029 -277.02891)
					(mid 13.24229 -277.02891)
					(end 15.02029 -277.02891)
				)
			)
		)
	)
	(zone
		(layers "In1.Cu" "In4.Cu")
		(hatch none 0.5)
		(connect_pads
			(clearance 0)
		)
		(min_thickness 0.25)
		(keepout
			(tracks not_allowed)
			(vias allowed)
			(pads allowed)
			(copperpour not_allowed)
			(footprints allowed)
		)
		(placement
			(enabled no)
			(sheetname "")
		)
		(fill yes
			(thermal_gap 0.5)
			(thermal_bridge_width 0.5)
			(island_removal_mode 0)
		)
		(polygon
			(pts
				(arc
					(start 14.351 -88.518238)
					(mid 12.573 -88.518238)
					(end 14.351 -88.518238)
				)
			)
		)
	)
	(zone
		(layers "In1.Cu" "In4.Cu")
		(hatch none 0.5)
		(connect_pads
			(clearance 0)
		)
		(min_thickness 0.25)
		(keepout
			(tracks not_allowed)
			(vias allowed)
			(pads allowed)
			(copperpour not_allowed)
			(footprints allowed)
		)
		(placement
			(enabled no)
			(sheetname "")
		)
		(fill yes
			(thermal_gap 0.5)
			(thermal_bridge_width 0.5)
			(island_removal_mode 0)
		)
		(polygon
			(pts
				(arc
					(start 41.238932 -84.385912)
					(mid 39.460932 -84.385912)
					(end 41.238932 -84.385912)
				)
			)
		)
	)
	(zone
		(layers "In1.Cu" "In4.Cu")
		(hatch none 0.5)
		(connect_pads
			(clearance 0)
		)
		(min_thickness 0.25)
		(keepout
			(tracks not_allowed)
			(vias allowed)
			(pads allowed)
			(copperpour not_allowed)
			(footprints allowed)
		)
		(placement
			(enabled no)
			(sheetname "")
		)
		(fill yes
			(thermal_gap 0.5)
			(thermal_bridge_width 0.5)
			(island_removal_mode 0)
		)
		(polygon
			(pts
				(arc
					(start 29.977588 -12.0142)
					(mid 28.199588 -12.0142)
					(end 29.977588 -12.0142)
				)
			)
		)
	)
	(zone
		(layers "In1.Cu" "In4.Cu")
		(hatch none 0.5)
		(connect_pads
			(clearance 0)
		)
		(min_thickness 0.25)
		(keepout
			(tracks not_allowed)
			(vias allowed)
			(pads allowed)
			(copperpour not_allowed)
			(footprints allowed)
		)
		(placement
			(enabled no)
			(sheetname "")
		)
		(fill yes
			(thermal_gap 0.5)
			(thermal_bridge_width 0.5)
			(island_removal_mode 0)
		)
		(polygon
			(pts
				(arc
					(start 5.334 -91.116912)
					(mid 3.556 -91.116912)
					(end 5.334 -91.116912)
				)
			)
		)
	)
	(zone
		(layers "In1.Cu" "In4.Cu")
		(hatch none 0.5)
		(connect_pads
			(clearance 0)
		)
		(min_thickness 0.25)
		(keepout
			(tracks not_allowed)
			(vias allowed)
			(pads allowed)
			(copperpour not_allowed)
			(footprints allowed)
		)
		(placement
			(enabled no)
			(sheetname "")
		)
		(fill yes
			(thermal_gap 0.5)
			(thermal_bridge_width 0.5)
			(island_removal_mode 0)
		)
		(polygon
			(pts
				(arc
					(start 46.32071 -293.310056)
					(mid 43.67911 -293.310056)
					(end 46.32071 -293.310056)
				)
			)
		)
	)
	(zone
		(layers "In1.Cu" "In4.Cu")
		(hatch none 0.5)
		(connect_pads
			(clearance 0)
		)
		(min_thickness 0.25)
		(keepout
			(tracks not_allowed)
			(vias allowed)
			(pads allowed)
			(copperpour not_allowed)
			(footprints allowed)
		)
		(placement
			(enabled no)
			(sheetname "")
		)
		(fill yes
			(thermal_gap 0.5)
			(thermal_bridge_width 0.5)
			(island_removal_mode 0)
		)
		(polygon
			(pts
				(arc
					(start 44.465748 -264.486136)
					(mid 42.687748 -264.486136)
					(end 44.465748 -264.486136)
				)
			)
		)
	)
	(zone
		(layers "In1.Cu" "In4.Cu")
		(hatch none 0.5)
		(connect_pads
			(clearance 0)
		)
		(min_thickness 0.25)
		(keepout
			(tracks not_allowed)
			(vias allowed)
			(pads allowed)
			(copperpour not_allowed)
			(footprints allowed)
		)
		(placement
			(enabled no)
			(sheetname "")
		)
		(fill yes
			(thermal_gap 0.5)
			(thermal_bridge_width 0.5)
			(island_removal_mode 0)
		)
		(polygon
			(pts
				(arc
					(start 22.225 -214.6173)
					(mid 20.447 -214.6173)
					(end 22.225 -214.6173)
				)
			)
		)
	)
	(zone
		(layers "In1.Cu" "In4.Cu")
		(hatch none 0.5)
		(connect_pads
			(clearance 0)
		)
		(min_thickness 0.25)
		(keepout
			(tracks not_allowed)
			(vias allowed)
			(pads allowed)
			(copperpour not_allowed)
			(footprints allowed)
		)
		(placement
			(enabled no)
			(sheetname "")
		)
		(fill yes
			(thermal_gap 0.5)
			(thermal_bridge_width 0.5)
			(island_removal_mode 0)
		)
		(polygon
			(pts
				(arc
					(start 42.840656 -47.280322)
					(mid 41.062656 -47.280322)
					(end 42.840656 -47.280322)
				)
			)
		)
	)
	(zone
		(layers "In1.Cu" "In4.Cu")
		(hatch none 0.5)
		(connect_pads
			(clearance 0)
		)
		(min_thickness 0.25)
		(keepout
			(tracks not_allowed)
			(vias allowed)
			(pads allowed)
			(copperpour not_allowed)
			(footprints allowed)
		)
		(placement
			(enabled no)
			(sheetname "")
		)
		(fill yes
			(thermal_gap 0.5)
			(thermal_bridge_width 0.5)
			(island_removal_mode 0)
		)
		(polygon
			(pts
				(arc
					(start 8.328914 -59.713622)
					(mid 6.550914 -59.713622)
					(end 8.328914 -59.713622)
				)
			)
		)
	)
	(zone
		(layers "In1.Cu" "In4.Cu")
		(hatch none 0.5)
		(connect_pads
			(clearance 0)
		)
		(min_thickness 0.25)
		(keepout
			(tracks not_allowed)
			(vias allowed)
			(pads allowed)
			(copperpour not_allowed)
			(footprints allowed)
		)
		(placement
			(enabled no)
			(sheetname "")
		)
		(fill yes
			(thermal_gap 0.5)
			(thermal_bridge_width 0.5)
			(island_removal_mode 0)
		)
		(polygon
			(pts
				(arc
					(start 34.006028 -267.97)
					(mid 32.228028 -267.97)
					(end 34.006028 -267.97)
				)
			)
		)
	)
	(zone
		(layers "In1.Cu" "In4.Cu")
		(hatch none 0.5)
		(connect_pads
			(clearance 0)
		)
		(min_thickness 0.25)
		(keepout
			(tracks not_allowed)
			(vias allowed)
			(pads allowed)
			(copperpour not_allowed)
			(footprints allowed)
		)
		(placement
			(enabled no)
			(sheetname "")
		)
		(fill yes
			(thermal_gap 0.5)
			(thermal_bridge_width 0.5)
			(island_removal_mode 0)
		)
		(polygon
			(pts
				(arc
					(start 13.794232 -222.86341)
					(mid 12.016232 -222.86341)
					(end 13.794232 -222.86341)
				)
			)
		)
	)
	(zone
		(layers "In1.Cu" "In4.Cu")
		(hatch none 0.5)
		(connect_pads
			(clearance 0)
		)
		(min_thickness 0.25)
		(keepout
			(tracks not_allowed)
			(vias allowed)
			(pads allowed)
			(copperpour not_allowed)
			(footprints allowed)
		)
		(placement
			(enabled no)
			(sheetname "")
		)
		(fill yes
			(thermal_gap 0.5)
			(thermal_bridge_width 0.5)
			(island_removal_mode 0)
		)
		(polygon
			(pts
				(arc
					(start 40.151304 -37.248846)
					(mid 38.373304 -37.248846)
					(end 40.151304 -37.248846)
				)
			)
		)
	)
	(zone
		(layers "In1.Cu" "In4.Cu")
		(hatch none 0.5)
		(connect_pads
			(clearance 0)
		)
		(min_thickness 0.25)
		(keepout
			(tracks not_allowed)
			(vias allowed)
			(pads allowed)
			(copperpour not_allowed)
			(footprints allowed)
		)
		(placement
			(enabled no)
			(sheetname "")
		)
		(fill yes
			(thermal_gap 0.5)
			(thermal_bridge_width 0.5)
			(island_removal_mode 0)
		)
		(polygon
			(pts
				(arc
					(start 12.950698 -43.501056)
					(mid 11.172698 -43.501056)
					(end 12.950698 -43.501056)
				)
			)
		)
	)
	(zone
		(layers "In1.Cu" "In4.Cu")
		(hatch none 0.5)
		(connect_pads
			(clearance 0)
		)
		(min_thickness 0.25)
		(keepout
			(tracks not_allowed)
			(vias allowed)
			(pads allowed)
			(copperpour not_allowed)
			(footprints allowed)
		)
		(placement
			(enabled no)
			(sheetname "")
		)
		(fill yes
			(thermal_gap 0.5)
			(thermal_bridge_width 0.5)
			(island_removal_mode 0)
		)
		(polygon
			(pts
				(arc
					(start 36.848288 -271.2466)
					(mid 35.070288 -271.2466)
					(end 36.848288 -271.2466)
				)
			)
		)
	)
	(zone
		(layers "In1.Cu" "In4.Cu")
		(hatch none 0.5)
		(connect_pads
			(clearance 0)
		)
		(min_thickness 0.25)
		(keepout
			(tracks not_allowed)
			(vias allowed)
			(pads allowed)
			(copperpour not_allowed)
			(footprints allowed)
		)
		(placement
			(enabled no)
			(sheetname "")
		)
		(fill yes
			(thermal_gap 0.5)
			(thermal_bridge_width 0.5)
			(island_removal_mode 0)
		)
		(polygon
			(pts
				(arc
					(start 38.627304 -37.248846)
					(mid 36.849304 -37.248846)
					(end 38.627304 -37.248846)
				)
			)
		)
	)
	(zone
		(layers "In1.Cu" "In4.Cu")
		(hatch none 0.5)
		(connect_pads
			(clearance 0)
		)
		(min_thickness 0.25)
		(keepout
			(tracks not_allowed)
			(vias allowed)
			(pads allowed)
			(copperpour not_allowed)
			(footprints allowed)
		)
		(placement
			(enabled no)
			(sheetname "")
		)
		(fill yes
			(thermal_gap 0.5)
			(thermal_bridge_width 0.5)
			(island_removal_mode 0)
		)
		(polygon
			(pts
				(arc
					(start 10.43559 -264.4902)
					(mid 8.65759 -264.4902)
					(end 10.43559 -264.4902)
				)
			)
		)
	)
	(zone
		(layers "In1.Cu" "In4.Cu")
		(hatch none 0.5)
		(connect_pads
			(clearance 0)
		)
		(min_thickness 0.25)
		(keepout
			(tracks not_allowed)
			(vias allowed)
			(pads allowed)
			(copperpour not_allowed)
			(footprints allowed)
		)
		(placement
			(enabled no)
			(sheetname "")
		)
		(fill yes
			(thermal_gap 0.5)
			(thermal_bridge_width 0.5)
			(island_removal_mode 0)
		)
		(polygon
			(pts
				(arc
					(start 13.076174 -263.68629)
					(mid 11.298174 -263.68629)
					(end 13.076174 -263.68629)
				)
			)
		)
	)
	(zone
		(layers "In1.Cu" "In4.Cu")
		(hatch none 0.5)
		(connect_pads
			(clearance 0)
		)
		(min_thickness 0.25)
		(keepout
			(tracks not_allowed)
			(vias allowed)
			(pads allowed)
			(copperpour not_allowed)
			(footprints allowed)
		)
		(placement
			(enabled no)
			(sheetname "")
		)
		(fill yes
			(thermal_gap 0.5)
			(thermal_bridge_width 0.5)
			(island_removal_mode 0)
		)
		(polygon
			(pts
				(arc
					(start 21.717 -105.41)
					(mid 19.939 -105.41)
					(end 21.717 -105.41)
				)
			)
		)
	)
	(zone
		(layers "In1.Cu" "In4.Cu")
		(hatch none 0.5)
		(connect_pads
			(clearance 0)
		)
		(min_thickness 0.25)
		(keepout
			(tracks not_allowed)
			(vias allowed)
			(pads allowed)
			(copperpour not_allowed)
			(footprints allowed)
		)
		(placement
			(enabled no)
			(sheetname "")
		)
		(fill yes
			(thermal_gap 0.5)
			(thermal_bridge_width 0.5)
			(island_removal_mode 0)
		)
		(polygon
			(pts
				(arc
					(start 13.594334 -79.721202)
					(mid 11.816334 -79.721202)
					(end 13.594334 -79.721202)
				)
			)
		)
	)
	(zone
		(layers "In1.Cu" "In4.Cu")
		(hatch none 0.5)
		(connect_pads
			(clearance 0)
		)
		(min_thickness 0.25)
		(keepout
			(tracks not_allowed)
			(vias allowed)
			(pads allowed)
			(copperpour not_allowed)
			(footprints allowed)
		)
		(placement
			(enabled no)
			(sheetname "")
		)
		(fill yes
			(thermal_gap 0.5)
			(thermal_bridge_width 0.5)
			(island_removal_mode 0)
		)
		(polygon
			(pts
				(arc
					(start 12.928346 -38.014656)
					(mid 11.150346 -38.014656)
					(end 12.928346 -38.014656)
				)
			)
		)
	)
	(zone
		(layers "In1.Cu" "In4.Cu")
		(hatch none 0.5)
		(connect_pads
			(clearance 0)
		)
		(min_thickness 0.25)
		(keepout
			(tracks not_allowed)
			(vias allowed)
			(pads allowed)
			(copperpour not_allowed)
			(footprints allowed)
		)
		(placement
			(enabled no)
			(sheetname "")
		)
		(fill yes
			(thermal_gap 0.5)
			(thermal_bridge_width 0.5)
			(island_removal_mode 0)
		)
		(polygon
			(pts
				(arc
					(start 5.50799 -264.6426)
					(mid 3.72999 -264.6426)
					(end 5.50799 -264.6426)
				)
			)
		)
	)
	(zone
		(layers "In1.Cu" "In4.Cu")
		(hatch none 0.5)
		(connect_pads
			(clearance 0)
		)
		(min_thickness 0.25)
		(keepout
			(tracks not_allowed)
			(vias allowed)
			(pads allowed)
			(copperpour not_allowed)
			(footprints allowed)
		)
		(placement
			(enabled no)
			(sheetname "")
		)
		(fill yes
			(thermal_gap 0.5)
			(thermal_bridge_width 0.5)
			(island_removal_mode 0)
		)
		(polygon
			(pts
				(arc
					(start 29.977588 -11.3792)
					(mid 28.199588 -11.3792)
					(end 29.977588 -11.3792)
				)
			)
		)
	)
	(zone
		(layers "In1.Cu" "In4.Cu")
		(hatch none 0.5)
		(connect_pads
			(clearance 0)
		)
		(min_thickness 0.25)
		(keepout
			(tracks not_allowed)
			(vias allowed)
			(pads allowed)
			(copperpour not_allowed)
			(footprints allowed)
		)
		(placement
			(enabled no)
			(sheetname "")
		)
		(fill yes
			(thermal_gap 0.5)
			(thermal_bridge_width 0.5)
			(island_removal_mode 0)
		)
		(polygon
			(pts
				(arc
					(start 6.858 -91.878912)
					(mid 5.08 -91.878912)
					(end 6.858 -91.878912)
				)
			)
		)
	)
	(zone
		(layers "In1.Cu" "In4.Cu")
		(hatch none 0.5)
		(connect_pads
			(clearance 0)
		)
		(min_thickness 0.25)
		(keepout
			(tracks not_allowed)
			(vias allowed)
			(pads allowed)
			(copperpour not_allowed)
			(footprints allowed)
		)
		(placement
			(enabled no)
			(sheetname "")
		)
		(fill yes
			(thermal_gap 0.5)
			(thermal_bridge_width 0.5)
			(island_removal_mode 0)
		)
		(polygon
			(pts
				(arc
					(start 47.969932 -57.741312)
					(mid 46.191932 -57.741312)
					(end 47.969932 -57.741312)
				)
			)
		)
	)
	(zone
		(layers "In1.Cu" "In4.Cu")
		(hatch none 0.5)
		(connect_pads
			(clearance 0)
		)
		(min_thickness 0.25)
		(keepout
			(tracks not_allowed)
			(vias allowed)
			(pads allowed)
			(copperpour not_allowed)
			(footprints allowed)
		)
		(placement
			(enabled no)
			(sheetname "")
		)
		(fill yes
			(thermal_gap 0.5)
			(thermal_bridge_width 0.5)
			(island_removal_mode 0)
		)
		(polygon
			(pts
				(arc
					(start 12.166346 -37.303456)
					(mid 10.388346 -37.303456)
					(end 12.166346 -37.303456)
				)
			)
		)
	)
	(zone
		(layers "In1.Cu" "In4.Cu")
		(hatch none 0.5)
		(connect_pads
			(clearance 0)
		)
		(min_thickness 0.25)
		(keepout
			(tracks not_allowed)
			(vias allowed)
			(pads allowed)
			(copperpour not_allowed)
			(footprints allowed)
		)
		(placement
			(enabled no)
			(sheetname "")
		)
		(fill yes
			(thermal_gap 0.5)
			(thermal_bridge_width 0.5)
			(island_removal_mode 0)
		)
		(polygon
			(pts
				(arc
					(start 11.599418 -243.4336)
					(mid 9.821418 -243.4336)
					(end 11.599418 -243.4336)
				)
			)
		)
	)
	(zone
		(layers "In1.Cu" "In4.Cu")
		(hatch none 0.5)
		(connect_pads
			(clearance 0)
		)
		(min_thickness 0.25)
		(keepout
			(tracks not_allowed)
			(vias allowed)
			(pads allowed)
			(copperpour not_allowed)
			(footprints allowed)
		)
		(placement
			(enabled no)
			(sheetname "")
		)
		(fill yes
			(thermal_gap 0.5)
			(thermal_bridge_width 0.5)
			(island_removal_mode 0)
		)
		(polygon
			(pts
				(arc
					(start 13.731494 -263.68629)
					(mid 11.953494 -263.68629)
					(end 13.731494 -263.68629)
				)
			)
		)
	)
	(zone
		(layers "In1.Cu" "In4.Cu")
		(hatch none 0.5)
		(connect_pads
			(clearance 0)
		)
		(min_thickness 0.25)
		(keepout
			(tracks not_allowed)
			(vias allowed)
			(pads allowed)
			(copperpour not_allowed)
			(footprints allowed)
		)
		(placement
			(enabled no)
			(sheetname "")
		)
		(fill yes
			(thermal_gap 0.5)
			(thermal_bridge_width 0.5)
			(island_removal_mode 0)
		)
		(polygon
			(pts
				(arc
					(start 39.263828 -245.113556)
					(mid 37.485828 -245.113556)
					(end 39.263828 -245.113556)
				)
			)
		)
	)
	(zone
		(layers "In1.Cu" "In4.Cu")
		(hatch none 0.5)
		(connect_pads
			(clearance 0)
		)
		(min_thickness 0.25)
		(keepout
			(tracks not_allowed)
			(vias allowed)
			(pads allowed)
			(copperpour not_allowed)
			(footprints allowed)
		)
		(placement
			(enabled no)
			(sheetname "")
		)
		(fill yes
			(thermal_gap 0.5)
			(thermal_bridge_width 0.5)
			(island_removal_mode 0)
		)
		(polygon
			(pts
				(arc
					(start 10.837418 -58.477912)
					(mid 9.059418 -58.477912)
					(end 10.837418 -58.477912)
				)
			)
		)
	)
	(zone
		(layers "In1.Cu" "In4.Cu")
		(hatch none 0.5)
		(connect_pads
			(clearance 0)
		)
		(min_thickness 0.25)
		(keepout
			(tracks not_allowed)
			(vias allowed)
			(pads allowed)
			(copperpour not_allowed)
			(footprints allowed)
		)
		(placement
			(enabled no)
			(sheetname "")
		)
		(fill yes
			(thermal_gap 0.5)
			(thermal_bridge_width 0.5)
			(island_removal_mode 0)
		)
		(polygon
			(pts
				(arc
					(start 8.303514 -53.448712)
					(mid 6.525514 -53.448712)
					(end 8.303514 -53.448712)
				)
			)
		)
	)
	(zone
		(layers "In1.Cu" "In4.Cu")
		(hatch none 0.5)
		(connect_pads
			(clearance 0)
		)
		(min_thickness 0.25)
		(keepout
			(tracks not_allowed)
			(vias allowed)
			(pads allowed)
			(copperpour not_allowed)
			(footprints allowed)
		)
		(placement
			(enabled no)
			(sheetname "")
		)
		(fill yes
			(thermal_gap 0.5)
			(thermal_bridge_width 0.5)
			(island_removal_mode 0)
		)
		(polygon
			(pts
				(arc
					(start 37.229288 -273.812)
					(mid 35.451288 -273.812)
					(end 37.229288 -273.812)
				)
			)
		)
	)
	(zone
		(layers "In1.Cu" "In4.Cu")
		(hatch none 0.5)
		(connect_pads
			(clearance 0)
		)
		(min_thickness 0.25)
		(keepout
			(tracks not_allowed)
			(vias allowed)
			(pads allowed)
			(copperpour not_allowed)
			(footprints allowed)
		)
		(placement
			(enabled no)
			(sheetname "")
		)
		(fill yes
			(thermal_gap 0.5)
			(thermal_bridge_width 0.5)
			(island_removal_mode 0)
		)
		(polygon
			(pts
				(arc
					(start 13.266674 -247.600978)
					(mid 11.488674 -247.600978)
					(end 13.266674 -247.600978)
				)
			)
		)
	)
	(zone
		(layers "In1.Cu" "In4.Cu")
		(hatch none 0.5)
		(connect_pads
			(clearance 0)
		)
		(min_thickness 0.25)
		(keepout
			(tracks not_allowed)
			(vias allowed)
			(pads allowed)
			(copperpour not_allowed)
			(footprints allowed)
		)
		(placement
			(enabled no)
			(sheetname "")
		)
		(fill yes
			(thermal_gap 0.5)
			(thermal_bridge_width 0.5)
			(island_removal_mode 0)
		)
		(polygon
			(pts
				(arc
					(start 8.303514 -52.686712)
					(mid 6.525514 -52.686712)
					(end 8.303514 -52.686712)
				)
			)
		)
	)
	(zone
		(layers "In1.Cu" "In4.Cu")
		(hatch none 0.5)
		(connect_pads
			(clearance 0)
		)
		(min_thickness 0.25)
		(keepout
			(tracks not_allowed)
			(vias allowed)
			(pads allowed)
			(copperpour not_allowed)
			(footprints allowed)
		)
		(placement
			(enabled no)
			(sheetname "")
		)
		(fill yes
			(thermal_gap 0.5)
			(thermal_bridge_width 0.5)
			(island_removal_mode 0)
		)
		(polygon
			(pts
				(arc
					(start 15.0368 -274.139406)
					(mid 13.2588 -274.139406)
					(end 15.0368 -274.139406)
				)
			)
		)
	)
	(zone
		(layers "In1.Cu" "In4.Cu")
		(hatch none 0.5)
		(connect_pads
			(clearance 0)
		)
		(min_thickness 0.25)
		(keepout
			(tracks not_allowed)
			(vias allowed)
			(pads allowed)
			(copperpour not_allowed)
			(footprints allowed)
		)
		(placement
			(enabled no)
			(sheetname "")
		)
		(fill yes
			(thermal_gap 0.5)
			(thermal_bridge_width 0.5)
			(island_removal_mode 0)
		)
		(polygon
			(pts
				(arc
					(start 5.229098 -58.913776)
					(mid 3.451098 -58.913776)
					(end 5.229098 -58.913776)
				)
			)
		)
	)
	(zone
		(layers "In1.Cu" "In4.Cu")
		(hatch none 0.5)
		(connect_pads
			(clearance 0)
		)
		(min_thickness 0.25)
		(keepout
			(tracks not_allowed)
			(vias allowed)
			(pads allowed)
			(copperpour not_allowed)
			(footprints allowed)
		)
		(placement
			(enabled no)
			(sheetname "")
		)
		(fill yes
			(thermal_gap 0.5)
			(thermal_bridge_width 0.5)
			(island_removal_mode 0)
		)
		(polygon
			(pts
				(arc
					(start 47.334932 -92.02166)
					(mid 45.556932 -92.02166)
					(end 47.334932 -92.02166)
				)
			)
		)
	)
	(zone
		(layers "In1.Cu" "In4.Cu")
		(hatch none 0.5)
		(connect_pads
			(clearance 0)
		)
		(min_thickness 0.25)
		(keepout
			(tracks not_allowed)
			(vias allowed)
			(pads allowed)
			(copperpour not_allowed)
			(footprints allowed)
		)
		(placement
			(enabled no)
			(sheetname "")
		)
		(fill yes
			(thermal_gap 0.5)
			(thermal_bridge_width 0.5)
			(island_removal_mode 0)
		)
		(polygon
			(pts
				(arc
					(start 13.241274 -246.305578)
					(mid 11.463274 -246.305578)
					(end 13.241274 -246.305578)
				)
			)
		)
	)
	(zone
		(layers "In1.Cu" "In4.Cu")
		(hatch none 0.5)
		(connect_pads
			(clearance 0)
		)
		(min_thickness 0.25)
		(keepout
			(tracks not_allowed)
			(vias allowed)
			(pads allowed)
			(copperpour not_allowed)
			(footprints allowed)
		)
		(placement
			(enabled no)
			(sheetname "")
		)
		(fill yes
			(thermal_gap 0.5)
			(thermal_bridge_width 0.5)
			(island_removal_mode 0)
		)
		(polygon
			(pts
				(arc
					(start 47.969932 -58.503312)
					(mid 46.191932 -58.503312)
					(end 47.969932 -58.503312)
				)
			)
		)
	)
	(zone
		(layers "In1.Cu" "In4.Cu")
		(hatch none 0.5)
		(connect_pads
			(clearance 0)
		)
		(min_thickness 0.25)
		(keepout
			(tracks not_allowed)
			(vias allowed)
			(pads allowed)
			(copperpour not_allowed)
			(footprints allowed)
		)
		(placement
			(enabled no)
			(sheetname "")
		)
		(fill yes
			(thermal_gap 0.5)
			(thermal_bridge_width 0.5)
			(island_removal_mode 0)
		)
		(polygon
			(pts
				(arc
					(start 14.239494 -79.721202)
					(mid 12.461494 -79.721202)
					(end 14.239494 -79.721202)
				)
			)
		)
	)
	(zone
		(layers "In1.Cu" "In4.Cu")
		(hatch none 0.5)
		(connect_pads
			(clearance 0)
		)
		(min_thickness 0.25)
		(keepout
			(tracks not_allowed)
			(vias allowed)
			(pads allowed)
			(copperpour not_allowed)
			(footprints allowed)
		)
		(placement
			(enabled no)
			(sheetname "")
		)
		(fill yes
			(thermal_gap 0.5)
			(thermal_bridge_width 0.5)
			(island_removal_mode 0)
		)
		(polygon
			(pts
				(arc
					(start 17.33931 -80.521048)
					(mid 15.56131 -80.521048)
					(end 17.33931 -80.521048)
				)
			)
		)
	)
	(zone
		(layers "In1.Cu" "In4.Cu")
		(hatch none 0.5)
		(connect_pads
			(clearance 0)
		)
		(min_thickness 0.25)
		(keepout
			(tracks not_allowed)
			(vias allowed)
			(pads allowed)
			(copperpour not_allowed)
			(footprints allowed)
		)
		(placement
			(enabled no)
			(sheetname "")
		)
		(fill yes
			(thermal_gap 0.5)
			(thermal_bridge_width 0.5)
			(island_removal_mode 0)
		)
		(polygon
			(pts
				(arc
					(start 9.22655 -232.369614)
					(mid 7.44855 -232.369614)
					(end 9.22655 -232.369614)
				)
			)
		)
	)
	(zone
		(layers "In1.Cu" "In4.Cu")
		(hatch none 0.5)
		(connect_pads
			(clearance 0)
		)
		(min_thickness 0.25)
		(keepout
			(tracks not_allowed)
			(vias allowed)
			(pads allowed)
			(copperpour not_allowed)
			(footprints allowed)
		)
		(placement
			(enabled no)
			(sheetname "")
		)
		(fill yes
			(thermal_gap 0.5)
			(thermal_bridge_width 0.5)
			(island_removal_mode 0)
		)
		(polygon
			(pts
				(arc
					(start 43.810428 -265.121136)
					(mid 42.032428 -265.121136)
					(end 43.810428 -265.121136)
				)
			)
		)
	)
	(zone
		(layers "In1.Cu" "In4.Cu")
		(hatch none 0.5)
		(connect_pads
			(clearance 0)
		)
		(min_thickness 0.25)
		(keepout
			(tracks not_allowed)
			(vias allowed)
			(pads allowed)
			(copperpour not_allowed)
			(footprints allowed)
		)
		(placement
			(enabled no)
			(sheetname "")
		)
		(fill yes
			(thermal_gap 0.5)
			(thermal_bridge_width 0.5)
			(island_removal_mode 0)
		)
		(polygon
			(pts
				(arc
					(start 15.02029 -277.895304)
					(mid 13.24229 -277.895304)
					(end 15.02029 -277.895304)
				)
			)
		)
	)
	(zone
		(layers "In1.Cu" "In4.Cu")
		(hatch none 0.5)
		(connect_pads
			(clearance 0)
		)
		(min_thickness 0.25)
		(keepout
			(tracks not_allowed)
			(vias allowed)
			(pads allowed)
			(copperpour not_allowed)
			(footprints allowed)
		)
		(placement
			(enabled no)
			(sheetname "")
		)
		(fill yes
			(thermal_gap 0.5)
			(thermal_bridge_width 0.5)
			(island_removal_mode 0)
		)
		(polygon
			(pts
				(arc
					(start 8.984234 -243.67871)
					(mid 7.206234 -243.67871)
					(end 8.984234 -243.67871)
				)
			)
		)
	)
	(zone
		(layers "In1.Cu" "In4.Cu")
		(hatch none 0.5)
		(connect_pads
			(clearance 0)
		)
		(min_thickness 0.25)
		(keepout
			(tracks not_allowed)
			(vias allowed)
			(pads allowed)
			(copperpour not_allowed)
			(footprints allowed)
		)
		(placement
			(enabled no)
			(sheetname "")
		)
		(fill yes
			(thermal_gap 0.5)
			(thermal_bridge_width 0.5)
			(island_removal_mode 0)
		)
		(polygon
			(pts
				(arc
					(start 13.794232 -224.38741)
					(mid 12.016232 -224.38741)
					(end 13.794232 -224.38741)
				)
			)
		)
	)
	(zone
		(layers "In1.Cu" "In4.Cu")
		(hatch none 0.5)
		(connect_pads
			(clearance 0)
		)
		(min_thickness 0.25)
		(keepout
			(tracks not_allowed)
			(vias allowed)
			(pads allowed)
			(copperpour not_allowed)
			(footprints allowed)
		)
		(placement
			(enabled no)
			(sheetname "")
		)
		(fill yes
			(thermal_gap 0.5)
			(thermal_bridge_width 0.5)
			(island_removal_mode 0)
		)
		(polygon
			(pts
				(arc
					(start 13.266674 -243.079778)
					(mid 11.488674 -243.079778)
					(end 13.266674 -243.079778)
				)
			)
		)
	)
	(zone
		(layers "In1.Cu" "In4.Cu")
		(hatch none 0.5)
		(connect_pads
			(clearance 0)
		)
		(min_thickness 0.25)
		(keepout
			(tracks not_allowed)
			(vias allowed)
			(pads allowed)
			(copperpour not_allowed)
			(footprints allowed)
		)
		(placement
			(enabled no)
			(sheetname "")
		)
		(fill yes
			(thermal_gap 0.5)
			(thermal_bridge_width 0.5)
			(island_removal_mode 0)
		)
		(polygon
			(pts
				(arc
					(start 44.320714 -295.310052)
					(mid 41.679114 -295.310052)
					(end 44.320714 -295.310052)
				)
			)
		)
	)
	(zone
		(layers "In1.Cu" "In4.Cu")
		(hatch none 0.5)
		(connect_pads
			(clearance 0)
		)
		(min_thickness 0.25)
		(keepout
			(tracks not_allowed)
			(vias allowed)
			(pads allowed)
			(copperpour not_allowed)
			(footprints allowed)
		)
		(placement
			(enabled no)
			(sheetname "")
		)
		(fill yes
			(thermal_gap 0.5)
			(thermal_bridge_width 0.5)
			(island_removal_mode 0)
		)
		(polygon
			(pts
				(arc
					(start 40.401748 -59.713622)
					(mid 38.623748 -59.713622)
					(end 40.401748 -59.713622)
				)
			)
		)
	)
	(zone
		(layers "In1.Cu" "In4.Cu")
		(hatch none 0.5)
		(connect_pads
			(clearance 0)
		)
		(min_thickness 0.25)
		(keepout
			(tracks not_allowed)
			(vias allowed)
			(pads allowed)
			(copperpour not_allowed)
			(footprints allowed)
		)
		(placement
			(enabled no)
			(sheetname "")
		)
		(fill yes
			(thermal_gap 0.5)
			(thermal_bridge_width 0.5)
			(island_removal_mode 0)
		)
		(polygon
			(pts
				(arc
					(start 38.9636 -93.352112)
					(mid 37.1856 -93.352112)
					(end 38.9636 -93.352112)
				)
			)
		)
	)
	(zone
		(layers "In1.Cu" "In4.Cu")
		(hatch none 0.5)
		(connect_pads
			(clearance 0)
		)
		(min_thickness 0.25)
		(keepout
			(tracks not_allowed)
			(vias allowed)
			(pads allowed)
			(copperpour not_allowed)
			(footprints allowed)
		)
		(placement
			(enabled no)
			(sheetname "")
		)
		(fill yes
			(thermal_gap 0.5)
			(thermal_bridge_width 0.5)
			(island_removal_mode 0)
		)
		(polygon
			(pts
				(arc
					(start 5.50799 -263.8806)
					(mid 3.72999 -263.8806)
					(end 5.50799 -263.8806)
				)
			)
		)
	)
	(zone
		(layers "In1.Cu" "In4.Cu")
		(hatch none 0.5)
		(connect_pads
			(clearance 0)
		)
		(min_thickness 0.25)
		(keepout
			(tracks not_allowed)
			(vias allowed)
			(pads allowed)
			(copperpour not_allowed)
			(footprints allowed)
		)
		(placement
			(enabled no)
			(sheetname "")
		)
		(fill yes
			(thermal_gap 0.5)
			(thermal_bridge_width 0.5)
			(island_removal_mode 0)
		)
		(polygon
			(pts
				(arc
					(start 13.266674 -243.714778)
					(mid 11.488674 -243.714778)
					(end 13.266674 -243.714778)
				)
			)
		)
	)
	(zone
		(layers "In1.Cu" "In4.Cu")
		(hatch none 0.5)
		(connect_pads
			(clearance 0)
		)
		(min_thickness 0.25)
		(keepout
			(tracks not_allowed)
			(vias allowed)
			(pads allowed)
			(copperpour not_allowed)
			(footprints allowed)
		)
		(placement
			(enabled no)
			(sheetname "")
		)
		(fill yes
			(thermal_gap 0.5)
			(thermal_bridge_width 0.5)
			(island_removal_mode 0)
		)
		(polygon
			(pts
				(arc
					(start 39.389304 -37.883846)
					(mid 37.611304 -37.883846)
					(end 39.389304 -37.883846)
				)
			)
		)
	)
	(zone
		(layers "In1.Cu" "In4.Cu")
		(hatch none 0.5)
		(connect_pads
			(clearance 0)
		)
		(min_thickness 0.25)
		(keepout
			(tracks not_allowed)
			(vias allowed)
			(pads allowed)
			(copperpour not_allowed)
			(footprints allowed)
		)
		(placement
			(enabled no)
			(sheetname "")
		)
		(fill yes
			(thermal_gap 0.5)
			(thermal_bridge_width 0.5)
			(island_removal_mode 0)
		)
		(polygon
			(pts
				(arc
					(start 41.355772 -264.32129)
					(mid 39.577772 -264.32129)
					(end 41.355772 -264.32129)
				)
			)
		)
	)
	(zone
		(layers "In1.Cu" "In4.Cu")
		(hatch none 0.5)
		(connect_pads
			(clearance 0)
		)
		(min_thickness 0.25)
		(keepout
			(tracks not_allowed)
			(vias allowed)
			(pads allowed)
			(copperpour not_allowed)
			(footprints allowed)
		)
		(placement
			(enabled no)
			(sheetname "")
		)
		(fill yes
			(thermal_gap 0.5)
			(thermal_bridge_width 0.5)
			(island_removal_mode 0)
		)
		(polygon
			(pts
				(arc
					(start 9.17575 -235.011214)
					(mid 7.39775 -235.011214)
					(end 9.17575 -235.011214)
				)
			)
		)
	)
	(zone
		(layers "In1.Cu" "In4.Cu")
		(hatch none 0.5)
		(connect_pads
			(clearance 0)
		)
		(min_thickness 0.25)
		(keepout
			(tracks not_allowed)
			(vias allowed)
			(pads allowed)
			(copperpour not_allowed)
			(footprints allowed)
		)
		(placement
			(enabled no)
			(sheetname "")
		)
		(fill yes
			(thermal_gap 0.5)
			(thermal_bridge_width 0.5)
			(island_removal_mode 0)
		)
		(polygon
			(pts
				(arc
					(start 33.193228 -263.906)
					(mid 31.415228 -263.906)
					(end 33.193228 -263.906)
				)
			)
		)
	)
	(zone
		(layers "In1.Cu" "In4.Cu")
		(hatch none 0.5)
		(connect_pads
			(clearance 0)
		)
		(min_thickness 0.25)
		(keepout
			(tracks not_allowed)
			(vias allowed)
			(pads allowed)
			(copperpour not_allowed)
			(footprints allowed)
		)
		(placement
			(enabled no)
			(sheetname "")
		)
		(fill yes
			(thermal_gap 0.5)
			(thermal_bridge_width 0.5)
			(island_removal_mode 0)
		)
		(polygon
			(pts
				(arc
					(start 18.9992 -116.84)
					(mid 17.2212 -116.84)
					(end 18.9992 -116.84)
				)
			)
		)
	)
	(zone
		(layers "In1.Cu" "In4.Cu")
		(hatch none 0.5)
		(connect_pads
			(clearance 0)
		)
		(min_thickness 0.25)
		(keepout
			(tracks not_allowed)
			(vias allowed)
			(pads allowed)
			(copperpour not_allowed)
			(footprints allowed)
		)
		(placement
			(enabled no)
			(sheetname "")
		)
		(fill yes
			(thermal_gap 0.5)
			(thermal_bridge_width 0.5)
			(island_removal_mode 0)
		)
		(polygon
			(pts
				(arc
					(start 13.241274 -245.670578)
					(mid 11.463274 -245.670578)
					(end 13.241274 -245.670578)
				)
			)
		)
	)
	(zone
		(layers "In1.Cu" "In4.Cu")
		(hatch none 0.5)
		(connect_pads
			(clearance 0)
		)
		(min_thickness 0.25)
		(keepout
			(tracks not_allowed)
			(vias allowed)
			(pads allowed)
			(copperpour not_allowed)
			(footprints allowed)
		)
		(placement
			(enabled no)
			(sheetname "")
		)
		(fill yes
			(thermal_gap 0.5)
			(thermal_bridge_width 0.5)
			(island_removal_mode 0)
		)
		(polygon
			(pts
				(arc
					(start 5.715 -280.4922)
					(mid 3.937 -280.4922)
					(end 5.715 -280.4922)
				)
			)
		)
	)
	(zone
		(layers "In1.Cu" "In4.Cu")
		(hatch none 0.5)
		(connect_pads
			(clearance 0)
		)
		(min_thickness 0.25)
		(keepout
			(tracks not_allowed)
			(vias allowed)
			(pads allowed)
			(copperpour not_allowed)
			(footprints allowed)
		)
		(placement
			(enabled no)
			(sheetname "")
		)
		(fill yes
			(thermal_gap 0.5)
			(thermal_bridge_width 0.5)
			(island_removal_mode 0)
		)
		(polygon
			(pts
				(arc
					(start 39.589456 -226.08921)
					(mid 37.811456 -226.08921)
					(end 39.589456 -226.08921)
				)
			)
		)
	)
	(zone
		(layers "In1.Cu" "In4.Cu")
		(hatch none 0.5)
		(connect_pads
			(clearance 0)
		)
		(min_thickness 0.25)
		(keepout
			(tracks not_allowed)
			(vias allowed)
			(pads allowed)
			(copperpour not_allowed)
			(footprints allowed)
		)
		(placement
			(enabled no)
			(sheetname "")
		)
		(fill yes
			(thermal_gap 0.5)
			(thermal_bridge_width 0.5)
			(island_removal_mode 0)
		)
		(polygon
			(pts
				(arc
					(start 38.9636 -87.9602)
					(mid 37.1856 -87.9602)
					(end 38.9636 -87.9602)
				)
			)
		)
	)
	(zone
		(layers "In1.Cu" "In4.Cu")
		(hatch none 0.5)
		(connect_pads
			(clearance 0)
		)
		(min_thickness 0.25)
		(keepout
			(tracks not_allowed)
			(vias allowed)
			(pads allowed)
			(copperpour not_allowed)
			(footprints allowed)
		)
		(placement
			(enabled no)
			(sheetname "")
		)
		(fill yes
			(thermal_gap 0.5)
			(thermal_bridge_width 0.5)
			(island_removal_mode 0)
		)
		(polygon
			(pts
				(arc
					(start 32.004 -25.908)
					(mid 30.226 -25.908)
					(end 32.004 -25.908)
				)
			)
		)
	)
	(zone
		(layers "In1.Cu" "In4.Cu")
		(hatch none 0.5)
		(connect_pads
			(clearance 0)
		)
		(min_thickness 0.25)
		(keepout
			(tracks not_allowed)
			(vias allowed)
			(pads allowed)
			(copperpour not_allowed)
			(footprints allowed)
		)
		(placement
			(enabled no)
			(sheetname "")
		)
		(fill yes
			(thermal_gap 0.5)
			(thermal_bridge_width 0.5)
			(island_removal_mode 0)
		)
		(polygon
			(pts
				(arc
					(start 8.984234 -59.713622)
					(mid 7.206234 -59.713622)
					(end 8.984234 -59.713622)
				)
			)
		)
	)
	(zone
		(layers "In1.Cu" "In4.Cu")
		(hatch none 0.5)
		(connect_pads
			(clearance 0)
		)
		(min_thickness 0.25)
		(keepout
			(tracks not_allowed)
			(vias allowed)
			(pads allowed)
			(copperpour not_allowed)
			(footprints allowed)
		)
		(placement
			(enabled no)
			(sheetname "")
		)
		(fill yes
			(thermal_gap 0.5)
			(thermal_bridge_width 0.5)
			(island_removal_mode 0)
		)
		(polygon
			(pts
				(arc
					(start 46.572932 -91.38666)
					(mid 44.794932 -91.38666)
					(end 46.572932 -91.38666)
				)
			)
		)
	)
	(zone
		(layers "In1.Cu" "In4.Cu")
		(hatch none 0.5)
		(connect_pads
			(clearance 0)
		)
		(min_thickness 0.25)
		(keepout
			(tracks not_allowed)
			(vias allowed)
			(pads allowed)
			(copperpour not_allowed)
			(footprints allowed)
		)
		(placement
			(enabled no)
			(sheetname "")
		)
		(fill yes
			(thermal_gap 0.5)
			(thermal_bridge_width 0.5)
			(island_removal_mode 0)
		)
		(polygon
			(pts
				(arc
					(start 13.076174 -264.32129)
					(mid 11.298174 -264.32129)
					(end 13.076174 -264.32129)
				)
			)
		)
	)
	(zone
		(layers "In1.Cu" "In4.Cu")
		(hatch none 0.5)
		(connect_pads
			(clearance 0)
		)
		(min_thickness 0.25)
		(keepout
			(tracks not_allowed)
			(vias allowed)
			(pads allowed)
			(copperpour not_allowed)
			(footprints allowed)
		)
		(placement
			(enabled no)
			(sheetname "")
		)
		(fill yes
			(thermal_gap 0.5)
			(thermal_bridge_width 0.5)
			(island_removal_mode 0)
		)
		(polygon
			(pts
				(arc
					(start 43.704256 -54.493922)
					(mid 41.926256 -54.493922)
					(end 43.704256 -54.493922)
				)
			)
		)
	)
	(zone
		(layers "In1.Cu" "In4.Cu")
		(hatch none 0.5)
		(connect_pads
			(clearance 0)
		)
		(min_thickness 0.25)
		(keepout
			(tracks not_allowed)
			(vias allowed)
			(pads allowed)
			(copperpour not_allowed)
			(footprints allowed)
		)
		(placement
			(enabled no)
			(sheetname "")
		)
		(fill yes
			(thermal_gap 0.5)
			(thermal_bridge_width 0.5)
			(island_removal_mode 0)
		)
		(polygon
			(pts
				(arc
					(start 47.563532 -242.062)
					(mid 45.785532 -242.062)
					(end 47.563532 -242.062)
				)
			)
		)
	)
	(zone
		(layers "In1.Cu" "In4.Cu")
		(hatch none 0.5)
		(connect_pads
			(clearance 0)
		)
		(min_thickness 0.25)
		(keepout
			(tracks not_allowed)
			(vias allowed)
			(pads allowed)
			(copperpour not_allowed)
			(footprints allowed)
		)
		(placement
			(enabled no)
			(sheetname "")
		)
		(fill yes
			(thermal_gap 0.5)
			(thermal_bridge_width 0.5)
			(island_removal_mode 0)
		)
		(polygon
			(pts
				(arc
					(start 48.249332 -280.330148)
					(mid 46.471332 -280.330148)
					(end 48.249332 -280.330148)
				)
			)
		)
	)
	(zone
		(layers "In1.Cu" "In4.Cu")
		(hatch none 0.5)
		(connect_pads
			(clearance 0)
		)
		(min_thickness 0.25)
		(keepout
			(tracks not_allowed)
			(vias allowed)
			(pads allowed)
			(copperpour not_allowed)
			(footprints allowed)
		)
		(placement
			(enabled no)
			(sheetname "")
		)
		(fill yes
			(thermal_gap 0.5)
			(thermal_bridge_width 0.5)
			(island_removal_mode 0)
		)
		(polygon
			(pts
				(arc
					(start 34.8996 -197.104)
					(mid 33.1216 -197.104)
					(end 34.8996 -197.104)
				)
			)
		)
	)
	(zone
		(layers "In1.Cu" "In4.Cu")
		(hatch none 0.5)
		(connect_pads
			(clearance 0)
		)
		(min_thickness 0.25)
		(keepout
			(tracks not_allowed)
			(vias allowed)
			(pads allowed)
			(copperpour not_allowed)
			(footprints allowed)
		)
		(placement
			(enabled no)
			(sheetname "")
		)
		(fill yes
			(thermal_gap 0.5)
			(thermal_bridge_width 0.5)
			(island_removal_mode 0)
		)
		(polygon
			(pts
				(arc
					(start 40.554148 -245.113556)
					(mid 38.776148 -245.113556)
					(end 40.554148 -245.113556)
				)
			)
		)
	)
	(zone
		(layers "In1.Cu" "In4.Cu")
		(hatch none 0.5)
		(connect_pads
			(clearance 0)
		)
		(min_thickness 0.25)
		(keepout
			(tracks not_allowed)
			(vias allowed)
			(pads allowed)
			(copperpour not_allowed)
			(footprints allowed)
		)
		(placement
			(enabled no)
			(sheetname "")
		)
		(fill yes
			(thermal_gap 0.5)
			(thermal_bridge_width 0.5)
			(island_removal_mode 0)
		)
		(polygon
			(pts
				(arc
					(start 4.594098 -58.278776)
					(mid 2.816098 -58.278776)
					(end 4.594098 -58.278776)
				)
			)
		)
	)
	(zone
		(layers "In1.Cu" "In4.Cu")
		(hatch none 0.5)
		(connect_pads
			(clearance 0)
		)
		(min_thickness 0.25)
		(keepout
			(tracks not_allowed)
			(vias allowed)
			(pads allowed)
			(copperpour not_allowed)
			(footprints allowed)
		)
		(placement
			(enabled no)
			(sheetname "")
		)
		(fill yes
			(thermal_gap 0.5)
			(thermal_bridge_width 0.5)
			(island_removal_mode 0)
		)
		(polygon
			(pts
				(arc
					(start 8.984234 -244.31371)
					(mid 7.206234 -244.31371)
					(end 8.984234 -244.31371)
				)
			)
		)
	)
	(zone
		(layers "In1.Cu" "In4.Cu")
		(hatch none 0.5)
		(connect_pads
			(clearance 0)
		)
		(min_thickness 0.25)
		(keepout
			(tracks not_allowed)
			(vias allowed)
			(pads allowed)
			(copperpour not_allowed)
			(footprints allowed)
		)
		(placement
			(enabled no)
			(sheetname "")
		)
		(fill yes
			(thermal_gap 0.5)
			(thermal_bridge_width 0.5)
			(island_removal_mode 0)
		)
		(polygon
			(pts
				(arc
					(start 36.011612 -244.31371)
					(mid 34.233612 -244.31371)
					(end 36.011612 -244.31371)
				)
			)
		)
	)
	(zone
		(layers "In1.Cu" "In4.Cu")
		(hatch none 0.5)
		(connect_pads
			(clearance 0)
		)
		(min_thickness 0.25)
		(keepout
			(tracks not_allowed)
			(vias allowed)
			(pads allowed)
			(copperpour not_allowed)
			(footprints allowed)
		)
		(placement
			(enabled no)
			(sheetname "")
		)
		(fill yes
			(thermal_gap 0.5)
			(thermal_bridge_width 0.5)
			(island_removal_mode 0)
		)
		(polygon
			(pts
				(arc
					(start 48.249332 -281.092148)
					(mid 46.471332 -281.092148)
					(end 48.249332 -281.092148)
				)
			)
		)
	)
	(zone
		(layers "In1.Cu" "In4.Cu")
		(hatch none 0.5)
		(connect_pads
			(clearance 0)
		)
		(min_thickness 0.25)
		(keepout
			(tracks not_allowed)
			(vias allowed)
			(pads allowed)
			(copperpour not_allowed)
			(footprints allowed)
		)
		(placement
			(enabled no)
			(sheetname "")
		)
		(fill yes
			(thermal_gap 0.5)
			(thermal_bridge_width 0.5)
			(island_removal_mode 0)
		)
		(polygon
			(pts
				(arc
					(start 6.096 -91.878912)
					(mid 4.318 -91.878912)
					(end 6.096 -91.878912)
				)
			)
		)
	)
	(zone
		(layers "In1.Cu" "In4.Cu")
		(hatch none 0.5)
		(connect_pads
			(clearance 0)
		)
		(min_thickness 0.25)
		(keepout
			(tracks not_allowed)
			(vias allowed)
			(pads allowed)
			(copperpour not_allowed)
			(footprints allowed)
		)
		(placement
			(enabled no)
			(sheetname "")
		)
		(fill yes
			(thermal_gap 0.5)
			(thermal_bridge_width 0.5)
			(island_removal_mode 0)
		)
		(polygon
			(pts
				(arc
					(start 4.594098 -58.913776)
					(mid 2.816098 -58.913776)
					(end 4.594098 -58.913776)
				)
			)
		)
	)
	(zone
		(layers "In1.Cu" "In4.Cu")
		(hatch none 0.5)
		(connect_pads
			(clearance 0)
		)
		(min_thickness 0.25)
		(keepout
			(tracks not_allowed)
			(vias allowed)
			(pads allowed)
			(copperpour not_allowed)
			(footprints allowed)
		)
		(placement
			(enabled no)
			(sheetname "")
		)
		(fill yes
			(thermal_gap 0.5)
			(thermal_bridge_width 0.5)
			(island_removal_mode 0)
		)
		(polygon
			(pts
				(arc
					(start 12.928346 -37.303456)
					(mid 11.150346 -37.303456)
					(end 12.928346 -37.303456)
				)
			)
		)
	)
	(zone
		(layers "In1.Cu" "In4.Cu")
		(hatch none 0.5)
		(connect_pads
			(clearance 0)
		)
		(min_thickness 0.25)
		(keepout
			(tracks not_allowed)
			(vias allowed)
			(pads allowed)
			(copperpour not_allowed)
			(footprints allowed)
		)
		(placement
			(enabled no)
			(sheetname "")
		)
		(fill yes
			(thermal_gap 0.5)
			(thermal_bridge_width 0.5)
			(island_removal_mode 0)
		)
		(polygon
			(pts
				(arc
					(start 12.950698 -44.263056)
					(mid 11.172698 -44.263056)
					(end 12.950698 -44.263056)
				)
			)
		)
	)
	(zone
		(layers "In1.Cu" "In4.Cu")
		(hatch none 0.5)
		(connect_pads
			(clearance 0)
		)
		(min_thickness 0.25)
		(keepout
			(tracks not_allowed)
			(vias allowed)
			(pads allowed)
			(copperpour not_allowed)
			(footprints allowed)
		)
		(placement
			(enabled no)
			(sheetname "")
		)
		(fill yes
			(thermal_gap 0.5)
			(thermal_bridge_width 0.5)
			(island_removal_mode 0)
		)
		(polygon
			(pts
				(arc
					(start 42.789856 -49.921922)
					(mid 41.011856 -49.921922)
					(end 42.789856 -49.921922)
				)
			)
		)
	)
	(zone
		(layers "In1.Cu" "In4.Cu")
		(hatch none 0.5)
		(connect_pads
			(clearance 0)
		)
		(min_thickness 0.25)
		(keepout
			(tracks not_allowed)
			(vias allowed)
			(pads allowed)
			(copperpour not_allowed)
			(footprints allowed)
		)
		(placement
			(enabled no)
			(sheetname "")
		)
		(fill yes
			(thermal_gap 0.5)
			(thermal_bridge_width 0.5)
			(island_removal_mode 0)
		)
		(polygon
			(pts
				(arc
					(start 15.0368 -273.273012)
					(mid 13.2588 -273.273012)
					(end 15.0368 -273.273012)
				)
			)
		)
	)
	(zone
		(layers "In1.Cu" "In4.Cu")
		(hatch none 0.5)
		(connect_pads
			(clearance 0)
		)
		(min_thickness 0.25)
		(keepout
			(tracks not_allowed)
			(vias allowed)
			(pads allowed)
			(copperpour not_allowed)
			(footprints allowed)
		)
		(placement
			(enabled no)
			(sheetname "")
		)
		(fill yes
			(thermal_gap 0.5)
			(thermal_bridge_width 0.5)
			(island_removal_mode 0)
		)
		(polygon
			(pts
				(arc
					(start 32.131 -210.594956)
					(mid 30.353 -210.594956)
					(end 32.131 -210.594956)
				)
			)
		)
	)
	(zone
		(layers "In1.Cu" "In4.Cu")
		(hatch none 0.5)
		(connect_pads
			(clearance 0)
		)
		(min_thickness 0.25)
		(keepout
			(tracks not_allowed)
			(vias allowed)
			(pads allowed)
			(copperpour not_allowed)
			(footprints allowed)
		)
		(placement
			(enabled no)
			(sheetname "")
		)
		(fill yes
			(thermal_gap 0.5)
			(thermal_bridge_width 0.5)
			(island_removal_mode 0)
		)
		(polygon
			(pts
				(arc
					(start 16.04899 -79.886048)
					(mid 14.27099 -79.886048)
					(end 16.04899 -79.886048)
				)
			)
		)
	)
	(zone
		(layers "In1.Cu" "In4.Cu")
		(hatch none 0.5)
		(connect_pads
			(clearance 0)
		)
		(min_thickness 0.25)
		(keepout
			(tracks not_allowed)
			(vias allowed)
			(pads allowed)
			(copperpour not_allowed)
			(footprints allowed)
		)
		(placement
			(enabled no)
			(sheetname "")
		)
		(fill yes
			(thermal_gap 0.5)
			(thermal_bridge_width 0.5)
			(island_removal_mode 0)
		)
		(polygon
			(pts
				(arc
					(start 44.320714 -110.709964)
					(mid 41.679114 -110.709964)
					(end 44.320714 -110.709964)
				)
			)
		)
	)
	(zone
		(layers "In1.Cu" "In4.Cu")
		(hatch none 0.5)
		(connect_pads
			(clearance 0)
		)
		(min_thickness 0.25)
		(keepout
			(tracks not_allowed)
			(vias allowed)
			(pads allowed)
			(copperpour not_allowed)
			(footprints allowed)
		)
		(placement
			(enabled no)
			(sheetname "")
		)
		(fill yes
			(thermal_gap 0.5)
			(thermal_bridge_width 0.5)
			(island_removal_mode 0)
		)
		(polygon
			(pts
				(arc
					(start 47.487332 -280.330148)
					(mid 45.709332 -280.330148)
					(end 47.487332 -280.330148)
				)
			)
		)
	)
	(zone
		(layers "In1.Cu" "In4.Cu")
		(hatch none 0.5)
		(connect_pads
			(clearance 0)
		)
		(min_thickness 0.25)
		(keepout
			(tracks not_allowed)
			(vias allowed)
			(pads allowed)
			(copperpour not_allowed)
			(footprints allowed)
		)
		(placement
			(enabled no)
			(sheetname "")
		)
		(fill yes
			(thermal_gap 0.5)
			(thermal_bridge_width 0.5)
			(island_removal_mode 0)
		)
		(polygon
			(pts
				(arc
					(start 44.465748 -79.886048)
					(mid 42.687748 -79.886048)
					(end 44.465748 -79.886048)
				)
			)
		)
	)
	(zone
		(layers "In1.Cu" "In4.Cu")
		(hatch none 0.5)
		(connect_pads
			(clearance 0)
		)
		(min_thickness 0.25)
		(keepout
			(tracks not_allowed)
			(vias allowed)
			(pads allowed)
			(copperpour not_allowed)
			(footprints allowed)
		)
		(placement
			(enabled no)
			(sheetname "")
		)
		(fill yes
			(thermal_gap 0.5)
			(thermal_bridge_width 0.5)
			(island_removal_mode 0)
		)
		(polygon
			(pts
				(arc
					(start 21.844 -101.092)
					(mid 20.066 -101.092)
					(end 21.844 -101.092)
				)
			)
		)
	)
	(zone
		(layers "In1.Cu" "In4.Cu")
		(hatch none 0.5)
		(connect_pads
			(clearance 0)
		)
		(min_thickness 0.25)
		(keepout
			(tracks not_allowed)
			(vias allowed)
			(pads allowed)
			(copperpour not_allowed)
			(footprints allowed)
		)
		(placement
			(enabled no)
			(sheetname "")
		)
		(fill yes
			(thermal_gap 0.5)
			(thermal_bridge_width 0.5)
			(island_removal_mode 0)
		)
		(polygon
			(pts
				(arc
					(start 43.605958 -238.7854)
					(mid 41.827958 -238.7854)
					(end 43.605958 -238.7854)
				)
			)
		)
	)
	(zone
		(layers "In1.Cu" "In4.Cu")
		(hatch none 0.5)
		(connect_pads
			(clearance 0)
		)
		(min_thickness 0.25)
		(keepout
			(tracks not_allowed)
			(vias allowed)
			(pads allowed)
			(copperpour not_allowed)
			(footprints allowed)
		)
		(placement
			(enabled no)
			(sheetname "")
		)
		(fill yes
			(thermal_gap 0.5)
			(thermal_bridge_width 0.5)
			(island_removal_mode 0)
		)
		(polygon
			(pts
				(arc
					(start 33.193228 -264.668)
					(mid 31.415228 -264.668)
					(end 33.193228 -264.668)
				)
			)
		)
	)
	(zone
		(layers "In1.Cu" "In4.Cu")
		(hatch none 0.5)
		(connect_pads
			(clearance 0)
		)
		(min_thickness 0.25)
		(keepout
			(tracks not_allowed)
			(vias allowed)
			(pads allowed)
			(copperpour not_allowed)
			(footprints allowed)
		)
		(placement
			(enabled no)
			(sheetname "")
		)
		(fill yes
			(thermal_gap 0.5)
			(thermal_bridge_width 0.5)
			(island_removal_mode 0)
		)
		(polygon
			(pts
				(arc
					(start 38.9636 -92.5322)
					(mid 37.1856 -92.5322)
					(end 38.9636 -92.5322)
				)
			)
		)
	)
	(zone
		(layers "In1.Cu" "In4.Cu")
		(hatch none 0.5)
		(connect_pads
			(clearance 0)
		)
		(min_thickness 0.25)
		(keepout
			(tracks not_allowed)
			(vias allowed)
			(pads allowed)
			(copperpour not_allowed)
			(footprints allowed)
		)
		(placement
			(enabled no)
			(sheetname "")
		)
		(fill yes
			(thermal_gap 0.5)
			(thermal_bridge_width 0.5)
			(island_removal_mode 0)
		)
		(polygon
			(pts
				(arc
					(start 7.693914 -244.31371)
					(mid 5.915914 -244.31371)
					(end 7.693914 -244.31371)
				)
			)
		)
	)
	(zone
		(layers "In1.Cu" "In4.Cu")
		(hatch none 0.5)
		(connect_pads
			(clearance 0)
		)
		(min_thickness 0.25)
		(keepout
			(tracks not_allowed)
			(vias allowed)
			(pads allowed)
			(copperpour not_allowed)
			(footprints allowed)
		)
		(placement
			(enabled no)
			(sheetname "")
		)
		(fill yes
			(thermal_gap 0.5)
			(thermal_bridge_width 0.5)
			(island_removal_mode 0)
		)
		(polygon
			(pts
				(arc
					(start 31.877 -117.602)
					(mid 30.099 -117.602)
					(end 31.877 -117.602)
				)
			)
		)
	)
	(zone
		(layers "In1.Cu" "In4.Cu")
		(hatch none 0.5)
		(connect_pads
			(clearance 0)
		)
		(min_thickness 0.25)
		(keepout
			(tracks not_allowed)
			(vias allowed)
			(pads allowed)
			(copperpour not_allowed)
			(footprints allowed)
		)
		(placement
			(enabled no)
			(sheetname "")
		)
		(fill yes
			(thermal_gap 0.5)
			(thermal_bridge_width 0.5)
			(island_removal_mode 0)
		)
		(polygon
			(pts
				(arc
					(start 15.037054 -272.25244)
					(mid 13.259054 -272.25244)
					(end 15.037054 -272.25244)
				)
			)
		)
	)
	(zone
		(layers "In1.Cu" "In4.Cu")
		(hatch none 0.5)
		(connect_pads
			(clearance 0)
		)
		(min_thickness 0.25)
		(keepout
			(tracks not_allowed)
			(vias allowed)
			(pads allowed)
			(copperpour not_allowed)
			(footprints allowed)
		)
		(placement
			(enabled no)
			(sheetname "")
		)
		(fill yes
			(thermal_gap 0.5)
			(thermal_bridge_width 0.5)
			(island_removal_mode 0)
		)
		(polygon
			(pts
				(arc
					(start 5.884418 -242.878864)
					(mid 4.106418 -242.878864)
					(end 5.884418 -242.878864)
				)
			)
		)
	)
	(zone
		(layers "In1.Cu" "In4.Cu")
		(hatch none 0.5)
		(connect_pads
			(clearance 0)
		)
		(min_thickness 0.25)
		(keepout
			(tracks not_allowed)
			(vias allowed)
			(pads allowed)
			(copperpour not_allowed)
			(footprints allowed)
		)
		(placement
			(enabled no)
			(sheetname "")
		)
		(fill yes
			(thermal_gap 0.5)
			(thermal_bridge_width 0.5)
			(island_removal_mode 0)
		)
		(polygon
			(pts
				(arc
					(start 15.0368 -86.995)
					(mid 13.2588 -86.995)
					(end 15.0368 -86.995)
				)
			)
		)
	)
	(zone
		(layers "In1.Cu" "In4.Cu")
		(hatch none 0.5)
		(connect_pads
			(clearance 0)
		)
		(min_thickness 0.25)
		(keepout
			(tracks not_allowed)
			(vias allowed)
			(pads allowed)
			(copperpour not_allowed)
			(footprints allowed)
		)
		(placement
			(enabled no)
			(sheetname "")
		)
		(fill yes
			(thermal_gap 0.5)
			(thermal_bridge_width 0.5)
			(island_removal_mode 0)
		)
		(polygon
			(pts
				(arc
					(start 39.908988 -244.478556)
					(mid 38.130988 -244.478556)
					(end 39.908988 -244.478556)
				)
			)
		)
	)
	(zone
		(layers "In1.Cu" "In4.Cu")
		(hatch none 0.5)
		(connect_pads
			(clearance 0)
		)
		(min_thickness 0.25)
		(keepout
			(tracks not_allowed)
			(vias allowed)
			(pads allowed)
			(copperpour not_allowed)
			(footprints allowed)
		)
		(placement
			(enabled no)
			(sheetname "")
		)
		(fill yes
			(thermal_gap 0.5)
			(thermal_bridge_width 0.5)
			(island_removal_mode 0)
		)
		(polygon
			(pts
				(arc
					(start 8.020812 -22.409912)
					(mid 5.379212 -22.409912)
					(end 8.020812 -22.409912)
				)
			)
		)
	)
	(zone
		(layers "In1.Cu" "In4.Cu")
		(hatch none 0.5)
		(connect_pads
			(clearance 0)
		)
		(min_thickness 0.25)
		(keepout
			(tracks not_allowed)
			(vias allowed)
			(pads allowed)
			(copperpour not_allowed)
			(footprints allowed)
		)
		(placement
			(enabled no)
			(sheetname "")
		)
		(fill yes
			(thermal_gap 0.5)
			(thermal_bridge_width 0.5)
			(island_removal_mode 0)
		)
		(polygon
			(pts
				(arc
					(start 12.928346 -38.649656)
					(mid 11.150346 -38.649656)
					(end 12.928346 -38.649656)
				)
			)
		)
	)
	(zone
		(layers "In1.Cu" "In4.Cu")
		(hatch none 0.5)
		(connect_pads
			(clearance 0)
		)
		(min_thickness 0.25)
		(keepout
			(tracks not_allowed)
			(vias allowed)
			(pads allowed)
			(copperpour not_allowed)
			(footprints allowed)
		)
		(placement
			(enabled no)
			(sheetname "")
		)
		(fill yes
			(thermal_gap 0.5)
			(thermal_bridge_width 0.5)
			(island_removal_mode 0)
		)
		(polygon
			(pts
				(arc
					(start 39.263828 -244.478556)
					(mid 37.485828 -244.478556)
					(end 39.263828 -244.478556)
				)
			)
		)
	)
	(zone
		(layers "In1.Cu" "In4.Cu")
		(hatch none 0.5)
		(connect_pads
			(clearance 0)
		)
		(min_thickness 0.25)
		(keepout
			(tracks not_allowed)
			(vias allowed)
			(pads allowed)
			(copperpour not_allowed)
			(footprints allowed)
		)
		(placement
			(enabled no)
			(sheetname "")
		)
		(fill yes
			(thermal_gap 0.5)
			(thermal_bridge_width 0.5)
			(island_removal_mode 0)
		)
		(polygon
			(pts
				(arc
					(start 38.903656 -42.022522)
					(mid 37.125656 -42.022522)
					(end 38.903656 -42.022522)
				)
			)
		)
	)
	(zone
		(layers "In1.Cu" "In4.Cu")
		(hatch none 0.5)
		(connect_pads
			(clearance 0)
		)
		(min_thickness 0.25)
		(keepout
			(tracks not_allowed)
			(vias allowed)
			(pads allowed)
			(copperpour not_allowed)
			(footprints allowed)
		)
		(placement
			(enabled no)
			(sheetname "")
		)
		(fill yes
			(thermal_gap 0.5)
			(thermal_bridge_width 0.5)
			(island_removal_mode 0)
		)
		(polygon
			(pts
				(arc
					(start 42.259758 -237.363)
					(mid 40.481758 -237.363)
					(end 42.259758 -237.363)
				)
			)
		)
	)
	(zone
		(layers "In1.Cu" "In4.Cu")
		(hatch none 0.5)
		(connect_pads
			(clearance 0)
		)
		(min_thickness 0.25)
		(keepout
			(tracks not_allowed)
			(vias allowed)
			(pads allowed)
			(copperpour not_allowed)
			(footprints allowed)
		)
		(placement
			(enabled no)
			(sheetname "")
		)
		(fill yes
			(thermal_gap 0.5)
			(thermal_bridge_width 0.5)
			(island_removal_mode 0)
		)
		(polygon
			(pts
				(arc
					(start 38.9636 -88.653112)
					(mid 37.1856 -88.653112)
					(end 38.9636 -88.653112)
				)
			)
		)
	)
	(zone
		(layers "In1.Cu" "In4.Cu")
		(hatch none 0.5)
		(connect_pads
			(clearance 0)
		)
		(min_thickness 0.25)
		(keepout
			(tracks not_allowed)
			(vias allowed)
			(pads allowed)
			(copperpour not_allowed)
			(footprints allowed)
		)
		(placement
			(enabled no)
			(sheetname "")
		)
		(fill yes
			(thermal_gap 0.5)
			(thermal_bridge_width 0.5)
			(island_removal_mode 0)
		)
		(polygon
			(pts
				(arc
					(start 47.207932 -58.503312)
					(mid 45.429932 -58.503312)
					(end 47.207932 -58.503312)
				)
			)
		)
	)
	(zone
		(layers "In1.Cu" "In4.Cu")
		(hatch none 0.5)
		(connect_pads
			(clearance 0)
		)
		(min_thickness 0.25)
		(keepout
			(tracks not_allowed)
			(vias allowed)
			(pads allowed)
			(copperpour not_allowed)
			(footprints allowed)
		)
		(placement
			(enabled no)
			(sheetname "")
		)
		(fill yes
			(thermal_gap 0.5)
			(thermal_bridge_width 0.5)
			(island_removal_mode 0)
		)
		(polygon
			(pts
				(arc
					(start 13.159232 -224.38741)
					(mid 11.381232 -224.38741)
					(end 13.159232 -224.38741)
				)
			)
		)
	)
	(zone
		(layers "In1.Cu" "In4.Cu")
		(hatch none 0.5)
		(connect_pads
			(clearance 0)
		)
		(min_thickness 0.25)
		(keepout
			(tracks not_allowed)
			(vias allowed)
			(pads allowed)
			(copperpour not_allowed)
			(footprints allowed)
		)
		(placement
			(enabled no)
			(sheetname "")
		)
		(fill yes
			(thermal_gap 0.5)
			(thermal_bridge_width 0.5)
			(island_removal_mode 0)
		)
		(polygon
			(pts
				(arc
					(start 40.710612 -263.68629)
					(mid 38.932612 -263.68629)
					(end 40.710612 -263.68629)
				)
			)
		)
	)
	(zone
		(layers "In1.Cu" "In4.Cu")
		(hatch none 0.5)
		(connect_pads
			(clearance 0)
		)
		(min_thickness 0.25)
		(keepout
			(tracks not_allowed)
			(vias allowed)
			(pads allowed)
			(copperpour not_allowed)
			(footprints allowed)
		)
		(placement
			(enabled no)
			(sheetname "")
		)
		(fill yes
			(thermal_gap 0.5)
			(thermal_bridge_width 0.5)
			(island_removal_mode 0)
		)
		(polygon
			(pts
				(arc
					(start 13.202158 -59.298078)
					(mid 11.424158 -59.298078)
					(end 13.202158 -59.298078)
				)
			)
		)
	)
	(zone
		(layers "In1.Cu" "In4.Cu")
		(hatch none 0.5)
		(connect_pads
			(clearance 0)
		)
		(min_thickness 0.25)
		(keepout
			(tracks not_allowed)
			(vias allowed)
			(pads allowed)
			(copperpour not_allowed)
			(footprints allowed)
		)
		(placement
			(enabled no)
			(sheetname "")
		)
		(fill yes
			(thermal_gap 0.5)
			(thermal_bridge_width 0.5)
			(island_removal_mode 0)
		)
		(polygon
			(pts
				(arc
					(start 40.151304 -37.883846)
					(mid 38.373304 -37.883846)
					(end 40.151304 -37.883846)
				)
			)
		)
	)
	(zone
		(layers "In1.Cu" "In4.Cu")
		(hatch none 0.5)
		(connect_pads
			(clearance 0)
		)
		(min_thickness 0.25)
		(keepout
			(tracks not_allowed)
			(vias allowed)
			(pads allowed)
			(copperpour not_allowed)
			(footprints allowed)
		)
		(placement
			(enabled no)
			(sheetname "")
		)
		(fill yes
			(thermal_gap 0.5)
			(thermal_bridge_width 0.5)
			(island_removal_mode 0)
		)
		(polygon
			(pts
				(arc
					(start 37.301932 -58.278776)
					(mid 35.523932 -58.278776)
					(end 37.301932 -58.278776)
				)
			)
		)
	)
	(zone
		(layers "In1.Cu" "In4.Cu")
		(hatch none 0.5)
		(connect_pads
			(clearance 0)
		)
		(min_thickness 0.25)
		(keepout
			(tracks not_allowed)
			(vias allowed)
			(pads allowed)
			(copperpour not_allowed)
			(footprints allowed)
		)
		(placement
			(enabled no)
			(sheetname "")
		)
		(fill yes
			(thermal_gap 0.5)
			(thermal_bridge_width 0.5)
			(island_removal_mode 0)
		)
		(polygon
			(pts
				(arc
					(start 38.954456 -227.61321)
					(mid 37.176456 -227.61321)
					(end 38.954456 -227.61321)
				)
			)
		)
	)
	(zone
		(layers "In1.Cu" "In4.Cu")
		(hatch none 0.5)
		(connect_pads
			(clearance 0)
		)
		(min_thickness 0.25)
		(keepout
			(tracks not_allowed)
			(vias allowed)
			(pads allowed)
			(copperpour not_allowed)
			(footprints allowed)
		)
		(placement
			(enabled no)
			(sheetname "")
		)
		(fill yes
			(thermal_gap 0.5)
			(thermal_bridge_width 0.5)
			(island_removal_mode 0)
		)
		(polygon
			(pts
				(arc
					(start 10.837418 -243.4336)
					(mid 9.059418 -243.4336)
					(end 10.837418 -243.4336)
				)
			)
		)
	)
	(zone
		(layers "In1.Cu" "In4.Cu")
		(hatch none 0.5)
		(connect_pads
			(clearance 0)
		)
		(min_thickness 0.25)
		(keepout
			(tracks not_allowed)
			(vias allowed)
			(pads allowed)
			(copperpour not_allowed)
			(footprints allowed)
		)
		(placement
			(enabled no)
			(sheetname "")
		)
		(fill yes
			(thermal_gap 0.5)
			(thermal_bridge_width 0.5)
			(island_removal_mode 0)
		)
		(polygon
			(pts
				(arc
					(start 21.336 -18.796)
					(mid 19.558 -18.796)
					(end 21.336 -18.796)
				)
			)
		)
	)
	(zone
		(layers "In1.Cu" "In4.Cu")
		(hatch none 0.5)
		(connect_pads
			(clearance 0)
		)
		(min_thickness 0.25)
		(keepout
			(tracks not_allowed)
			(vias allowed)
			(pads allowed)
			(copperpour not_allowed)
			(footprints allowed)
		)
		(placement
			(enabled no)
			(sheetname "")
		)
		(fill yes
			(thermal_gap 0.5)
			(thermal_bridge_width 0.5)
			(island_removal_mode 0)
		)
		(polygon
			(pts
				(arc
					(start 34.768028 -264.668)
					(mid 32.990028 -264.668)
					(end 34.768028 -264.668)
				)
			)
		)
	)
	(zone
		(layers "In1.Cu" "In4.Cu")
		(hatch none 0.5)
		(connect_pads
			(clearance 0)
		)
		(min_thickness 0.25)
		(keepout
			(tracks not_allowed)
			(vias allowed)
			(pads allowed)
			(copperpour not_allowed)
			(footprints allowed)
		)
		(placement
			(enabled no)
			(sheetname "")
		)
		(fill yes
			(thermal_gap 0.5)
			(thermal_bridge_width 0.5)
			(island_removal_mode 0)
		)
		(polygon
			(pts
				(arc
					(start 17.33931 -79.886048)
					(mid 15.56131 -79.886048)
					(end 17.33931 -79.886048)
				)
			)
		)
	)
	(zone
		(layers "In1.Cu" "In4.Cu")
		(hatch none 0.5)
		(connect_pads
			(clearance 0)
		)
		(min_thickness 0.25)
		(keepout
			(tracks not_allowed)
			(vias allowed)
			(pads allowed)
			(copperpour not_allowed)
			(footprints allowed)
		)
		(placement
			(enabled no)
			(sheetname "")
		)
		(fill yes
			(thermal_gap 0.5)
			(thermal_bridge_width 0.5)
			(island_removal_mode 0)
		)
		(polygon
			(pts
				(arc
					(start 9.663176 -48.14316)
					(mid 7.885176 -48.14316)
					(end 9.663176 -48.14316)
				)
			)
		)
	)
	(zone
		(layers "In1.Cu" "In4.Cu")
		(hatch none 0.5)
		(connect_pads
			(clearance 0)
		)
		(min_thickness 0.25)
		(keepout
			(tracks not_allowed)
			(vias allowed)
			(pads allowed)
			(copperpour not_allowed)
			(footprints allowed)
		)
		(placement
			(enabled no)
			(sheetname "")
		)
		(fill yes
			(thermal_gap 0.5)
			(thermal_bridge_width 0.5)
			(island_removal_mode 0)
		)
		(polygon
			(pts
				(arc
					(start 7.62 -91.116912)
					(mid 5.842 -91.116912)
					(end 7.62 -91.116912)
				)
			)
		)
	)
	(zone
		(layers "In1.Cu" "In4.Cu")
		(hatch none 0.5)
		(connect_pads
			(clearance 0)
		)
		(min_thickness 0.25)
		(keepout
			(tracks not_allowed)
			(vias allowed)
			(pads allowed)
			(copperpour not_allowed)
			(footprints allowed)
		)
		(placement
			(enabled no)
			(sheetname "")
		)
		(fill yes
			(thermal_gap 0.5)
			(thermal_bridge_width 0.5)
			(island_removal_mode 0)
		)
		(polygon
			(pts
				(arc
					(start 32.258 -15.113)
					(mid 30.48 -15.113)
					(end 32.258 -15.113)
				)
			)
		)
	)
	(zone
		(layers "In1.Cu" "In4.Cu")
		(hatch none 0.5)
		(connect_pads
			(clearance 0)
		)
		(min_thickness 0.25)
		(keepout
			(tracks not_allowed)
			(vias allowed)
			(pads allowed)
			(copperpour not_allowed)
			(footprints allowed)
		)
		(placement
			(enabled no)
			(sheetname "")
		)
		(fill yes
			(thermal_gap 0.5)
			(thermal_bridge_width 0.5)
			(island_removal_mode 0)
		)
		(polygon
			(pts
				(arc
					(start 13.721334 -264.32129)
					(mid 11.943334 -264.32129)
					(end 13.721334 -264.32129)
				)
			)
		)
	)
	(zone
		(layers "In1.Cu" "In4.Cu")
		(hatch none 0.5)
		(connect_pads
			(clearance 0)
		)
		(min_thickness 0.25)
		(keepout
			(tracks not_allowed)
			(vias allowed)
			(pads allowed)
			(copperpour not_allowed)
			(footprints allowed)
		)
		(placement
			(enabled no)
			(sheetname "")
		)
		(fill yes
			(thermal_gap 0.5)
			(thermal_bridge_width 0.5)
			(island_removal_mode 0)
		)
		(polygon
			(pts
				(arc
					(start 5.239258 -242.878864)
					(mid 3.461258 -242.878864)
					(end 5.239258 -242.878864)
				)
			)
		)
	)
	(zone
		(layers "In1.Cu" "In4.Cu")
		(hatch none 0.5)
		(connect_pads
			(clearance 0)
		)
		(min_thickness 0.25)
		(keepout
			(tracks not_allowed)
			(vias allowed)
			(pads allowed)
			(copperpour not_allowed)
			(footprints allowed)
		)
		(placement
			(enabled no)
			(sheetname "")
		)
		(fill yes
			(thermal_gap 0.5)
			(thermal_bridge_width 0.5)
			(island_removal_mode 0)
		)
		(polygon
			(pts
				(arc
					(start 44.320714 -203.010008)
					(mid 41.679114 -203.010008)
					(end 44.320714 -203.010008)
				)
			)
		)
	)
	(zone
		(layers "In1.Cu" "In4.Cu")
		(hatch none 0.5)
		(connect_pads
			(clearance 0)
		)
		(min_thickness 0.25)
		(keepout
			(tracks not_allowed)
			(vias allowed)
			(pads allowed)
			(copperpour not_allowed)
			(footprints allowed)
		)
		(placement
			(enabled no)
			(sheetname "")
		)
		(fill yes
			(thermal_gap 0.5)
			(thermal_bridge_width 0.5)
			(island_removal_mode 0)
		)
		(polygon
			(pts
				(arc
					(start 9.64692 -51.369722)
					(mid 7.86892 -51.369722)
					(end 9.64692 -51.369722)
				)
			)
		)
	)
	(zone
		(layers "In1.Cu" "In4.Cu")
		(hatch none 0.5)
		(connect_pads
			(clearance 0)
		)
		(min_thickness 0.25)
		(keepout
			(tracks not_allowed)
			(vias allowed)
			(pads allowed)
			(copperpour not_allowed)
			(footprints allowed)
		)
		(placement
			(enabled no)
			(sheetname "")
		)
		(fill yes
			(thermal_gap 0.5)
			(thermal_bridge_width 0.5)
			(island_removal_mode 0)
		)
		(polygon
			(pts
				(arc
					(start 28.067 -98.933)
					(mid 26.289 -98.933)
					(end 28.067 -98.933)
				)
			)
		)
	)
	(zone
		(layers "In1.Cu" "In4.Cu")
		(hatch none 0.5)
		(connect_pads
			(clearance 0)
		)
		(min_thickness 0.25)
		(keepout
			(tracks not_allowed)
			(vias allowed)
			(pads allowed)
			(copperpour not_allowed)
			(footprints allowed)
		)
		(placement
			(enabled no)
			(sheetname "")
		)
		(fill yes
			(thermal_gap 0.5)
			(thermal_bridge_width 0.5)
			(island_removal_mode 0)
		)
		(polygon
			(pts
				(arc
					(start 13.604494 -79.086202)
					(mid 11.826494 -79.086202)
					(end 13.604494 -79.086202)
				)
			)
		)
	)
	(zone
		(layers "In1.Cu" "In4.Cu")
		(hatch none 0.5)
		(connect_pads
			(clearance 0)
		)
		(min_thickness 0.25)
		(keepout
			(tracks not_allowed)
			(vias allowed)
			(pads allowed)
			(copperpour not_allowed)
			(footprints allowed)
		)
		(placement
			(enabled no)
			(sheetname "")
		)
		(fill yes
			(thermal_gap 0.5)
			(thermal_bridge_width 0.5)
			(island_removal_mode 0)
		)
		(polygon
			(pts
				(arc
					(start 4.315968 -267.146024)
					(mid 2.537968 -267.146024)
					(end 4.315968 -267.146024)
				)
			)
		)
	)
	(zone
		(layers "In1.Cu" "In4.Cu")
		(hatch none 0.5)
		(connect_pads
			(clearance 0)
		)
		(min_thickness 0.25)
		(keepout
			(tracks not_allowed)
			(vias allowed)
			(pads allowed)
			(copperpour not_allowed)
			(footprints allowed)
		)
		(placement
			(enabled no)
			(sheetname "")
		)
		(fill yes
			(thermal_gap 0.5)
			(thermal_bridge_width 0.5)
			(island_removal_mode 0)
		)
		(polygon
			(pts
				(arc
					(start 12.166346 -38.649656)
					(mid 10.388346 -38.649656)
					(end 12.166346 -38.649656)
				)
			)
		)
	)
	(zone
		(layers "In1.Cu" "In4.Cu")
		(hatch none 0.5)
		(connect_pads
			(clearance 0)
		)
		(min_thickness 0.25)
		(keepout
			(tracks not_allowed)
			(vias allowed)
			(pads allowed)
			(copperpour not_allowed)
			(footprints allowed)
		)
		(placement
			(enabled no)
			(sheetname "")
		)
		(fill yes
			(thermal_gap 0.5)
			(thermal_bridge_width 0.5)
			(island_removal_mode 0)
		)
		(polygon
			(pts
				(arc
					(start 20.193 -33.909)
					(mid 18.415 -33.909)
					(end 20.193 -33.909)
				)
			)
		)
	)
	(zone
		(layers "In1.Cu" "In4.Cu")
		(hatch none 0.5)
		(connect_pads
			(clearance 0)
		)
		(min_thickness 0.25)
		(keepout
			(tracks not_allowed)
			(vias allowed)
			(pads allowed)
			(copperpour not_allowed)
			(footprints allowed)
		)
		(placement
			(enabled no)
			(sheetname "")
		)
		(fill yes
			(thermal_gap 0.5)
			(thermal_bridge_width 0.5)
			(island_removal_mode 0)
		)
		(polygon
			(pts
				(arc
					(start 6.26999 -80.067912)
					(mid 4.49199 -80.067912)
					(end 6.26999 -80.067912)
				)
			)
		)
	)
	(zone
		(layers "In1.Cu" "In4.Cu")
		(hatch none 0.5)
		(connect_pads
			(clearance 0)
		)
		(min_thickness 0.25)
		(keepout
			(tracks not_allowed)
			(vias allowed)
			(pads allowed)
			(copperpour not_allowed)
			(footprints allowed)
		)
		(placement
			(enabled no)
			(sheetname "")
		)
		(fill yes
			(thermal_gap 0.5)
			(thermal_bridge_width 0.5)
			(island_removal_mode 0)
		)
		(polygon
			(pts
				(arc
					(start 47.207932 -57.741312)
					(mid 45.429932 -57.741312)
					(end 47.207932 -57.741312)
				)
			)
		)
	)
	(zone
		(layers "In1.Cu" "In4.Cu")
		(hatch none 0.5)
		(connect_pads
			(clearance 0)
		)
		(min_thickness 0.25)
		(keepout
			(tracks not_allowed)
			(vias allowed)
			(pads allowed)
			(copperpour not_allowed)
			(footprints allowed)
		)
		(placement
			(enabled no)
			(sheetname "")
		)
		(fill yes
			(thermal_gap 0.5)
			(thermal_bridge_width 0.5)
			(island_removal_mode 0)
		)
		(polygon
			(pts
				(arc
					(start 38.857428 -264.922)
					(mid 37.079428 -264.922)
					(end 38.857428 -264.922)
				)
			)
		)
	)
	(zone
		(layers "In1.Cu" "In4.Cu")
		(hatch none 0.5)
		(connect_pads
			(clearance 0)
		)
		(min_thickness 0.25)
		(keepout
			(tracks not_allowed)
			(vias allowed)
			(pads allowed)
			(copperpour not_allowed)
			(footprints allowed)
		)
		(placement
			(enabled no)
			(sheetname "")
		)
		(fill yes
			(thermal_gap 0.5)
			(thermal_bridge_width 0.5)
			(island_removal_mode 0)
		)
		(polygon
			(pts
				(arc
					(start 38.095428 -80.321912)
					(mid 36.317428 -80.321912)
					(end 38.095428 -80.321912)
				)
			)
		)
	)
	(zone
		(layers "In1.Cu" "In4.Cu")
		(hatch none 0.5)
		(connect_pads
			(clearance 0)
		)
		(min_thickness 0.25)
		(keepout
			(tracks not_allowed)
			(vias allowed)
			(pads allowed)
			(copperpour not_allowed)
			(footprints allowed)
		)
		(placement
			(enabled no)
			(sheetname "")
		)
		(fill yes
			(thermal_gap 0.5)
			(thermal_bridge_width 0.5)
			(island_removal_mode 0)
		)
		(polygon
			(pts
				(arc
					(start 20.066 -216.535)
					(mid 18.288 -216.535)
					(end 20.066 -216.535)
				)
			)
		)
	)
	(zone
		(layers "In1.Cu" "In4.Cu")
		(hatch none 0.5)
		(connect_pads
			(clearance 0)
		)
		(min_thickness 0.25)
		(keepout
			(tracks not_allowed)
			(vias allowed)
			(pads allowed)
			(copperpour not_allowed)
			(footprints allowed)
		)
		(placement
			(enabled no)
			(sheetname "")
		)
		(fill yes
			(thermal_gap 0.5)
			(thermal_bridge_width 0.5)
			(island_removal_mode 0)
		)
		(polygon
			(pts
				(arc
					(start 6.32079 -263.8806)
					(mid 4.54279 -263.8806)
					(end 6.32079 -263.8806)
				)
			)
		)
	)
	(zone
		(layers "In1.Cu" "In4.Cu")
		(hatch none 0.5)
		(connect_pads
			(clearance 0)
		)
		(min_thickness 0.25)
		(keepout
			(tracks not_allowed)
			(vias allowed)
			(pads allowed)
			(copperpour not_allowed)
			(footprints allowed)
		)
		(placement
			(enabled no)
			(sheetname "")
		)
		(fill yes
			(thermal_gap 0.5)
			(thermal_bridge_width 0.5)
			(island_removal_mode 0)
		)
		(polygon
			(pts
				(arc
					(start 13.159232 -223.62541)
					(mid 11.381232 -223.62541)
					(end 13.159232 -223.62541)
				)
			)
		)
	)
	(zone
		(layers "In1.Cu" "In4.Cu")
		(hatch none 0.5)
		(connect_pads
			(clearance 0)
		)
		(min_thickness 0.25)
		(keepout
			(tracks not_allowed)
			(vias allowed)
			(pads allowed)
			(copperpour not_allowed)
			(footprints allowed)
		)
		(placement
			(enabled no)
			(sheetname "")
		)
		(fill yes
			(thermal_gap 0.5)
			(thermal_bridge_width 0.5)
			(island_removal_mode 0)
		)
		(polygon
			(pts
				(arc
					(start 15.358618 -62.541912)
					(mid 13.580618 -62.541912)
					(end 15.358618 -62.541912)
				)
			)
		)
	)
	(zone
		(layers "In1.Cu" "In4.Cu")
		(hatch none 0.5)
		(connect_pads
			(clearance 0)
		)
		(min_thickness 0.25)
		(keepout
			(tracks not_allowed)
			(vias allowed)
			(pads allowed)
			(copperpour not_allowed)
			(footprints allowed)
		)
		(placement
			(enabled no)
			(sheetname "")
		)
		(fill yes
			(thermal_gap 0.5)
			(thermal_bridge_width 0.5)
			(island_removal_mode 0)
		)
		(polygon
			(pts
				(arc
					(start 44.320714 -18.40992)
					(mid 41.679114 -18.40992)
					(end 44.320714 -18.40992)
				)
			)
		)
	)
	(zone
		(layers "In1.Cu" "In4.Cu")
		(hatch none 0.5)
		(connect_pads
			(clearance 0)
		)
		(min_thickness 0.25)
		(keepout
			(tracks not_allowed)
			(vias allowed)
			(pads allowed)
			(copperpour not_allowed)
			(footprints allowed)
		)
		(placement
			(enabled no)
			(sheetname "")
		)
		(fill yes
			(thermal_gap 0.5)
			(thermal_bridge_width 0.5)
			(island_removal_mode 0)
		)
		(polygon
			(pts
				(arc
					(start 9.17575 -235.773214)
					(mid 7.39775 -235.773214)
					(end 9.17575 -235.773214)
				)
			)
		)
	)
	(zone
		(layers "In1.Cu" "In4.Cu")
		(hatch none 0.5)
		(connect_pads
			(clearance 0)
		)
		(min_thickness 0.25)
		(keepout
			(tracks not_allowed)
			(vias allowed)
			(pads allowed)
			(copperpour not_allowed)
			(footprints allowed)
		)
		(placement
			(enabled no)
			(sheetname "")
		)
		(fill yes
			(thermal_gap 0.5)
			(thermal_bridge_width 0.5)
			(island_removal_mode 0)
		)
		(polygon
			(pts
				(arc
					(start 32.258 -288.925)
					(mid 30.48 -288.925)
					(end 32.258 -288.925)
				)
			)
		)
	)
	(zone
		(layers "In1.Cu" "In4.Cu")
		(hatch none 0.5)
		(connect_pads
			(clearance 0)
		)
		(min_thickness 0.25)
		(keepout
			(tracks not_allowed)
			(vias allowed)
			(pads allowed)
			(copperpour not_allowed)
			(footprints allowed)
		)
		(placement
			(enabled no)
			(sheetname "")
		)
		(fill yes
			(thermal_gap 0.5)
			(thermal_bridge_width 0.5)
			(island_removal_mode 0)
		)
		(polygon
			(pts
				(arc
					(start 10.020808 -297.310048)
					(mid 7.379208 -297.310048)
					(end 10.020808 -297.310048)
				)
			)
		)
	)
	(zone
		(layers "In1.Cu" "In4.Cu")
		(hatch none 0.5)
		(connect_pads
			(clearance 0)
		)
		(min_thickness 0.25)
		(keepout
			(tracks not_allowed)
			(vias allowed)
			(pads allowed)
			(copperpour not_allowed)
			(footprints allowed)
		)
		(placement
			(enabled no)
			(sheetname "")
		)
		(fill yes
			(thermal_gap 0.5)
			(thermal_bridge_width 0.5)
			(island_removal_mode 0)
		)
		(polygon
			(pts
				(arc
					(start 16.04899 -80.521048)
					(mid 14.27099 -80.521048)
					(end 16.04899 -80.521048)
				)
			)
		)
	)
	(zone
		(layers "In1.Cu" "In4.Cu")
		(hatch none 0.5)
		(connect_pads
			(clearance 0)
		)
		(min_thickness 0.25)
		(keepout
			(tracks not_allowed)
			(vias allowed)
			(pads allowed)
			(copperpour not_allowed)
			(footprints allowed)
		)
		(placement
			(enabled no)
			(sheetname "")
		)
		(fill yes
			(thermal_gap 0.5)
			(thermal_bridge_width 0.5)
			(island_removal_mode 0)
		)
		(polygon
			(pts
				(arc
					(start 10.020808 -112.70996)
					(mid 7.379208 -112.70996)
					(end 10.020808 -112.70996)
				)
			)
		)
	)
	(zone
		(layers "In1.Cu" "In4.Cu")
		(hatch none 0.5)
		(connect_pads
			(clearance 0)
		)
		(min_thickness 0.25)
		(keepout
			(tracks not_allowed)
			(vias allowed)
			(pads allowed)
			(copperpour not_allowed)
			(footprints allowed)
		)
		(placement
			(enabled no)
			(sheetname "")
		)
		(fill yes
			(thermal_gap 0.5)
			(thermal_bridge_width 0.5)
			(island_removal_mode 0)
		)
		(polygon
			(pts
				(arc
					(start 7.79399 -79.305912)
					(mid 6.01599 -79.305912)
					(end 7.79399 -79.305912)
				)
			)
		)
	)
	(zone
		(layers "In1.Cu" "In4.Cu")
		(hatch none 0.5)
		(connect_pads
			(clearance 0)
		)
		(min_thickness 0.25)
		(keepout
			(tracks not_allowed)
			(vias allowed)
			(pads allowed)
			(copperpour not_allowed)
			(footprints allowed)
		)
		(placement
			(enabled no)
			(sheetname "")
		)
		(fill yes
			(thermal_gap 0.5)
			(thermal_bridge_width 0.5)
			(island_removal_mode 0)
		)
		(polygon
			(pts
				(arc
					(start 48.096932 -91.38666)
					(mid 46.318932 -91.38666)
					(end 48.096932 -91.38666)
				)
			)
		)
	)
	(zone
		(layers "In1.Cu" "In4.Cu")
		(hatch none 0.5)
		(connect_pads
			(clearance 0)
		)
		(min_thickness 0.25)
		(keepout
			(tracks not_allowed)
			(vias allowed)
			(pads allowed)
			(copperpour not_allowed)
			(footprints allowed)
		)
		(placement
			(enabled no)
			(sheetname "")
		)
		(fill yes
			(thermal_gap 0.5)
			(thermal_bridge_width 0.5)
			(island_removal_mode 0)
		)
		(polygon
			(pts
				(arc
					(start 46.32071 -108.709968)
					(mid 43.67911 -108.709968)
					(end 46.32071 -108.709968)
				)
			)
		)
	)
	(zone
		(layers "In1.Cu" "In4.Cu")
		(hatch none 0.5)
		(connect_pads
			(clearance 0)
		)
		(min_thickness 0.25)
		(keepout
			(tracks not_allowed)
			(vias allowed)
			(pads allowed)
			(copperpour not_allowed)
			(footprints allowed)
		)
		(placement
			(enabled no)
			(sheetname "")
		)
		(fill yes
			(thermal_gap 0.5)
			(thermal_bridge_width 0.5)
			(island_removal_mode 0)
		)
		(polygon
			(pts
				(arc
					(start 6.858 -91.116912)
					(mid 5.08 -91.116912)
					(end 6.858 -91.116912)
				)
			)
		)
	)
	(zone
		(layers "In1.Cu" "In4.Cu")
		(hatch none 0.5)
		(connect_pads
			(clearance 0)
		)
		(min_thickness 0.25)
		(keepout
			(tracks not_allowed)
			(vias allowed)
			(pads allowed)
			(copperpour not_allowed)
			(footprints allowed)
		)
		(placement
			(enabled no)
			(sheetname "")
		)
		(fill yes
			(thermal_gap 0.5)
			(thermal_bridge_width 0.5)
			(island_removal_mode 0)
		)
		(polygon
			(pts
				(arc
					(start 45.810932 -91.38666)
					(mid 44.032932 -91.38666)
					(end 45.810932 -91.38666)
				)
			)
		)
	)
	(zone
		(layers "In1.Cu" "In4.Cu")
		(hatch none 0.5)
		(connect_pads
			(clearance 0)
		)
		(min_thickness 0.25)
		(keepout
			(tracks not_allowed)
			(vias allowed)
			(pads allowed)
			(copperpour not_allowed)
			(footprints allowed)
		)
		(placement
			(enabled no)
			(sheetname "")
		)
		(fill yes
			(thermal_gap 0.5)
			(thermal_bridge_width 0.5)
			(island_removal_mode 0)
		)
		(polygon
			(pts
				(arc
					(start 42.764456 -52.182522)
					(mid 40.986456 -52.182522)
					(end 42.764456 -52.182522)
				)
			)
		)
	)
	(zone
		(layers "In1.Cu" "In4.Cu")
		(hatch none 0.5)
		(connect_pads
			(clearance 0)
		)
		(min_thickness 0.25)
		(keepout
			(tracks not_allowed)
			(vias allowed)
			(pads allowed)
			(copperpour not_allowed)
			(footprints allowed)
		)
		(placement
			(enabled no)
			(sheetname "")
		)
		(fill yes
			(thermal_gap 0.5)
			(thermal_bridge_width 0.5)
			(island_removal_mode 0)
		)
		(polygon
			(pts
				(arc
					(start 13.266674 -246.965978)
					(mid 11.488674 -246.965978)
					(end 13.266674 -246.965978)
				)
			)
		)
	)
	(zone
		(layers "In1.Cu" "In4.Cu")
		(hatch none 0.5)
		(connect_pads
			(clearance 0)
		)
		(min_thickness 0.25)
		(keepout
			(tracks not_allowed)
			(vias allowed)
			(pads allowed)
			(copperpour not_allowed)
			(footprints allowed)
		)
		(placement
			(enabled no)
			(sheetname "")
		)
		(fill yes
			(thermal_gap 0.5)
			(thermal_bridge_width 0.5)
			(island_removal_mode 0)
		)
		(polygon
			(pts
				(arc
					(start 7.896098 -238.20501)
					(mid 6.118098 -238.20501)
					(end 7.896098 -238.20501)
				)
			)
		)
	)
	(zone
		(layers "In1.Cu" "In4.Cu")
		(hatch none 0.5)
		(connect_pads
			(clearance 0)
		)
		(min_thickness 0.25)
		(keepout
			(tracks not_allowed)
			(vias allowed)
			(pads allowed)
			(copperpour not_allowed)
			(footprints allowed)
		)
		(placement
			(enabled no)
			(sheetname "")
		)
		(fill yes
			(thermal_gap 0.5)
			(thermal_bridge_width 0.5)
			(island_removal_mode 0)
		)
		(polygon
			(pts
				(arc
					(start 45.100748 -80.521048)
					(mid 43.322748 -80.521048)
					(end 45.100748 -80.521048)
				)
			)
		)
	)
	(zone
		(layers "In1.Cu" "In4.Cu")
		(hatch none 0.5)
		(connect_pads
			(clearance 0)
		)
		(min_thickness 0.25)
		(keepout
			(tracks not_allowed)
			(vias allowed)
			(pads allowed)
			(copperpour not_allowed)
			(footprints allowed)
		)
		(placement
			(enabled no)
			(sheetname "")
		)
		(fill yes
			(thermal_gap 0.5)
			(thermal_bridge_width 0.5)
			(island_removal_mode 0)
		)
		(polygon
			(pts
				(arc
					(start 6.096 -91.116912)
					(mid 4.318 -91.116912)
					(end 6.096 -91.116912)
				)
			)
		)
	)
	(zone
		(layers "In1.Cu" "In4.Cu")
		(hatch none 0.5)
		(connect_pads
			(clearance 0)
		)
		(min_thickness 0.25)
		(keepout
			(tracks not_allowed)
			(vias allowed)
			(pads allowed)
			(copperpour not_allowed)
			(footprints allowed)
		)
		(placement
			(enabled no)
			(sheetname "")
		)
		(fill yes
			(thermal_gap 0.5)
			(thermal_bridge_width 0.5)
			(island_removal_mode 0)
		)
		(polygon
			(pts
				(arc
					(start 14.239494 -79.086202)
					(mid 12.461494 -79.086202)
					(end 14.239494 -79.086202)
				)
			)
		)
	)
	(zone
		(layers "In1.Cu" "In4.Cu")
		(hatch none 0.5)
		(connect_pads
			(clearance 0)
		)
		(min_thickness 0.25)
		(keepout
			(tracks not_allowed)
			(vias allowed)
			(pads allowed)
			(copperpour not_allowed)
			(footprints allowed)
		)
		(placement
			(enabled no)
			(sheetname "")
		)
		(fill yes
			(thermal_gap 0.5)
			(thermal_bridge_width 0.5)
			(island_removal_mode 0)
		)
		(polygon
			(pts
				(arc
					(start 48.300132 -246.126)
					(mid 46.522132 -246.126)
					(end 48.300132 -246.126)
				)
			)
		)
	)
	(zone
		(layers "In1.Cu" "In4.Cu")
		(hatch none 0.5)
		(connect_pads
			(clearance 0)
		)
		(min_thickness 0.25)
		(keepout
			(tracks not_allowed)
			(vias allowed)
			(pads allowed)
			(copperpour not_allowed)
			(footprints allowed)
		)
		(placement
			(enabled no)
			(sheetname "")
		)
		(fill yes
			(thermal_gap 0.5)
			(thermal_bridge_width 0.5)
			(island_removal_mode 0)
		)
		(polygon
			(pts
				(arc
					(start 14.351 -93.344238)
					(mid 12.573 -93.344238)
					(end 14.351 -93.344238)
				)
			)
		)
	)
	(zone
		(layers "In1.Cu" "In4.Cu")
		(hatch none 0.5)
		(connect_pads
			(clearance 0)
		)
		(min_thickness 0.25)
		(keepout
			(tracks not_allowed)
			(vias allowed)
			(pads allowed)
			(copperpour not_allowed)
			(footprints allowed)
		)
		(placement
			(enabled no)
			(sheetname "")
		)
		(fill yes
			(thermal_gap 0.5)
			(thermal_bridge_width 0.5)
			(island_removal_mode 0)
		)
		(polygon
			(pts
				(arc
					(start 43.704256 -55.255922)
					(mid 41.926256 -55.255922)
					(end 43.704256 -55.255922)
				)
			)
		)
	)
	(zone
		(layers "In1.Cu" "In4.Cu")
		(hatch none 0.5)
		(connect_pads
			(clearance 0)
		)
		(min_thickness 0.25)
		(keepout
			(tracks not_allowed)
			(vias allowed)
			(pads allowed)
			(copperpour not_allowed)
			(footprints allowed)
		)
		(placement
			(enabled no)
			(sheetname "")
		)
		(fill yes
			(thermal_gap 0.5)
			(thermal_bridge_width 0.5)
			(island_removal_mode 0)
		)
		(polygon
			(pts
				(arc
					(start 34.768028 -267.97)
					(mid 32.990028 -267.97)
					(end 34.768028 -267.97)
				)
			)
		)
	)
	(zone
		(layers "In1.Cu" "In4.Cu")
		(hatch none 0.5)
		(connect_pads
			(clearance 0)
		)
		(min_thickness 0.25)
		(keepout
			(tracks not_allowed)
			(vias allowed)
			(pads allowed)
			(copperpour not_allowed)
			(footprints allowed)
		)
		(placement
			(enabled no)
			(sheetname "")
		)
		(fill yes
			(thermal_gap 0.5)
			(thermal_bridge_width 0.5)
			(island_removal_mode 0)
		)
		(polygon
			(pts
				(arc
					(start 9.62152 -46.391322)
					(mid 7.84352 -46.391322)
					(end 9.62152 -46.391322)
				)
			)
		)
	)
	(zone
		(layers "In1.Cu" "In4.Cu")
		(hatch none 0.5)
		(connect_pads
			(clearance 0)
		)
		(min_thickness 0.25)
		(keepout
			(tracks not_allowed)
			(vias allowed)
			(pads allowed)
			(copperpour not_allowed)
			(footprints allowed)
		)
		(placement
			(enabled no)
			(sheetname "")
		)
		(fill yes
			(thermal_gap 0.5)
			(thermal_bridge_width 0.5)
			(island_removal_mode 0)
		)
		(polygon
			(pts
				(arc
					(start 7.15899 -264.6172)
					(mid 5.38099 -264.6172)
					(end 7.15899 -264.6172)
				)
			)
		)
	)
	(zone
		(layers "In1.Cu" "In4.Cu")
		(hatch none 0.5)
		(connect_pads
			(clearance 0)
		)
		(min_thickness 0.25)
		(keepout
			(tracks not_allowed)
			(vias allowed)
			(pads allowed)
			(copperpour not_allowed)
			(footprints allowed)
		)
		(placement
			(enabled no)
			(sheetname "")
		)
		(fill yes
			(thermal_gap 0.5)
			(thermal_bridge_width 0.5)
			(island_removal_mode 0)
		)
		(polygon
			(pts
				(arc
					(start 42.789856 -50.683922)
					(mid 41.011856 -50.683922)
					(end 42.789856 -50.683922)
				)
			)
		)
	)
	(zone
		(layers "In1.Cu" "In4.Cu")
		(hatch none 0.5)
		(connect_pads
			(clearance 0)
		)
		(min_thickness 0.25)
		(keepout
			(tracks not_allowed)
			(vias allowed)
			(pads allowed)
			(copperpour not_allowed)
			(footprints allowed)
		)
		(placement
			(enabled no)
			(sheetname "")
		)
		(fill yes
			(thermal_gap 0.5)
			(thermal_bridge_width 0.5)
			(island_removal_mode 0)
		)
		(polygon
			(pts
				(arc
					(start 44.455588 -80.521048)
					(mid 42.677588 -80.521048)
					(end 44.455588 -80.521048)
				)
			)
		)
	)
	(zone
		(layers "In1.Cu" "In4.Cu")
		(hatch none 0.5)
		(connect_pads
			(clearance 0)
		)
		(min_thickness 0.25)
		(keepout
			(tracks not_allowed)
			(vias allowed)
			(pads allowed)
			(copperpour not_allowed)
			(footprints allowed)
		)
		(placement
			(enabled no)
			(sheetname "")
		)
		(fill yes
			(thermal_gap 0.5)
			(thermal_bridge_width 0.5)
			(island_removal_mode 0)
		)
		(polygon
			(pts
				(arc
					(start 5.50799 -80.067912)
					(mid 3.72999 -80.067912)
					(end 5.50799 -80.067912)
				)
			)
		)
	)
	(zone
		(layers "In1.Cu" "In4.Cu")
		(hatch none 0.5)
		(connect_pads
			(clearance 0)
		)
		(min_thickness 0.25)
		(keepout
			(tracks not_allowed)
			(vias allowed)
			(pads allowed)
			(copperpour not_allowed)
			(footprints allowed)
		)
		(placement
			(enabled no)
			(sheetname "")
		)
		(fill yes
			(thermal_gap 0.5)
			(thermal_bridge_width 0.5)
			(island_removal_mode 0)
		)
		(polygon
			(pts
				(arc
					(start 30.734 -101.219)
					(mid 28.956 -101.219)
					(end 30.734 -101.219)
				)
			)
		)
	)
	(zone
		(layers "In1.Cu" "In4.Cu")
		(hatch none 0.5)
		(connect_pads
			(clearance 0)
		)
		(min_thickness 0.25)
		(keepout
			(tracks not_allowed)
			(vias allowed)
			(pads allowed)
			(copperpour not_allowed)
			(footprints allowed)
		)
		(placement
			(enabled no)
			(sheetname "")
		)
		(fill yes
			(thermal_gap 0.5)
			(thermal_bridge_width 0.5)
			(island_removal_mode 0)
		)
		(polygon
			(pts
				(arc
					(start 9.62152 -45.629322)
					(mid 7.84352 -45.629322)
					(end 9.62152 -45.629322)
				)
			)
		)
	)
	(zone
		(layers "In1.Cu" "In4.Cu")
		(hatch none 0.5)
		(connect_pads
			(clearance 0)
		)
		(min_thickness 0.25)
		(keepout
			(tracks not_allowed)
			(vias allowed)
			(pads allowed)
			(copperpour not_allowed)
			(footprints allowed)
		)
		(placement
			(enabled no)
			(sheetname "")
		)
		(fill yes
			(thermal_gap 0.5)
			(thermal_bridge_width 0.5)
			(island_removal_mode 0)
		)
		(polygon
			(pts
				(arc
					(start 14.351 -89.153238)
					(mid 12.573 -89.153238)
					(end 14.351 -89.153238)
				)
			)
		)
	)
	(zone
		(layers "In1.Cu" "In4.Cu")
		(hatch none 0.5)
		(connect_pads
			(clearance 0)
		)
		(min_thickness 0.25)
		(keepout
			(tracks not_allowed)
			(vias allowed)
			(pads allowed)
			(copperpour not_allowed)
			(footprints allowed)
		)
		(placement
			(enabled no)
			(sheetname "")
		)
		(fill yes
			(thermal_gap 0.5)
			(thermal_bridge_width 0.5)
			(island_removal_mode 0)
		)
		(polygon
			(pts
				(arc
					(start 46.572932 -92.02166)
					(mid 44.794932 -92.02166)
					(end 46.572932 -92.02166)
				)
			)
		)
	)
	(zone
		(layers "In1.Cu" "In4.Cu")
		(hatch none 0.5)
		(connect_pads
			(clearance 0)
		)
		(min_thickness 0.25)
		(keepout
			(tracks not_allowed)
			(vias allowed)
			(pads allowed)
			(copperpour not_allowed)
			(footprints allowed)
		)
		(placement
			(enabled no)
			(sheetname "")
		)
		(fill yes
			(thermal_gap 0.5)
			(thermal_bridge_width 0.5)
			(island_removal_mode 0)
		)
		(polygon
			(pts
				(arc
					(start 37.229288 -277.495)
					(mid 35.451288 -277.495)
					(end 37.229288 -277.495)
				)
			)
		)
	)
	(zone
		(layers "In1.Cu" "In4.Cu")
		(hatch none 0.5)
		(connect_pads
			(clearance 0)
		)
		(min_thickness 0.25)
		(keepout
			(tracks not_allowed)
			(vias allowed)
			(pads allowed)
			(copperpour not_allowed)
			(footprints allowed)
		)
		(placement
			(enabled no)
			(sheetname "")
		)
		(fill yes
			(thermal_gap 0.5)
			(thermal_bridge_width 0.5)
			(island_removal_mode 0)
		)
		(polygon
			(pts
				(arc
					(start 8.020812 -207.01)
					(mid 5.379212 -207.01)
					(end 8.020812 -207.01)
				)
			)
		)
	)
	(zone
		(layers "In1.Cu" "In4.Cu")
		(hatch none 0.5)
		(connect_pads
			(clearance 0)
		)
		(min_thickness 0.25)
		(keepout
			(tracks not_allowed)
			(vias allowed)
			(pads allowed)
			(copperpour not_allowed)
			(footprints allowed)
		)
		(placement
			(enabled no)
			(sheetname "")
		)
		(fill yes
			(thermal_gap 0.5)
			(thermal_bridge_width 0.5)
			(island_removal_mode 0)
		)
		(polygon
			(pts
				(arc
					(start 16.129 -202.67295)
					(mid 14.351 -202.67295)
					(end 16.129 -202.67295)
				)
			)
		)
	)
	(zone
		(layers "In1.Cu" "In4.Cu")
		(hatch none 0.5)
		(connect_pads
			(clearance 0)
		)
		(min_thickness 0.25)
		(keepout
			(tracks not_allowed)
			(vias allowed)
			(pads allowed)
			(copperpour not_allowed)
			(footprints allowed)
		)
		(placement
			(enabled no)
			(sheetname "")
		)
		(fill yes
			(thermal_gap 0.5)
			(thermal_bridge_width 0.5)
			(island_removal_mode 0)
		)
		(polygon
			(pts
				(arc
					(start 16.390366 -270.294862)
					(mid 14.612366 -270.294862)
					(end 16.390366 -270.294862)
				)
			)
		)
	)
	(zone
		(layers "In1.Cu" "In4.Cu")
		(hatch none 0.5)
		(connect_pads
			(clearance 0)
		)
		(min_thickness 0.25)
		(keepout
			(tracks not_allowed)
			(vias allowed)
			(pads allowed)
			(copperpour not_allowed)
			(footprints allowed)
		)
		(placement
			(enabled no)
			(sheetname "")
		)
		(fill yes
			(thermal_gap 0.5)
			(thermal_bridge_width 0.5)
			(island_removal_mode 0)
		)
		(polygon
			(pts
				(arc
					(start 40.710612 -264.32129)
					(mid 38.932612 -264.32129)
					(end 40.710612 -264.32129)
				)
			)
		)
	)
	(zone
		(layers "In1.Cu" "In4.Cu")
		(hatch none 0.5)
		(connect_pads
			(clearance 0)
		)
		(min_thickness 0.25)
		(keepout
			(tracks not_allowed)
			(vias allowed)
			(pads allowed)
			(copperpour not_allowed)
			(footprints allowed)
		)
		(placement
			(enabled no)
			(sheetname "")
		)
		(fill yes
			(thermal_gap 0.5)
			(thermal_bridge_width 0.5)
			(island_removal_mode 0)
		)
		(polygon
			(pts
				(arc
					(start 13.964158 -59.298078)
					(mid 12.186158 -59.298078)
					(end 13.964158 -59.298078)
				)
			)
		)
	)
	(zone
		(layers "In1.Cu" "In4.Cu")
		(hatch none 0.5)
		(connect_pads
			(clearance 0)
		)
		(min_thickness 0.25)
		(keepout
			(tracks not_allowed)
			(vias allowed)
			(pads allowed)
			(copperpour not_allowed)
			(footprints allowed)
		)
		(placement
			(enabled no)
			(sheetname "")
		)
		(fill yes
			(thermal_gap 0.5)
			(thermal_bridge_width 0.5)
			(island_removal_mode 0)
		)
		(polygon
			(pts
				(arc
					(start 16.17599 -264.486136)
					(mid 14.39799 -264.486136)
					(end 16.17599 -264.486136)
				)
			)
		)
	)
	(zone
		(layers "In1.Cu" "In4.Cu")
		(hatch none 0.5)
		(connect_pads
			(clearance 0)
		)
		(min_thickness 0.25)
		(keepout
			(tracks not_allowed)
			(vias allowed)
			(pads allowed)
			(copperpour not_allowed)
			(footprints allowed)
		)
		(placement
			(enabled no)
			(sheetname "")
		)
		(fill yes
			(thermal_gap 0.5)
			(thermal_bridge_width 0.5)
			(island_removal_mode 0)
		)
		(polygon
			(pts
				(arc
					(start 37.229288 -278.765)
					(mid 35.451288 -278.765)
					(end 37.229288 -278.765)
				)
			)
		)
	)
	(zone
		(layers "In1.Cu" "In4.Cu")
		(hatch none 0.5)
		(connect_pads
			(clearance 0)
		)
		(min_thickness 0.25)
		(keepout
			(tracks not_allowed)
			(vias allowed)
			(pads allowed)
			(copperpour not_allowed)
			(footprints allowed)
		)
		(placement
			(enabled no)
			(sheetname "")
		)
		(fill yes
			(thermal_gap 0.5)
			(thermal_bridge_width 0.5)
			(island_removal_mode 0)
		)
		(polygon
			(pts
				(arc
					(start 47.487332 -281.092148)
					(mid 45.709332 -281.092148)
					(end 47.487332 -281.092148)
				)
			)
		)
	)
	(zone
		(layers "In1.Cu" "In4.Cu")
		(hatch none 0.5)
		(connect_pads
			(clearance 0)
		)
		(min_thickness 0.25)
		(keepout
			(tracks not_allowed)
			(vias allowed)
			(pads allowed)
			(copperpour not_allowed)
			(footprints allowed)
		)
		(placement
			(enabled no)
			(sheetname "")
		)
		(fill yes
			(thermal_gap 0.5)
			(thermal_bridge_width 0.5)
			(island_removal_mode 0)
		)
		(polygon
			(pts
				(arc
					(start 9.64692 -50.607722)
					(mid 7.86892 -50.607722)
					(end 9.64692 -50.607722)
				)
			)
		)
	)
	(zone
		(layers "In1.Cu" "In4.Cu")
		(hatch none 0.5)
		(connect_pads
			(clearance 0)
		)
		(min_thickness 0.25)
		(keepout
			(tracks not_allowed)
			(vias allowed)
			(pads allowed)
			(copperpour not_allowed)
			(footprints allowed)
		)
		(placement
			(enabled no)
			(sheetname "")
		)
		(fill yes
			(thermal_gap 0.5)
			(thermal_bridge_width 0.5)
			(island_removal_mode 0)
		)
		(polygon
			(pts
				(arc
					(start 34.544 -25.146)
					(mid 32.766 -25.146)
					(end 34.544 -25.146)
				)
			)
		)
	)
	(zone
		(layers "In1.Cu" "In4.Cu")
		(hatch none 0.5)
		(connect_pads
			(clearance 0)
		)
		(min_thickness 0.25)
		(keepout
			(tracks not_allowed)
			(vias allowed)
			(pads allowed)
			(copperpour not_allowed)
			(footprints allowed)
		)
		(placement
			(enabled no)
			(sheetname "")
		)
		(fill yes
			(thermal_gap 0.5)
			(thermal_bridge_width 0.5)
			(island_removal_mode 0)
		)
		(polygon
			(pts
				(arc
					(start 5.239258 -58.278776)
					(mid 3.461258 -58.278776)
					(end 5.239258 -58.278776)
				)
			)
		)
	)
	(zone
		(layers "In1.Cu" "In4.Cu")
		(hatch none 0.5)
		(connect_pads
			(clearance 0)
		)
		(min_thickness 0.25)
		(keepout
			(tracks not_allowed)
			(vias allowed)
			(pads allowed)
			(copperpour not_allowed)
			(footprints allowed)
		)
		(placement
			(enabled no)
			(sheetname "")
		)
		(fill yes
			(thermal_gap 0.5)
			(thermal_bridge_width 0.5)
			(island_removal_mode 0)
		)
		(polygon
			(pts
				(arc
					(start 38.954456 -226.08921)
					(mid 37.176456 -226.08921)
					(end 38.954456 -226.08921)
				)
			)
		)
	)
	(zone
		(layers "In1.Cu" "In4.Cu")
		(hatch none 0.5)
		(connect_pads
			(clearance 0)
		)
		(min_thickness 0.25)
		(keepout
			(tracks not_allowed)
			(vias allowed)
			(pads allowed)
			(copperpour not_allowed)
			(footprints allowed)
		)
		(placement
			(enabled no)
			(sheetname "")
		)
		(fill yes
			(thermal_gap 0.5)
			(thermal_bridge_width 0.5)
			(island_removal_mode 0)
		)
		(polygon
			(pts
				(arc
					(start 45.100748 -264.486136)
					(mid 43.322748 -264.486136)
					(end 45.100748 -264.486136)
				)
			)
		)
	)
	(zone
		(layers "In1.Cu" "In4.Cu")
		(hatch none 0.5)
		(connect_pads
			(clearance 0)
		)
		(min_thickness 0.25)
		(keepout
			(tracks not_allowed)
			(vias allowed)
			(pads allowed)
			(copperpour not_allowed)
			(footprints allowed)
		)
		(placement
			(enabled no)
			(sheetname "")
		)
		(fill yes
			(thermal_gap 0.5)
			(thermal_bridge_width 0.5)
			(island_removal_mode 0)
		)
		(polygon
			(pts
				(arc
					(start 14.351 -93.979238)
					(mid 12.573 -93.979238)
					(end 14.351 -93.979238)
				)
			)
		)
	)
	(zone
		(layers "In1.Cu" "In4.Cu")
		(hatch none 0.5)
		(connect_pads
			(clearance 0)
		)
		(min_thickness 0.25)
		(keepout
			(tracks not_allowed)
			(vias allowed)
			(pads allowed)
			(copperpour not_allowed)
			(footprints allowed)
		)
		(placement
			(enabled no)
			(sheetname "")
		)
		(fill yes
			(thermal_gap 0.5)
			(thermal_bridge_width 0.5)
			(island_removal_mode 0)
		)
		(polygon
			(pts
				(arc
					(start 13.794232 -223.62541)
					(mid 12.016232 -223.62541)
					(end 13.794232 -223.62541)
				)
			)
		)
	)
	(zone
		(layers "In1.Cu" "In4.Cu")
		(hatch none 0.5)
		(connect_pads
			(clearance 0)
		)
		(min_thickness 0.25)
		(keepout
			(tracks not_allowed)
			(vias allowed)
			(pads allowed)
			(copperpour not_allowed)
			(footprints allowed)
		)
		(placement
			(enabled no)
			(sheetname "")
		)
		(fill yes
			(thermal_gap 0.5)
			(thermal_bridge_width 0.5)
			(island_removal_mode 0)
		)
		(polygon
			(pts
				(arc
					(start 7.896098 -237.44301)
					(mid 6.118098 -237.44301)
					(end 7.896098 -237.44301)
				)
			)
		)
	)
	(zone
		(layers "In1.Cu" "In4.Cu")
		(hatch none 0.5)
		(connect_pads
			(clearance 0)
		)
		(min_thickness 0.25)
		(keepout
			(tracks not_allowed)
			(vias allowed)
			(pads allowed)
			(copperpour not_allowed)
			(footprints allowed)
		)
		(placement
			(enabled no)
			(sheetname "")
		)
		(fill yes
			(thermal_gap 0.5)
			(thermal_bridge_width 0.5)
			(island_removal_mode 0)
		)
		(polygon
			(pts
				(arc
					(start 39.111428 -59.713622)
					(mid 37.333428 -59.713622)
					(end 39.111428 -59.713622)
				)
			)
		)
	)
	(zone
		(layers "In1.Cu" "In4.Cu")
		(hatch none 0.5)
		(connect_pads
			(clearance 0)
		)
		(min_thickness 0.25)
		(keepout
			(tracks not_allowed)
			(vias allowed)
			(pads allowed)
			(copperpour not_allowed)
			(footprints allowed)
		)
		(placement
			(enabled no)
			(sheetname "")
		)
		(fill yes
			(thermal_gap 0.5)
			(thermal_bridge_width 0.5)
			(island_removal_mode 0)
		)
		(polygon
			(pts
				(arc
					(start 12.188698 -43.501056)
					(mid 10.410698 -43.501056)
					(end 12.188698 -43.501056)
				)
			)
		)
	)
	(zone
		(layers "In1.Cu" "In4.Cu")
		(hatch none 0.5)
		(connect_pads
			(clearance 0)
		)
		(min_thickness 0.25)
		(keepout
			(tracks not_allowed)
			(vias allowed)
			(pads allowed)
			(copperpour not_allowed)
			(footprints allowed)
		)
		(placement
			(enabled no)
			(sheetname "")
		)
		(fill yes
			(thermal_gap 0.5)
			(thermal_bridge_width 0.5)
			(island_removal_mode 0)
		)
		(polygon
			(pts
				(arc
					(start 43.810428 -79.886048)
					(mid 42.032428 -79.886048)
					(end 43.810428 -79.886048)
				)
			)
		)
	)
	(zone
		(layers "In1.Cu" "In4.Cu")
		(hatch none 0.5)
		(connect_pads
			(clearance 0)
		)
		(min_thickness 0.25)
		(keepout
			(tracks not_allowed)
			(vias allowed)
			(pads allowed)
			(copperpour not_allowed)
			(footprints allowed)
		)
		(placement
			(enabled no)
			(sheetname "")
		)
		(fill yes
			(thermal_gap 0.5)
			(thermal_bridge_width 0.5)
			(island_removal_mode 0)
		)
		(polygon
			(pts
				(arc
					(start 7.79399 -80.067912)
					(mid 6.01599 -80.067912)
					(end 7.79399 -80.067912)
				)
			)
		)
	)
	(zone
		(layers "In1.Cu" "In4.Cu")
		(hatch none 0.5)
		(connect_pads
			(clearance 0)
		)
		(min_thickness 0.25)
		(keepout
			(tracks not_allowed)
			(vias allowed)
			(pads allowed)
			(copperpour not_allowed)
			(footprints allowed)
		)
		(placement
			(enabled no)
			(sheetname "")
		)
		(fill yes
			(thermal_gap 0.5)
			(thermal_bridge_width 0.5)
			(island_removal_mode 0)
		)
		(polygon
			(pts
				(arc
					(start 39.589456 -226.85121)
					(mid 37.811456 -226.85121)
					(end 39.589456 -226.85121)
				)
			)
		)
	)
	(zone
		(layers "In1.Cu" "In4.Cu")
		(hatch none 0.5)
		(connect_pads
			(clearance 0)
		)
		(min_thickness 0.25)
		(keepout
			(tracks not_allowed)
			(vias allowed)
			(pads allowed)
			(copperpour not_allowed)
			(footprints allowed)
		)
		(placement
			(enabled no)
			(sheetname "")
		)
		(fill yes
			(thermal_gap 0.5)
			(thermal_bridge_width 0.5)
			(island_removal_mode 0)
		)
		(polygon
			(pts
				(arc
					(start 42.762932 -244.2972)
					(mid 40.984932 -244.2972)
					(end 42.762932 -244.2972)
				)
			)
		)
	)
	(zone
		(layers "In1.Cu" "In4.Cu")
		(hatch none 0.5)
		(connect_pads
			(clearance 0)
		)
		(min_thickness 0.25)
		(keepout
			(tracks not_allowed)
			(vias allowed)
			(pads allowed)
			(copperpour not_allowed)
			(footprints allowed)
		)
		(placement
			(enabled no)
			(sheetname "")
		)
		(fill yes
			(thermal_gap 0.5)
			(thermal_bridge_width 0.5)
			(island_removal_mode 0)
		)
		(polygon
			(pts
				(arc
					(start 37.229288 -273.177)
					(mid 35.451288 -273.177)
					(end 37.229288 -273.177)
				)
			)
		)
	)
	(zone
		(layers "In1.Cu" "In4.Cu")
		(hatch none 0.5)
		(connect_pads
			(clearance 0)
		)
		(min_thickness 0.25)
		(keepout
			(tracks not_allowed)
			(vias allowed)
			(pads allowed)
			(copperpour not_allowed)
			(footprints allowed)
		)
		(placement
			(enabled no)
			(sheetname "")
		)
		(fill yes
			(thermal_gap 0.5)
			(thermal_bridge_width 0.5)
			(island_removal_mode 0)
		)
		(polygon
			(pts
				(arc
					(start 42.259758 -236.601)
					(mid 40.481758 -236.601)
					(end 42.259758 -236.601)
				)
			)
		)
	)
	(zone
		(layers "In1.Cu" "In4.Cu")
		(hatch none 0.5)
		(connect_pads
			(clearance 0)
		)
		(min_thickness 0.25)
		(keepout
			(tracks not_allowed)
			(vias allowed)
			(pads allowed)
			(copperpour not_allowed)
			(footprints allowed)
		)
		(placement
			(enabled no)
			(sheetname "")
		)
		(fill yes
			(thermal_gap 0.5)
			(thermal_bridge_width 0.5)
			(island_removal_mode 0)
		)
		(polygon
			(pts
				(arc
					(start 33.269428 -80.067912)
					(mid 31.491428 -80.067912)
					(end 33.269428 -80.067912)
				)
			)
		)
	)
	(zone
		(layers "In1.Cu" "In4.Cu")
		(hatch none 0.5)
		(connect_pads
			(clearance 0)
		)
		(min_thickness 0.25)
		(keepout
			(tracks not_allowed)
			(vias allowed)
			(pads allowed)
			(copperpour not_allowed)
			(footprints allowed)
		)
		(placement
			(enabled no)
			(sheetname "")
		)
		(fill yes
			(thermal_gap 0.5)
			(thermal_bridge_width 0.5)
			(island_removal_mode 0)
		)
		(polygon
			(pts
				(arc
					(start 39.746428 -59.713622)
					(mid 37.968428 -59.713622)
					(end 39.746428 -59.713622)
				)
			)
		)
	)
	(zone
		(layers "In1.Cu" "In4.Cu")
		(hatch none 0.5)
		(connect_pads
			(clearance 0)
		)
		(min_thickness 0.25)
		(keepout
			(tracks not_allowed)
			(vias allowed)
			(pads allowed)
			(copperpour not_allowed)
			(footprints allowed)
		)
		(placement
			(enabled no)
			(sheetname "")
		)
		(fill yes
			(thermal_gap 0.5)
			(thermal_bridge_width 0.5)
			(island_removal_mode 0)
		)
		(polygon
			(pts
				(arc
					(start 46.776132 -242.0366)
					(mid 44.998132 -242.0366)
					(end 46.776132 -242.0366)
				)
			)
		)
	)
	(zone
		(layers "In1.Cu" "In4.Cu")
		(hatch none 0.5)
		(connect_pads
			(clearance 0)
		)
		(min_thickness 0.25)
		(keepout
			(tracks not_allowed)
			(vias allowed)
			(pads allowed)
			(copperpour not_allowed)
			(footprints allowed)
		)
		(placement
			(enabled no)
			(sheetname "")
		)
		(fill yes
			(thermal_gap 0.5)
			(thermal_bridge_width 0.5)
			(island_removal_mode 0)
		)
		(polygon
			(pts
				(arc
					(start 13.241274 -245.010178)
					(mid 11.463274 -245.010178)
					(end 13.241274 -245.010178)
				)
			)
		)
	)
	(zone
		(layers "In1.Cu" "In4.Cu")
		(hatch none 0.5)
		(connect_pads
			(clearance 0)
		)
		(min_thickness 0.25)
		(keepout
			(tracks not_allowed)
			(vias allowed)
			(pads allowed)
			(copperpour not_allowed)
			(footprints allowed)
		)
		(placement
			(enabled no)
			(sheetname "")
		)
		(fill yes
			(thermal_gap 0.5)
			(thermal_bridge_width 0.5)
			(island_removal_mode 0)
		)
		(polygon
			(pts
				(arc
					(start 9.15035 -229.677214)
					(mid 7.37235 -229.677214)
					(end 9.15035 -229.677214)
				)
			)
		)
	)
	(zone
		(layers "In1.Cu" "In4.Cu")
		(hatch none 0.5)
		(connect_pads
			(clearance 0)
		)
		(min_thickness 0.25)
		(keepout
			(tracks not_allowed)
			(vias allowed)
			(pads allowed)
			(copperpour not_allowed)
			(footprints allowed)
		)
		(placement
			(enabled no)
			(sheetname "")
		)
		(fill yes
			(thermal_gap 0.5)
			(thermal_bridge_width 0.5)
			(island_removal_mode 0)
		)
		(polygon
			(pts
				(arc
					(start 34.031428 -79.305912)
					(mid 32.253428 -79.305912)
					(end 34.031428 -79.305912)
				)
			)
		)
	)
	(zone
		(layers "In1.Cu" "In4.Cu")
		(hatch none 0.5)
		(connect_pads
			(clearance 0)
		)
		(min_thickness 0.25)
		(keepout
			(tracks not_allowed)
			(vias allowed)
			(pads allowed)
			(copperpour not_allowed)
			(footprints allowed)
		)
		(placement
			(enabled no)
			(sheetname "")
		)
		(fill yes
			(thermal_gap 0.5)
			(thermal_bridge_width 0.5)
			(island_removal_mode 0)
		)
		(polygon
			(pts
				(arc
					(start 48.300132 -242.0366)
					(mid 46.522132 -242.0366)
					(end 48.300132 -242.0366)
				)
			)
		)
	)
	(zone
		(layers "In1.Cu" "In4.Cu")
		(hatch none 0.5)
		(connect_pads
			(clearance 0)
		)
		(min_thickness 0.25)
		(keepout
			(tracks not_allowed)
			(vias allowed)
			(pads allowed)
			(copperpour not_allowed)
			(footprints allowed)
		)
		(placement
			(enabled no)
			(sheetname "")
		)
		(fill yes
			(thermal_gap 0.5)
			(thermal_bridge_width 0.5)
			(island_removal_mode 0)
		)
		(polygon
			(pts
				(arc
					(start 20.2946 -301.7774)
					(mid 18.5166 -301.7774)
					(end 20.2946 -301.7774)
				)
			)
		)
	)
	(zone
		(layers "In1.Cu" "In4.Cu")
		(hatch none 0.5)
		(connect_pads
			(clearance 0)
		)
		(min_thickness 0.25)
		(keepout
			(tracks not_allowed)
			(vias allowed)
			(pads allowed)
			(copperpour not_allowed)
			(footprints allowed)
		)
		(placement
			(enabled no)
			(sheetname "")
		)
		(fill yes
			(thermal_gap 0.5)
			(thermal_bridge_width 0.5)
			(island_removal_mode 0)
		)
		(polygon
			(pts
				(arc
					(start 7.239 -280.4922)
					(mid 5.461 -280.4922)
					(end 7.239 -280.4922)
				)
			)
		)
	)
	(zone
		(layers "In1.Cu" "In4.Cu")
		(hatch none 0.5)
		(connect_pads
			(clearance 0)
		)
		(min_thickness 0.25)
		(keepout
			(tracks not_allowed)
			(vias allowed)
			(pads allowed)
			(copperpour not_allowed)
			(footprints allowed)
		)
		(placement
			(enabled no)
			(sheetname "")
		)
		(fill yes
			(thermal_gap 0.5)
			(thermal_bridge_width 0.5)
			(island_removal_mode 0)
		)
		(polygon
			(pts
				(arc
					(start 8.020812 -299.310044)
					(mid 5.379212 -299.310044)
					(end 8.020812 -299.310044)
				)
			)
		)
	)
	(zone
		(layers "In1.Cu" "In4.Cu")
		(hatch none 0.5)
		(connect_pads
			(clearance 0)
		)
		(min_thickness 0.25)
		(keepout
			(tracks not_allowed)
			(vias allowed)
			(pads allowed)
			(copperpour not_allowed)
			(footprints allowed)
		)
		(placement
			(enabled no)
			(sheetname "")
		)
		(fill yes
			(thermal_gap 0.5)
			(thermal_bridge_width 0.5)
			(island_removal_mode 0)
		)
		(polygon
			(pts
				(arc
					(start 11.09599 -80.321912)
					(mid 9.31799 -80.321912)
					(end 11.09599 -80.321912)
				)
			)
		)
	)
	(zone
		(layers "In1.Cu" "In4.Cu")
		(hatch none 0.5)
		(connect_pads
			(clearance 0)
		)
		(min_thickness 0.25)
		(keepout
			(tracks not_allowed)
			(vias allowed)
			(pads allowed)
			(copperpour not_allowed)
			(footprints allowed)
		)
		(placement
			(enabled no)
			(sheetname "")
		)
		(fill yes
			(thermal_gap 0.5)
			(thermal_bridge_width 0.5)
			(island_removal_mode 0)
		)
		(polygon
			(pts
				(arc
					(start 33.193228 -267.97)
					(mid 31.415228 -267.97)
					(end 33.193228 -267.97)
				)
			)
		)
	)
	(zone
		(layers "In1.Cu" "In4.Cu")
		(hatch none 0.5)
		(connect_pads
			(clearance 0)
		)
		(min_thickness 0.25)
		(keepout
			(tracks not_allowed)
			(vias allowed)
			(pads allowed)
			(copperpour not_allowed)
			(footprints allowed)
		)
		(placement
			(enabled no)
			(sheetname "")
		)
		(fill yes
			(thermal_gap 0.5)
			(thermal_bridge_width 0.5)
			(island_removal_mode 0)
		)
		(polygon
			(pts
				(arc
					(start 29.215588 -10.7442)
					(mid 27.437588 -10.7442)
					(end 29.215588 -10.7442)
				)
			)
		)
	)
	(zone
		(layers "In1.Cu" "In4.Cu")
		(hatch none 0.5)
		(connect_pads
			(clearance 0)
		)
		(min_thickness 0.25)
		(keepout
			(tracks not_allowed)
			(vias allowed)
			(pads allowed)
			(copperpour not_allowed)
			(footprints allowed)
		)
		(placement
			(enabled no)
			(sheetname "")
		)
		(fill yes
			(thermal_gap 0.5)
			(thermal_bridge_width 0.5)
			(island_removal_mode 0)
		)
		(polygon
			(pts
				(arc
					(start 8.984234 -59.078622)
					(mid 7.206234 -59.078622)
					(end 8.984234 -59.078622)
				)
			)
		)
	)
	(zone
		(layers "In1.Cu" "In4.Cu")
		(hatch none 0.5)
		(connect_pads
			(clearance 0)
		)
		(min_thickness 0.25)
		(keepout
			(tracks not_allowed)
			(vias allowed)
			(pads allowed)
			(copperpour not_allowed)
			(footprints allowed)
		)
		(placement
			(enabled no)
			(sheetname "")
		)
		(fill yes
			(thermal_gap 0.5)
			(thermal_bridge_width 0.5)
			(island_removal_mode 0)
		)
		(polygon
			(pts
				(arc
					(start 6.477 -281.2542)
					(mid 4.699 -281.2542)
					(end 6.477 -281.2542)
				)
			)
		)
	)
	(zone
		(layers "In1.Cu" "In4.Cu")
		(hatch none 0.5)
		(connect_pads
			(clearance 0)
		)
		(min_thickness 0.25)
		(keepout
			(tracks not_allowed)
			(vias allowed)
			(pads allowed)
			(copperpour not_allowed)
			(footprints allowed)
		)
		(placement
			(enabled no)
			(sheetname "")
		)
		(fill yes
			(thermal_gap 0.5)
			(thermal_bridge_width 0.5)
			(island_removal_mode 0)
		)
		(polygon
			(pts
				(arc
					(start 34.793428 -79.305912)
					(mid 33.015428 -79.305912)
					(end 34.793428 -79.305912)
				)
			)
		)
	)
	(zone
		(layers "In1.Cu" "In4.Cu")
		(hatch none 0.5)
		(connect_pads
			(clearance 0)
		)
		(min_thickness 0.25)
		(keepout
			(tracks not_allowed)
			(vias allowed)
			(pads allowed)
			(copperpour not_allowed)
			(footprints allowed)
		)
		(placement
			(enabled no)
			(sheetname "")
		)
		(fill yes
			(thermal_gap 0.5)
			(thermal_bridge_width 0.5)
			(island_removal_mode 0)
		)
		(polygon
			(pts
				(arc
					(start 36.646612 -244.31371)
					(mid 34.868612 -244.31371)
					(end 36.646612 -244.31371)
				)
			)
		)
	)
	(zone
		(layers "In1.Cu" "In4.Cu")
		(hatch none 0.5)
		(connect_pads
			(clearance 0)
		)
		(min_thickness 0.25)
		(keepout
			(tracks not_allowed)
			(vias allowed)
			(pads allowed)
			(copperpour not_allowed)
			(footprints allowed)
		)
		(placement
			(enabled no)
			(sheetname "")
		)
		(fill yes
			(thermal_gap 0.5)
			(thermal_bridge_width 0.5)
			(island_removal_mode 0)
		)
		(polygon
			(pts
				(arc
					(start 36.001452 -58.278776)
					(mid 34.223452 -58.278776)
					(end 36.001452 -58.278776)
				)
			)
		)
	)
	(zone
		(layers "In1.Cu" "In4.Cu")
		(hatch none 0.5)
		(connect_pads
			(clearance 0)
		)
		(min_thickness 0.25)
		(keepout
			(tracks not_allowed)
			(vias allowed)
			(pads allowed)
			(copperpour not_allowed)
			(footprints allowed)
		)
		(placement
			(enabled no)
			(sheetname "")
		)
		(fill yes
			(thermal_gap 0.5)
			(thermal_bridge_width 0.5)
			(island_removal_mode 0)
		)
		(polygon
			(pts
				(arc
					(start 38.9636 -94.0562)
					(mid 37.1856 -94.0562)
					(end 38.9636 -94.0562)
				)
			)
		)
	)
	(zone
		(layers "In1.Cu" "In4.Cu")
		(hatch none 0.5)
		(connect_pads
			(clearance 0)
		)
		(min_thickness 0.25)
		(keepout
			(tracks not_allowed)
			(vias allowed)
			(pads allowed)
			(copperpour not_allowed)
			(footprints allowed)
		)
		(placement
			(enabled no)
			(sheetname "")
		)
		(fill yes
			(thermal_gap 0.5)
			(thermal_bridge_width 0.5)
			(island_removal_mode 0)
		)
		(polygon
			(pts
				(arc
					(start 35.3695 -33.7185)
					(mid 33.5915 -33.7185)
					(end 35.3695 -33.7185)
				)
			)
		)
	)
	(zone
		(layers "In1.Cu" "In4.Cu")
		(hatch none 0.5)
		(connect_pads
			(clearance 0)
		)
		(min_thickness 0.25)
		(keepout
			(tracks not_allowed)
			(vias allowed)
			(pads allowed)
			(copperpour not_allowed)
			(footprints allowed)
		)
		(placement
			(enabled no)
			(sheetname "")
		)
		(fill yes
			(thermal_gap 0.5)
			(thermal_bridge_width 0.5)
			(island_removal_mode 0)
		)
		(polygon
			(pts
				(arc
					(start 29.977588 -10.7442)
					(mid 28.199588 -10.7442)
					(end 29.977588 -10.7442)
				)
			)
		)
	)
	(zone
		(layers "In1.Cu" "In4.Cu")
		(hatch none 0.5)
		(connect_pads
			(clearance 0)
		)
		(min_thickness 0.25)
		(keepout
			(tracks not_allowed)
			(vias allowed)
			(pads allowed)
			(copperpour not_allowed)
			(footprints allowed)
		)
		(placement
			(enabled no)
			(sheetname "")
		)
		(fill yes
			(thermal_gap 0.5)
			(thermal_bridge_width 0.5)
			(island_removal_mode 0)
		)
		(polygon
			(pts
				(arc
					(start 13.958824 -58.474356)
					(mid 12.180824 -58.474356)
					(end 13.958824 -58.474356)
				)
			)
		)
	)
	(zone
		(layers "In1.Cu" "In4.Cu")
		(hatch none 0.5)
		(connect_pads
			(clearance 0)
		)
		(min_thickness 0.25)
		(keepout
			(tracks not_allowed)
			(vias allowed)
			(pads allowed)
			(copperpour not_allowed)
			(footprints allowed)
		)
		(placement
			(enabled no)
			(sheetname "")
		)
		(fill yes
			(thermal_gap 0.5)
			(thermal_bridge_width 0.5)
			(island_removal_mode 0)
		)
		(polygon
			(pts
				(arc
					(start 42.000932 -264.32129)
					(mid 40.222932 -264.32129)
					(end 42.000932 -264.32129)
				)
			)
		)
	)
	(zone
		(layers "In1.Cu" "In4.Cu")
		(hatch none 0.5)
		(connect_pads
			(clearance 0)
		)
		(min_thickness 0.25)
		(keepout
			(tracks not_allowed)
			(vias allowed)
			(pads allowed)
			(copperpour not_allowed)
			(footprints allowed)
		)
		(placement
			(enabled no)
			(sheetname "")
		)
		(fill yes
			(thermal_gap 0.5)
			(thermal_bridge_width 0.5)
			(island_removal_mode 0)
		)
		(polygon
			(pts
				(arc
					(start 34.793428 -80.067912)
					(mid 33.015428 -80.067912)
					(end 34.793428 -80.067912)
				)
			)
		)
	)
	(zone
		(layers "In1.Cu" "In4.Cu")
		(hatch none 0.5)
		(connect_pads
			(clearance 0)
		)
		(min_thickness 0.25)
		(keepout
			(tracks not_allowed)
			(vias allowed)
			(pads allowed)
			(copperpour not_allowed)
			(footprints allowed)
		)
		(placement
			(enabled no)
			(sheetname "")
		)
		(fill yes
			(thermal_gap 0.5)
			(thermal_bridge_width 0.5)
			(island_removal_mode 0)
		)
		(polygon
			(pts
				(arc
					(start 45.100748 -265.121136)
					(mid 43.322748 -265.121136)
					(end 45.100748 -265.121136)
				)
			)
		)
	)
	(zone
		(layers "In1.Cu" "In4.Cu")
		(hatch none 0.5)
		(connect_pads
			(clearance 0)
		)
		(min_thickness 0.25)
		(keepout
			(tracks not_allowed)
			(vias allowed)
			(pads allowed)
			(copperpour not_allowed)
			(footprints allowed)
		)
		(placement
			(enabled no)
			(sheetname "")
		)
		(fill yes
			(thermal_gap 0.5)
			(thermal_bridge_width 0.5)
			(island_removal_mode 0)
		)
		(polygon
			(pts
				(arc
					(start 42.000932 -79.086202)
					(mid 40.222932 -79.086202)
					(end 42.000932 -79.086202)
				)
			)
		)
	)
	(zone
		(layers "In1.Cu" "In4.Cu")
		(hatch none 0.5)
		(connect_pads
			(clearance 0)
		)
		(min_thickness 0.25)
		(keepout
			(tracks not_allowed)
			(vias allowed)
			(pads allowed)
			(copperpour not_allowed)
			(footprints allowed)
		)
		(placement
			(enabled no)
			(sheetname "")
		)
		(fill yes
			(thermal_gap 0.5)
			(thermal_bridge_width 0.5)
			(island_removal_mode 0)
		)
		(polygon
			(pts
				(arc
					(start 36.646612 -58.913776)
					(mid 34.868612 -58.913776)
					(end 36.646612 -58.913776)
				)
			)
		)
	)
	(zone
		(layers "In1.Cu" "In4.Cu")
		(hatch none 0.5)
		(connect_pads
			(clearance 0)
		)
		(min_thickness 0.25)
		(keepout
			(tracks not_allowed)
			(vias allowed)
			(pads allowed)
			(copperpour not_allowed)
			(footprints allowed)
		)
		(placement
			(enabled no)
			(sheetname "")
		)
		(fill yes
			(thermal_gap 0.5)
			(thermal_bridge_width 0.5)
			(island_removal_mode 0)
		)
		(polygon
			(pts
				(arc
					(start 38.9636 -89.3572)
					(mid 37.1856 -89.3572)
					(end 38.9636 -89.3572)
				)
			)
		)
	)
	(zone
		(layers "In1.Cu" "In4.Cu")
		(hatch none 0.5)
		(connect_pads
			(clearance 0)
		)
		(min_thickness 0.25)
		(keepout
			(tracks not_allowed)
			(vias allowed)
			(pads allowed)
			(copperpour not_allowed)
			(footprints allowed)
		)
		(placement
			(enabled no)
			(sheetname "")
		)
		(fill yes
			(thermal_gap 0.5)
			(thermal_bridge_width 0.5)
			(island_removal_mode 0)
		)
		(polygon
			(pts
				(arc
					(start 36.848288 -271.8816)
					(mid 35.070288 -271.8816)
					(end 36.848288 -271.8816)
				)
			)
		)
	)
	(zone
		(layers "In1.Cu" "In4.Cu")
		(hatch none 0.5)
		(connect_pads
			(clearance 0)
		)
		(min_thickness 0.25)
		(keepout
			(tracks not_allowed)
			(vias allowed)
			(pads allowed)
			(copperpour not_allowed)
			(footprints allowed)
		)
		(placement
			(enabled no)
			(sheetname "")
		)
		(fill yes
			(thermal_gap 0.5)
			(thermal_bridge_width 0.5)
			(island_removal_mode 0)
		)
		(polygon
			(pts
				(arc
					(start 36.011612 -243.67871)
					(mid 34.233612 -243.67871)
					(end 36.011612 -243.67871)
				)
			)
		)
	)
	(zone
		(layers "In1.Cu" "In4.Cu")
		(hatch none 0.5)
		(connect_pads
			(clearance 0)
		)
		(min_thickness 0.25)
		(keepout
			(tracks not_allowed)
			(vias allowed)
			(pads allowed)
			(copperpour not_allowed)
			(footprints allowed)
		)
		(placement
			(enabled no)
			(sheetname "")
		)
		(fill yes
			(thermal_gap 0.5)
			(thermal_bridge_width 0.5)
			(island_removal_mode 0)
		)
		(polygon
			(pts
				(arc
					(start 10.020808 -205.010004)
					(mid 7.379208 -205.010004)
					(end 10.020808 -205.010004)
				)
			)
		)
	)
	(zone
		(layers "In1.Cu" "In4.Cu")
		(hatch none 0.5)
		(connect_pads
			(clearance 0)
		)
		(min_thickness 0.25)
		(keepout
			(tracks not_allowed)
			(vias allowed)
			(pads allowed)
			(copperpour not_allowed)
			(footprints allowed)
		)
		(placement
			(enabled no)
			(sheetname "")
		)
		(fill yes
			(thermal_gap 0.5)
			(thermal_bridge_width 0.5)
			(island_removal_mode 0)
		)
		(polygon
			(pts
				(arc
					(start 39.898828 -245.113556)
					(mid 38.120828 -245.113556)
					(end 39.898828 -245.113556)
				)
			)
		)
	)
	(zone
		(layers "In1.Cu" "In4.Cu")
		(hatch none 0.5)
		(connect_pads
			(clearance 0)
		)
		(min_thickness 0.25)
		(keepout
			(tracks not_allowed)
			(vias allowed)
			(pads allowed)
			(copperpour not_allowed)
			(footprints allowed)
		)
		(placement
			(enabled no)
			(sheetname "")
		)
		(fill yes
			(thermal_gap 0.5)
			(thermal_bridge_width 0.5)
			(island_removal_mode 0)
		)
		(polygon
			(pts
				(arc
					(start 38.903656 -42.784522)
					(mid 37.125656 -42.784522)
					(end 38.903656 -42.784522)
				)
			)
		)
	)
	(zone
		(layers "In1.Cu" "In4.Cu")
		(hatch none 0.5)
		(connect_pads
			(clearance 0)
		)
		(min_thickness 0.25)
		(keepout
			(tracks not_allowed)
			(vias allowed)
			(pads allowed)
			(copperpour not_allowed)
			(footprints allowed)
		)
		(placement
			(enabled no)
			(sheetname "")
		)
		(fill yes
			(thermal_gap 0.5)
			(thermal_bridge_width 0.5)
			(island_removal_mode 0)
		)
		(polygon
			(pts
				(arc
					(start 43.810428 -264.486136)
					(mid 42.032428 -264.486136)
					(end 43.810428 -264.486136)
				)
			)
		)
	)
	(zone
		(layers "In1.Cu" "In4.Cu")
		(hatch none 0.5)
		(connect_pads
			(clearance 0)
		)
		(min_thickness 0.25)
		(keepout
			(tracks not_allowed)
			(vias allowed)
			(pads allowed)
			(copperpour not_allowed)
			(footprints allowed)
		)
		(placement
			(enabled no)
			(sheetname "")
		)
		(fill yes
			(thermal_gap 0.5)
			(thermal_bridge_width 0.5)
			(island_removal_mode 0)
		)
		(polygon
			(pts
				(arc
					(start 5.229098 -243.513864)
					(mid 3.451098 -243.513864)
					(end 5.229098 -243.513864)
				)
			)
		)
	)
	(zone
		(layers "In1.Cu" "In4.Cu")
		(hatch none 0.5)
		(connect_pads
			(clearance 0)
		)
		(min_thickness 0.25)
		(keepout
			(tracks not_allowed)
			(vias allowed)
			(pads allowed)
			(copperpour not_allowed)
			(footprints allowed)
		)
		(placement
			(enabled no)
			(sheetname "")
		)
		(fill yes
			(thermal_gap 0.5)
			(thermal_bridge_width 0.5)
			(island_removal_mode 0)
		)
		(polygon
			(pts
				(arc
					(start 29.215588 -13.2842)
					(mid 27.437588 -13.2842)
					(end 29.215588 -13.2842)
				)
			)
		)
	)
	(zone
		(layers "In1.Cu" "In4.Cu")
		(hatch none 0.5)
		(connect_pads
			(clearance 0)
		)
		(min_thickness 0.25)
		(keepout
			(tracks not_allowed)
			(vias allowed)
			(pads allowed)
			(copperpour not_allowed)
			(footprints allowed)
		)
		(placement
			(enabled no)
			(sheetname "")
		)
		(fill yes
			(thermal_gap 0.5)
			(thermal_bridge_width 0.5)
			(island_removal_mode 0)
		)
		(polygon
			(pts
				(arc
					(start 38.903656 -44.308522)
					(mid 37.125656 -44.308522)
					(end 38.903656 -44.308522)
				)
			)
		)
	)
	(zone
		(layers "In1.Cu" "In4.Cu")
		(hatch none 0.5)
		(connect_pads
			(clearance 0)
		)
		(min_thickness 0.25)
		(keepout
			(tracks not_allowed)
			(vias allowed)
			(pads allowed)
			(copperpour not_allowed)
			(footprints allowed)
		)
		(placement
			(enabled no)
			(sheetname "")
		)
		(fill yes
			(thermal_gap 0.5)
			(thermal_bridge_width 0.5)
			(island_removal_mode 0)
		)
		(polygon
			(pts
				(arc
					(start 29.215588 -10.1092)
					(mid 27.437588 -10.1092)
					(end 29.215588 -10.1092)
				)
			)
		)
	)
	(zone
		(layers "In1.Cu" "In4.Cu")
		(hatch none 0.5)
		(connect_pads
			(clearance 0)
		)
		(min_thickness 0.25)
		(keepout
			(tracks not_allowed)
			(vias allowed)
			(pads allowed)
			(copperpour not_allowed)
			(footprints allowed)
		)
		(placement
			(enabled no)
			(sheetname "")
		)
		(fill yes
			(thermal_gap 0.5)
			(thermal_bridge_width 0.5)
			(island_removal_mode 0)
		)
		(polygon
			(pts
				(arc
					(start 16.83131 -264.486136)
					(mid 15.05331 -264.486136)
					(end 16.83131 -264.486136)
				)
			)
		)
	)
	(zone
		(layers "In1.Cu" "In4.Cu")
		(hatch none 0.5)
		(connect_pads
			(clearance 0)
		)
		(min_thickness 0.25)
		(keepout
			(tracks not_allowed)
			(vias allowed)
			(pads allowed)
			(copperpour not_allowed)
			(footprints allowed)
		)
		(placement
			(enabled no)
			(sheetname "")
		)
		(fill yes
			(thermal_gap 0.5)
			(thermal_bridge_width 0.5)
			(island_removal_mode 0)
		)
		(polygon
			(pts
				(arc
					(start 36.656772 -243.67871)
					(mid 34.878772 -243.67871)
					(end 36.656772 -243.67871)
				)
			)
		)
	)
	(zone
		(layers "In1.Cu" "In4.Cu")
		(hatch none 0.5)
		(connect_pads
			(clearance 0)
		)
		(min_thickness 0.25)
		(keepout
			(tracks not_allowed)
			(vias allowed)
			(pads allowed)
			(copperpour not_allowed)
			(footprints allowed)
		)
		(placement
			(enabled no)
			(sheetname "")
		)
		(fill yes
			(thermal_gap 0.5)
			(thermal_bridge_width 0.5)
			(island_removal_mode 0)
		)
		(polygon
			(pts
				(arc
					(start 21.082 -288.036)
					(mid 19.304 -288.036)
					(end 21.082 -288.036)
				)
			)
		)
	)
	(zone
		(layers "In1.Cu" "In4.Cu")
		(hatch none 0.5)
		(connect_pads
			(clearance 0)
		)
		(min_thickness 0.25)
		(keepout
			(tracks not_allowed)
			(vias allowed)
			(pads allowed)
			(copperpour not_allowed)
			(footprints allowed)
		)
		(placement
			(enabled no)
			(sheetname "")
		)
		(fill yes
			(thermal_gap 0.5)
			(thermal_bridge_width 0.5)
			(island_removal_mode 0)
		)
		(polygon
			(pts
				(arc
					(start 20.447 -209.169)
					(mid 18.669 -209.169)
					(end 20.447 -209.169)
				)
			)
		)
	)
	(zone
		(layers "In1.Cu" "In4.Cu")
		(hatch none 0.5)
		(connect_pads
			(clearance 0)
		)
		(min_thickness 0.25)
		(keepout
			(tracks not_allowed)
			(vias allowed)
			(pads allowed)
			(copperpour not_allowed)
			(footprints allowed)
		)
		(placement
			(enabled no)
			(sheetname "")
		)
		(fill yes
			(thermal_gap 0.5)
			(thermal_bridge_width 0.5)
			(island_removal_mode 0)
		)
		(polygon
			(pts
				(arc
					(start 34.006028 -263.906)
					(mid 32.228028 -263.906)
					(end 34.006028 -263.906)
				)
			)
		)
	)
	(zone
		(layers "In1.Cu" "In4.Cu")
		(hatch none 0.5)
		(connect_pads
			(clearance 0)
		)
		(min_thickness 0.25)
		(keepout
			(tracks not_allowed)
			(vias allowed)
			(pads allowed)
			(copperpour not_allowed)
			(footprints allowed)
		)
		(placement
			(enabled no)
			(sheetname "")
		)
		(fill yes
			(thermal_gap 0.5)
			(thermal_bridge_width 0.5)
			(island_removal_mode 0)
		)
		(polygon
			(pts
				(arc
					(start 41.365932 -79.086202)
					(mid 39.587932 -79.086202)
					(end 41.365932 -79.086202)
				)
			)
		)
	)
	(zone
		(layers "In1.Cu" "In4.Cu")
		(hatch none 0.5)
		(connect_pads
			(clearance 0)
		)
		(min_thickness 0.25)
		(keepout
			(tracks not_allowed)
			(vias allowed)
			(pads allowed)
			(copperpour not_allowed)
			(footprints allowed)
		)
		(placement
			(enabled no)
			(sheetname "")
		)
		(fill yes
			(thermal_gap 0.5)
			(thermal_bridge_width 0.5)
			(island_removal_mode 0)
		)
		(polygon
			(pts
				(arc
					(start 42.259758 -231.267)
					(mid 40.481758 -231.267)
					(end 42.259758 -231.267)
				)
			)
		)
	)
	(zone
		(layers "In1.Cu" "In4.Cu")
		(hatch none 0.5)
		(connect_pads
			(clearance 0)
		)
		(min_thickness 0.25)
		(keepout
			(tracks not_allowed)
			(vias allowed)
			(pads allowed)
			(copperpour not_allowed)
			(footprints allowed)
		)
		(placement
			(enabled no)
			(sheetname "")
		)
		(fill yes
			(thermal_gap 0.5)
			(thermal_bridge_width 0.5)
			(island_removal_mode 0)
		)
		(polygon
			(pts
				(arc
					(start 46.725332 -280.330148)
					(mid 44.947332 -280.330148)
					(end 46.725332 -280.330148)
				)
			)
		)
	)
	(zone
		(layers "In1.Cu" "In4.Cu")
		(hatch none 0.5)
		(connect_pads
			(clearance 0)
		)
		(min_thickness 0.25)
		(keepout
			(tracks not_allowed)
			(vias allowed)
			(pads allowed)
			(copperpour not_allowed)
			(footprints allowed)
		)
		(placement
			(enabled no)
			(sheetname "")
		)
		(fill yes
			(thermal_gap 0.5)
			(thermal_bridge_width 0.5)
			(island_removal_mode 0)
		)
		(polygon
			(pts
				(arc
					(start 21.209 -210.439)
					(mid 19.431 -210.439)
					(end 21.209 -210.439)
				)
			)
		)
	)
	(zone
		(layers "In1.Cu" "In4.Cu")
		(hatch none 0.5)
		(connect_pads
			(clearance 0)
		)
		(min_thickness 0.25)
		(keepout
			(tracks not_allowed)
			(vias allowed)
			(pads allowed)
			(copperpour not_allowed)
			(footprints allowed)
		)
		(placement
			(enabled no)
			(sheetname "")
		)
		(fill yes
			(thermal_gap 0.5)
			(thermal_bridge_width 0.5)
			(island_removal_mode 0)
		)
		(polygon
			(pts
				(arc
					(start 18.161 -204.369924)
					(mid 16.383 -204.369924)
					(end 18.161 -204.369924)
				)
			)
		)
	)
	(zone
		(layers "In1.Cu" "In4.Cu")
		(hatch none 0.5)
		(connect_pads
			(clearance 0)
		)
		(min_thickness 0.25)
		(keepout
			(tracks not_allowed)
			(vias allowed)
			(pads allowed)
			(copperpour not_allowed)
			(footprints allowed)
		)
		(placement
			(enabled no)
			(sheetname "")
		)
		(fill yes
			(thermal_gap 0.5)
			(thermal_bridge_width 0.5)
			(island_removal_mode 0)
		)
		(polygon
			(pts
				(arc
					(start 10.33399 -80.321912)
					(mid 8.55599 -80.321912)
					(end 10.33399 -80.321912)
				)
			)
		)
	)
	(zone
		(layers "In1.Cu" "In4.Cu")
		(hatch none 0.5)
		(connect_pads
			(clearance 0)
		)
		(min_thickness 0.25)
		(keepout
			(tracks not_allowed)
			(vias allowed)
			(pads allowed)
			(copperpour not_allowed)
			(footprints allowed)
		)
		(placement
			(enabled no)
			(sheetname "")
		)
		(fill yes
			(thermal_gap 0.5)
			(thermal_bridge_width 0.5)
			(island_removal_mode 0)
		)
		(polygon
			(pts
				(arc
					(start 4.315968 -265.855704)
					(mid 2.537968 -265.855704)
					(end 4.315968 -265.855704)
				)
			)
		)
	)
	(zone
		(layers "In1.Cu" "In4.Cu")
		(hatch none 0.5)
		(connect_pads
			(clearance 0)
		)
		(min_thickness 0.25)
		(keepout
			(tracks not_allowed)
			(vias allowed)
			(pads allowed)
			(copperpour not_allowed)
			(footprints allowed)
		)
		(placement
			(enabled no)
			(sheetname "")
		)
		(fill yes
			(thermal_gap 0.5)
			(thermal_bridge_width 0.5)
			(island_removal_mode 0)
		)
		(polygon
			(pts
				(arc
					(start 4.315968 -266.511024)
					(mid 2.537968 -266.511024)
					(end 4.315968 -266.511024)
				)
			)
		)
	)
	(zone
		(layers "In1.Cu" "In4.Cu")
		(hatch none 0.5)
		(connect_pads
			(clearance 0)
		)
		(min_thickness 0.25)
		(keepout
			(tracks not_allowed)
			(vias allowed)
			(pads allowed)
			(copperpour not_allowed)
			(footprints allowed)
		)
		(placement
			(enabled no)
			(sheetname "")
		)
		(fill yes
			(thermal_gap 0.5)
			(thermal_bridge_width 0.5)
			(island_removal_mode 0)
		)
		(polygon
			(pts
				(arc
					(start 42.764456 -52.944522)
					(mid 40.986456 -52.944522)
					(end 42.764456 -52.944522)
				)
			)
		)
	)
	(zone
		(layers "In1.Cu" "In4.Cu")
		(hatch none 0.5)
		(connect_pads
			(clearance 0)
		)
		(min_thickness 0.25)
		(keepout
			(tracks not_allowed)
			(vias allowed)
			(pads allowed)
			(copperpour not_allowed)
			(footprints allowed)
		)
		(placement
			(enabled no)
			(sheetname "")
		)
		(fill yes
			(thermal_gap 0.5)
			(thermal_bridge_width 0.5)
			(island_removal_mode 0)
		)
		(polygon
			(pts
				(arc
					(start 45.810932 -92.02166)
					(mid 44.032932 -92.02166)
					(end 45.810932 -92.02166)
				)
			)
		)
	)
	(zone
		(layers "In1.Cu" "In4.Cu")
		(hatch none 0.5)
		(connect_pads
			(clearance 0)
		)
		(min_thickness 0.25)
		(keepout
			(tracks not_allowed)
			(vias allowed)
			(pads allowed)
			(copperpour not_allowed)
			(footprints allowed)
		)
		(placement
			(enabled no)
			(sheetname "")
		)
		(fill yes
			(thermal_gap 0.5)
			(thermal_bridge_width 0.5)
			(island_removal_mode 0)
		)
		(polygon
			(pts
				(arc
					(start 5.884418 -243.513864)
					(mid 4.106418 -243.513864)
					(end 5.884418 -243.513864)
				)
			)
		)
	)
	(zone
		(layers "In1.Cu" "In4.Cu")
		(hatch none 0.5)
		(connect_pads
			(clearance 0)
		)
		(min_thickness 0.25)
		(keepout
			(tracks not_allowed)
			(vias allowed)
			(pads allowed)
			(copperpour not_allowed)
			(footprints allowed)
		)
		(placement
			(enabled no)
			(sheetname "")
		)
		(fill yes
			(thermal_gap 0.5)
			(thermal_bridge_width 0.5)
			(island_removal_mode 0)
		)
		(polygon
			(pts
				(arc
					(start 44.455588 -265.121136)
					(mid 42.677588 -265.121136)
					(end 44.455588 -265.121136)
				)
			)
		)
	)
	(zone
		(layers "In1.Cu" "In4.Cu")
		(hatch none 0.5)
		(connect_pads
			(clearance 0)
		)
		(min_thickness 0.25)
		(keepout
			(tracks not_allowed)
			(vias allowed)
			(pads allowed)
			(copperpour not_allowed)
			(footprints allowed)
		)
		(placement
			(enabled no)
			(sheetname "")
		)
		(fill yes
			(thermal_gap 0.5)
			(thermal_bridge_width 0.5)
			(island_removal_mode 0)
		)
		(polygon
			(pts
				(arc
					(start 13.834618 -62.541912)
					(mid 12.056618 -62.541912)
					(end 13.834618 -62.541912)
				)
			)
		)
	)
	(zone
		(layers "In1.Cu" "In4.Cu")
		(hatch none 0.5)
		(connect_pads
			(clearance 0)
		)
		(min_thickness 0.25)
		(keepout
			(tracks not_allowed)
			(vias allowed)
			(pads allowed)
			(copperpour not_allowed)
			(footprints allowed)
		)
		(placement
			(enabled no)
			(sheetname "")
		)
		(fill yes
			(thermal_gap 0.5)
			(thermal_bridge_width 0.5)
			(island_removal_mode 0)
		)
		(polygon
			(pts
				(arc
					(start 34.768028 -263.906)
					(mid 32.990028 -263.906)
					(end 34.768028 -263.906)
				)
			)
		)
	)
	(zone
		(layers "In1.Cu" "In4.Cu")
		(hatch none 0.5)
		(connect_pads
			(clearance 0)
		)
		(min_thickness 0.25)
		(keepout
			(tracks not_allowed)
			(vias allowed)
			(pads allowed)
			(copperpour not_allowed)
			(footprints allowed)
		)
		(placement
			(enabled no)
			(sheetname "")
		)
		(fill yes
			(thermal_gap 0.5)
			(thermal_bridge_width 0.5)
			(island_removal_mode 0)
		)
		(polygon
			(pts
				(arc
					(start 40.710612 -79.086202)
					(mid 38.932612 -79.086202)
					(end 40.710612 -79.086202)
				)
			)
		)
	)
	(zone
		(layers "In1.Cu" "In4.Cu")
		(hatch none 0.5)
		(connect_pads
			(clearance 0)
		)
		(min_thickness 0.25)
		(keepout
			(tracks not_allowed)
			(vias allowed)
			(pads allowed)
			(copperpour not_allowed)
			(footprints allowed)
		)
		(placement
			(enabled no)
			(sheetname "")
		)
		(fill yes
			(thermal_gap 0.5)
			(thermal_bridge_width 0.5)
			(island_removal_mode 0)
		)
		(polygon
			(pts
				(arc
					(start 39.589456 -227.61321)
					(mid 37.811456 -227.61321)
					(end 39.589456 -227.61321)
				)
			)
		)
	)
	(zone
		(layers "In1.Cu" "In4.Cu")
		(hatch none 0.5)
		(connect_pads
			(clearance 0)
		)
		(min_thickness 0.25)
		(keepout
			(tracks not_allowed)
			(vias allowed)
			(pads allowed)
			(copperpour not_allowed)
			(footprints allowed)
		)
		(placement
			(enabled no)
			(sheetname "")
		)
		(fill yes
			(thermal_gap 0.5)
			(thermal_bridge_width 0.5)
			(island_removal_mode 0)
		)
		(polygon
			(pts
				(arc
					(start 26.924 -248.793)
					(mid 25.146 -248.793)
					(end 26.924 -248.793)
				)
			)
		)
	)
	(zone
		(layers "In1.Cu" "In4.Cu")
		(hatch none 0.5)
		(connect_pads
			(clearance 0)
		)
		(min_thickness 0.25)
		(keepout
			(tracks not_allowed)
			(vias allowed)
			(pads allowed)
			(copperpour not_allowed)
			(footprints allowed)
		)
		(placement
			(enabled no)
			(sheetname "")
		)
		(fill yes
			(thermal_gap 0.5)
			(thermal_bridge_width 0.5)
			(island_removal_mode 0)
		)
		(polygon
			(pts
				(arc
					(start 12.188698 -44.263056)
					(mid 10.410698 -44.263056)
					(end 12.188698 -44.263056)
				)
			)
		)
	)
	(zone
		(layers "In1.Cu" "In4.Cu")
		(hatch none 0.5)
		(connect_pads
			(clearance 0)
		)
		(min_thickness 0.25)
		(keepout
			(tracks not_allowed)
			(vias allowed)
			(pads allowed)
			(copperpour not_allowed)
			(footprints allowed)
		)
		(placement
			(enabled no)
			(sheetname "")
		)
		(fill yes
			(thermal_gap 0.5)
			(thermal_bridge_width 0.5)
			(island_removal_mode 0)
		)
		(polygon
			(pts
				(arc
					(start 7.62 -91.878912)
					(mid 5.842 -91.878912)
					(end 7.62 -91.878912)
				)
			)
		)
	)
	(zone
		(layers "In1.Cu" "In4.Cu")
		(hatch none 0.5)
		(connect_pads
			(clearance 0)
		)
		(min_thickness 0.25)
		(keepout
			(tracks not_allowed)
			(vias allowed)
			(pads allowed)
			(copperpour not_allowed)
			(footprints allowed)
		)
		(placement
			(enabled no)
			(sheetname "")
		)
		(fill yes
			(thermal_gap 0.5)
			(thermal_bridge_width 0.5)
			(island_removal_mode 0)
		)
		(polygon
			(pts
				(arc
					(start 38.903656 -43.546522)
					(mid 37.125656 -43.546522)
					(end 38.903656 -43.546522)
				)
			)
		)
	)
	(zone
		(layers "In1.Cu" "In4.Cu")
		(hatch none 0.5)
		(connect_pads
			(clearance 0)
		)
		(min_thickness 0.25)
		(keepout
			(tracks not_allowed)
			(vias allowed)
			(pads allowed)
			(copperpour not_allowed)
			(footprints allowed)
		)
		(placement
			(enabled no)
			(sheetname "")
		)
		(fill yes
			(thermal_gap 0.5)
			(thermal_bridge_width 0.5)
			(island_removal_mode 0)
		)
		(polygon
			(pts
				(arc
					(start 16.70431 -79.886048)
					(mid 14.92631 -79.886048)
					(end 16.70431 -79.886048)
				)
			)
		)
	)
	(zone
		(layers "In1.Cu" "In4.Cu")
		(hatch none 0.5)
		(connect_pads
			(clearance 0)
		)
		(min_thickness 0.25)
		(keepout
			(tracks not_allowed)
			(vias allowed)
			(pads allowed)
			(copperpour not_allowed)
			(footprints allowed)
		)
		(placement
			(enabled no)
			(sheetname "")
		)
		(fill yes
			(thermal_gap 0.5)
			(thermal_bridge_width 0.5)
			(island_removal_mode 0)
		)
		(polygon
			(pts
				(arc
					(start 37.301932 -58.913776)
					(mid 35.523932 -58.913776)
					(end 37.301932 -58.913776)
				)
			)
		)
	)
	(zone
		(layers "In1.Cu" "In4.Cu")
		(hatch none 0.5)
		(connect_pads
			(clearance 0)
		)
		(min_thickness 0.25)
		(keepout
			(tracks not_allowed)
			(vias allowed)
			(pads allowed)
			(copperpour not_allowed)
			(footprints allowed)
		)
		(placement
			(enabled no)
			(sheetname "")
		)
		(fill yes
			(thermal_gap 0.5)
			(thermal_bridge_width 0.5)
			(island_removal_mode 0)
		)
		(polygon
			(pts
				(arc
					(start 38.954456 -226.85121)
					(mid 37.176456 -226.85121)
					(end 38.954456 -226.85121)
				)
			)
		)
	)
	(zone
		(layers "In1.Cu" "In4.Cu")
		(hatch none 0.5)
		(connect_pads
			(clearance 0)
		)
		(min_thickness 0.25)
		(keepout
			(tracks not_allowed)
			(vias allowed)
			(pads allowed)
			(copperpour not_allowed)
			(footprints allowed)
		)
		(placement
			(enabled no)
			(sheetname "")
		)
		(fill yes
			(thermal_gap 0.5)
			(thermal_bridge_width 0.5)
			(island_removal_mode 0)
		)
		(polygon
			(pts
				(arc
					(start 47.563532 -242.8748)
					(mid 45.785532 -242.8748)
					(end 47.563532 -242.8748)
				)
			)
		)
	)
	(zone
		(layers "In2.Cu" "In3.Cu")
		(hatch none 0.5)
		(connect_pads
			(clearance 0)
		)
		(min_thickness 0.25)
		(keepout
			(tracks not_allowed)
			(vias allowed)
			(pads allowed)
			(copperpour not_allowed)
			(footprints allowed)
		)
		(placement
			(enabled no)
			(sheetname "")
		)
		(fill yes
			(thermal_gap 0.5)
			(thermal_bridge_width 0.5)
			(island_removal_mode 0)
		)
		(polygon
			(pts
				(arc
					(start 6.35 -157.661102)
					(mid 10.850118 -162.16122)
					(end 15.349982 -157.661102)
				)
				(arc
					(start 15.349982 -145.660872)
					(mid 10.850118 -141.161008)
					(end 6.35 -145.660872)
				)
			)
		)
	)
	(zone
		(layers "In2.Cu" "In3.Cu")
		(hatch none 0.5)
		(connect_pads
			(clearance 0)
		)
		(min_thickness 0.25)
		(keepout
			(tracks not_allowed)
			(vias allowed)
			(pads allowed)
			(copperpour not_allowed)
			(footprints allowed)
		)
		(placement
			(enabled no)
			(sheetname "")
		)
		(fill yes
			(thermal_gap 0.5)
			(thermal_bridge_width 0.5)
			(island_removal_mode 0)
		)
		(polygon
			(pts
				(arc
					(start 21.34997 -51.90998)
					(mid 25.850088 -56.410098)
					(end 30.349952 -51.90998)
				)
				(arc
					(start 30.349952 -39.90975)
					(mid 25.850088 -35.409886)
					(end 21.34997 -39.90975)
				)
			)
		)
	)
	(zone
		(layers "In2.Cu" "In3.Cu")
		(hatch none 0.5)
		(connect_pads
			(clearance 0)
		)
		(min_thickness 0.25)
		(keepout
			(tracks not_allowed)
			(vias allowed)
			(pads allowed)
			(copperpour not_allowed)
			(footprints allowed)
		)
		(placement
			(enabled no)
			(sheetname "")
		)
		(fill yes
			(thermal_gap 0.5)
			(thermal_bridge_width 0.5)
			(island_removal_mode 0)
		)
		(polygon
			(pts
				(arc
					(start 36.34994 -157.661102)
					(mid 40.850058 -162.16122)
					(end 45.349922 -157.661102)
				)
				(arc
					(start 45.349922 -145.660872)
					(mid 40.850058 -141.161008)
					(end 36.34994 -145.660872)
				)
			)
		)
	)
	(zone
		(layers "In2.Cu" "In3.Cu")
		(hatch none 0.5)
		(connect_pads
			(clearance 0)
		)
		(min_thickness 0.25)
		(keepout
			(tracks not_allowed)
			(vias allowed)
			(pads allowed)
			(copperpour not_allowed)
			(footprints allowed)
		)
		(placement
			(enabled no)
			(sheetname "")
		)
		(fill yes
			(thermal_gap 0.5)
			(thermal_bridge_width 0.5)
			(island_removal_mode 0)
		)
		(polygon
			(pts
				(arc
					(start 21.34997 -241.909854)
					(mid 25.850088 -246.409972)
					(end 30.349952 -241.909854)
				)
				(arc
					(start 30.349952 -229.909624)
					(mid 25.850088 -225.40976)
					(end 21.34997 -229.909624)
				)
			)
		)
	)
)
